G04 ================== begin FILE IDENTIFICATION RECORD ==================*
G04 Layout Name:  15126-1b.brd*
G04 Film Name:    DP_REF_L3*
G04 File Format:  Gerber RS274X*
G04 File Origin:  Cadence Allegro 16.6-2015-S079*
G04 Origin Date:  Fri Feb 10 17:23:33 2017*
G04 *
G04 Layer:  BOARD GEOMETRY/PANEL_OUTLINE*
G04 Layer:  BOARD GEOMETRY/DP_REF_L3_TBL*
G04 Layer:  BOARD GEOMETRY/DP_REF_L3_L3*
G04 *
G04 Offset:    (0.00 0.00)*
G04 Mirror:    No*
G04 Mode:      Positive*
G04 Rotation:  0*
G04 FullContactRelief:  No*
G04 UndefLineWidth:     6.00*
G04 ================== end FILE IDENTIFICATION RECORD ====================*
%FSLAX35Y35*MOIN*%
%IR0*IPPOS*OFA0.00000B0.00000*MIA0B0*SFA1.00000B1.00000*%
%ADD10C,.02*%
%ADD11C,.006*%
%ADD12C,.0045*%
%ADD13C,.0056*%
G75*
%LPD*%
G75*
G54D10*
G01X2026678Y631398D02*
Y458148D01*
G01D02*
X2866678D01*
G01X2026678Y492798D02*
X2866678D01*
G01X2026678Y527448D02*
X2866678D01*
G01X2026678Y562098D02*
X2866678D01*
G01X2026678Y596748D02*
X2866678D01*
G01X2026678Y631398D02*
X2866678D01*
G01X2201678D02*
Y458148D01*
G01X2551678Y631398D02*
Y458148D01*
G01X2656678Y631398D02*
Y458148D01*
G01X2866678Y631398D02*
Y458148D01*
G54D11*
G01X-17372Y-95792D02*
Y-113292D01*
G01X-22394Y-95792D02*
X-12350D01*
G01X-3584Y-113292D02*
Y-95792D01*
G01Y-104250D02*
X-2492Y-102792D01*
X-1400Y-101917D01*
X346Y-101626D01*
X1656Y-101917D01*
X3185Y-103084D01*
X3840Y-104834D01*
Y-113292D01*
G01X17628Y-101626D02*
Y-113292D01*
G01Y-96959D02*
X17191Y-96667D01*
Y-96084D01*
X17628Y-95792D01*
X18065Y-96084D01*
Y-96667D01*
X17628Y-96959D01*
G01X31853Y-111251D02*
X32945Y-112417D01*
X34473Y-113292D01*
X35783D01*
X37093Y-112709D01*
X37966Y-111834D01*
X38403Y-110668D01*
X38185Y-108917D01*
X37311Y-108042D01*
X33381Y-106292D01*
X32508Y-104250D01*
X32945Y-102792D01*
X33818Y-101917D01*
X35128Y-101626D01*
X36438Y-101917D01*
X37748Y-102792D01*
G01X67071Y-117667D02*
X68600Y-118834D01*
X70346Y-119125D01*
X71874Y-118834D01*
X73185Y-117376D01*
X74058Y-115334D01*
Y-101626D01*
G01Y-103959D02*
X73185Y-102792D01*
X71874Y-101917D01*
X70346Y-101626D01*
X68600Y-102209D01*
X67508Y-103375D01*
X66634Y-105417D01*
X66198Y-107459D01*
X66416Y-109209D01*
X67290Y-111251D01*
X68600Y-112709D01*
X70346Y-113292D01*
X71656Y-113000D01*
X73185Y-111834D01*
X74058Y-110668D01*
G01X84353Y-105417D02*
X91340D01*
X90685Y-103375D01*
X89593Y-102209D01*
X88065Y-101626D01*
X86536Y-101917D01*
X85226Y-102792D01*
X84353Y-104834D01*
X83916Y-106584D01*
Y-108334D01*
X84353Y-110084D01*
X85445Y-111834D01*
X86755Y-113000D01*
X88283Y-113292D01*
X89811Y-112709D01*
X91340Y-110959D01*
G01X102071Y-113292D02*
Y-101626D01*
G01Y-103959D02*
X103163Y-102792D01*
X104255Y-101917D01*
X105783Y-101626D01*
X106874Y-101917D01*
X108185Y-102792D01*
G01X118698Y-113292D02*
Y-95792D01*
G01Y-104542D02*
X119790Y-102792D01*
X121100Y-101917D01*
X122410Y-101626D01*
X124374Y-102209D01*
X125685Y-103375D01*
X126558Y-105417D01*
Y-107750D01*
X126121Y-110084D01*
X125248Y-111834D01*
X123720Y-113000D01*
X122410Y-113292D01*
X121100Y-113000D01*
X119790Y-112126D01*
X118698Y-110668D01*
G01X136853Y-105417D02*
X143840D01*
X143185Y-103375D01*
X142093Y-102209D01*
X140565Y-101626D01*
X139036Y-101917D01*
X137726Y-102792D01*
X136853Y-104834D01*
X136416Y-106584D01*
Y-108334D01*
X136853Y-110084D01*
X137945Y-111834D01*
X139255Y-113000D01*
X140783Y-113292D01*
X142311Y-112709D01*
X143840Y-110959D01*
G01X154571Y-113292D02*
Y-101626D01*
G01Y-103959D02*
X155663Y-102792D01*
X156755Y-101917D01*
X158283Y-101626D01*
X159374Y-101917D01*
X160685Y-102792D01*
G01X192628Y-101626D02*
Y-113292D01*
G01Y-96959D02*
X192191Y-96667D01*
Y-96084D01*
X192628Y-95792D01*
X193065Y-96084D01*
Y-96667D01*
X192628Y-96959D01*
G01X206853Y-111251D02*
X207945Y-112417D01*
X209473Y-113292D01*
X210783D01*
X212093Y-112709D01*
X212966Y-111834D01*
X213403Y-110668D01*
X213185Y-108917D01*
X212311Y-108042D01*
X208381Y-106292D01*
X207508Y-104250D01*
X207945Y-102792D01*
X208818Y-101917D01*
X210128Y-101626D01*
X211438Y-101917D01*
X212748Y-102792D01*
G01X241634Y-117667D02*
X243163Y-118834D01*
X244473Y-119125D01*
X246220Y-118542D01*
X247530Y-117084D01*
X248185Y-114458D01*
Y-101626D01*
G01Y-96959D02*
X247748Y-96667D01*
Y-96084D01*
X248185Y-95792D01*
X248621Y-96084D01*
Y-96667D01*
X248185Y-96959D01*
G01X258916Y-101626D02*
Y-109792D01*
X259790Y-111834D01*
X261100Y-113000D01*
X262628Y-113292D01*
X264156Y-113000D01*
X265466Y-111834D01*
X266340Y-109792D01*
G01Y-113292D02*
Y-101626D01*
G01X276853Y-111251D02*
X277945Y-112417D01*
X279473Y-113292D01*
X280783D01*
X282093Y-112709D01*
X282966Y-111834D01*
X283403Y-110668D01*
X283185Y-108917D01*
X282311Y-108042D01*
X278381Y-106292D01*
X277508Y-104250D01*
X277945Y-102792D01*
X278818Y-101917D01*
X280128Y-101626D01*
X281438Y-101917D01*
X282748Y-102792D01*
G01X297628Y-95792D02*
Y-113292D01*
G01X294571Y-101626D02*
X300685D01*
G01X331318Y-113292D02*
Y-98417D01*
X331755Y-96959D01*
X332628Y-96084D01*
X333938Y-95792D01*
X335248Y-96375D01*
X335903Y-97834D01*
G01X333283Y-102792D02*
X328916D01*
G01X350128Y-113292D02*
X348818Y-113000D01*
X347508Y-111834D01*
X346634Y-109792D01*
X346198Y-107459D01*
X346634Y-105125D01*
X347508Y-103084D01*
X348818Y-101917D01*
X350128Y-101626D01*
X351438Y-101917D01*
X352748Y-103084D01*
X353621Y-105125D01*
X353840Y-107459D01*
X353621Y-109792D01*
X352748Y-111834D01*
X351438Y-113000D01*
X350128Y-113292D01*
G01X364571D02*
Y-101626D01*
G01Y-103959D02*
X365663Y-102792D01*
X366755Y-101917D01*
X368283Y-101626D01*
X369374Y-101917D01*
X370685Y-102792D01*
G01X398043Y-118542D02*
X399353Y-119125D01*
X401100Y-118542D01*
X402191Y-117376D01*
X403065Y-115917D01*
X404374Y-111251D01*
X407213Y-101626D01*
G01X400226D02*
X404374Y-111251D01*
G01X420128Y-113292D02*
X418818Y-113000D01*
X417508Y-111834D01*
X416634Y-109792D01*
X416198Y-107459D01*
X416634Y-105125D01*
X417508Y-103084D01*
X418818Y-101917D01*
X420128Y-101626D01*
X421438Y-101917D01*
X422748Y-103084D01*
X423621Y-105125D01*
X423840Y-107459D01*
X423621Y-109792D01*
X422748Y-111834D01*
X421438Y-113000D01*
X420128Y-113292D01*
G01X433916Y-101626D02*
Y-109792D01*
X434790Y-111834D01*
X436100Y-113000D01*
X437628Y-113292D01*
X439156Y-113000D01*
X440466Y-111834D01*
X441340Y-109792D01*
G01Y-113292D02*
Y-101626D01*
G01X452071Y-113292D02*
Y-101626D01*
G01Y-103959D02*
X453163Y-102792D01*
X454255Y-101917D01*
X455783Y-101626D01*
X456874Y-101917D01*
X458185Y-102792D01*
G01X487071Y-113292D02*
Y-101626D01*
G01Y-103959D02*
X488163Y-102792D01*
X489255Y-101917D01*
X490783Y-101626D01*
X491874Y-101917D01*
X493185Y-102792D01*
G01X504353Y-105417D02*
X511340D01*
X510685Y-103375D01*
X509593Y-102209D01*
X508065Y-101626D01*
X506536Y-101917D01*
X505226Y-102792D01*
X504353Y-104834D01*
X503916Y-106584D01*
Y-108334D01*
X504353Y-110084D01*
X505445Y-111834D01*
X506755Y-113000D01*
X508283Y-113292D01*
X509811Y-112709D01*
X511340Y-110959D01*
G01X523818Y-113292D02*
Y-98417D01*
X524255Y-96959D01*
X525128Y-96084D01*
X526438Y-95792D01*
X527748Y-96375D01*
X528403Y-97834D01*
G01X525783Y-102792D02*
X521416D01*
G01X539353Y-105417D02*
X546340D01*
X545685Y-103375D01*
X544593Y-102209D01*
X543065Y-101626D01*
X541536Y-101917D01*
X540226Y-102792D01*
X539353Y-104834D01*
X538916Y-106584D01*
Y-108334D01*
X539353Y-110084D01*
X540445Y-111834D01*
X541755Y-113000D01*
X543283Y-113292D01*
X544811Y-112709D01*
X546340Y-110959D01*
G01X557071Y-113292D02*
Y-101626D01*
G01Y-103959D02*
X558163Y-102792D01*
X559255Y-101917D01*
X560783Y-101626D01*
X561874Y-101917D01*
X563185Y-102792D01*
G01X574353Y-105417D02*
X581340D01*
X580685Y-103375D01*
X579593Y-102209D01*
X578065Y-101626D01*
X576536Y-101917D01*
X575226Y-102792D01*
X574353Y-104834D01*
X573916Y-106584D01*
Y-108334D01*
X574353Y-110084D01*
X575445Y-111834D01*
X576755Y-113000D01*
X578283Y-113292D01*
X579811Y-112709D01*
X581340Y-110959D01*
G01X591416Y-113292D02*
Y-101626D01*
G01Y-104542D02*
X592290Y-103084D01*
X593600Y-101917D01*
X595346Y-101626D01*
X596874Y-101917D01*
X598185Y-103084D01*
X598840Y-105125D01*
Y-113292D01*
G01X616121Y-103084D02*
X614593Y-101917D01*
X613283Y-101626D01*
X611536Y-102209D01*
X610226Y-103375D01*
X609353Y-105417D01*
X609134Y-107459D01*
X609353Y-109501D01*
X610226Y-111251D01*
X611536Y-112709D01*
X613283Y-113292D01*
X614811Y-112709D01*
X616121Y-111542D01*
G01X626853Y-105417D02*
X633840D01*
X633185Y-103375D01*
X632093Y-102209D01*
X630565Y-101626D01*
X629036Y-101917D01*
X627726Y-102792D01*
X626853Y-104834D01*
X626416Y-106584D01*
Y-108334D01*
X626853Y-110084D01*
X627945Y-111834D01*
X629255Y-113000D01*
X630783Y-113292D01*
X632311Y-112709D01*
X633840Y-110959D01*
G01X665128Y-95792D02*
Y-113292D01*
G01X662071Y-101626D02*
X668185D01*
G01X682628Y-113292D02*
X681318Y-113000D01*
X680008Y-111834D01*
X679134Y-109792D01*
X678698Y-107459D01*
X679134Y-105125D01*
X680008Y-103084D01*
X681318Y-101917D01*
X682628Y-101626D01*
X683938Y-101917D01*
X685248Y-103084D01*
X686121Y-105125D01*
X686340Y-107459D01*
X686121Y-109792D01*
X685248Y-111834D01*
X683938Y-113000D01*
X682628Y-113292D01*
G01X716318D02*
Y-98417D01*
X716755Y-96959D01*
X717628Y-96084D01*
X718938Y-95792D01*
X720248Y-96375D01*
X720903Y-97834D01*
G01X718283Y-102792D02*
X713916D01*
G01X735128Y-101626D02*
Y-113292D01*
G01Y-96959D02*
X734691Y-96667D01*
Y-96084D01*
X735128Y-95792D01*
X735565Y-96084D01*
Y-96667D01*
X735128Y-96959D01*
G01X748916Y-113292D02*
Y-101626D01*
G01Y-104542D02*
X749790Y-103084D01*
X751100Y-101917D01*
X752846Y-101626D01*
X754374Y-101917D01*
X755685Y-103084D01*
X756340Y-105125D01*
Y-113292D01*
G01X774058Y-95792D02*
Y-113292D01*
G01Y-110668D02*
X773185Y-112126D01*
X771874Y-113000D01*
X770346Y-113292D01*
X768600Y-112709D01*
X767290Y-111251D01*
X766416Y-109501D01*
X766198Y-107459D01*
X766416Y-105417D01*
X767290Y-103667D01*
X768600Y-102209D01*
X770346Y-101626D01*
X771874Y-101917D01*
X772966Y-102501D01*
X774058Y-103667D01*
G01X805128Y-95792D02*
Y-113292D01*
G01X802071Y-101626D02*
X808185D01*
G01X818916Y-113292D02*
Y-95792D01*
G01Y-104250D02*
X820008Y-102792D01*
X821100Y-101917D01*
X822846Y-101626D01*
X824156Y-101917D01*
X825685Y-103084D01*
X826340Y-104834D01*
Y-113292D01*
G01X836853Y-105417D02*
X843840D01*
X843185Y-103375D01*
X842093Y-102209D01*
X840565Y-101626D01*
X839036Y-101917D01*
X837726Y-102792D01*
X836853Y-104834D01*
X836416Y-106584D01*
Y-108334D01*
X836853Y-110084D01*
X837945Y-111834D01*
X839255Y-113000D01*
X840783Y-113292D01*
X842311Y-112709D01*
X843840Y-110959D01*
G01X870325Y-113292D02*
Y-95792D01*
X874691D01*
X876438Y-96667D01*
X877748Y-97834D01*
X878840Y-99583D01*
X879713Y-101626D01*
X879931Y-104542D01*
X879713Y-107459D01*
X878840Y-109501D01*
X877748Y-111251D01*
X876438Y-112417D01*
X874691Y-113292D01*
X870325D01*
G01X888261D02*
Y-95792D01*
X893501D01*
X895248Y-96667D01*
X896558Y-98709D01*
X896995Y-101042D01*
X896558Y-103375D01*
X895466Y-105125D01*
X893501Y-106001D01*
X888261D01*
G01X927628Y-101626D02*
Y-113292D01*
G01Y-96959D02*
X927191Y-96667D01*
Y-96084D01*
X927628Y-95792D01*
X928065Y-96084D01*
Y-96667D01*
X927628Y-96959D01*
G01X938578Y-113292D02*
Y-101626D01*
G01Y-104834D02*
X939233Y-103375D01*
X940325Y-102209D01*
X941853Y-101626D01*
X943381Y-102209D01*
X944473Y-103375D01*
X945128Y-104834D01*
Y-113292D01*
G01Y-104834D02*
X945783Y-103375D01*
X946874Y-102209D01*
X948403Y-101626D01*
X949931Y-102209D01*
X951023Y-103375D01*
X951678Y-105125D01*
Y-113292D01*
G01X958698Y-119125D02*
Y-101626D01*
G01Y-104250D02*
X959790Y-102792D01*
X960881Y-101917D01*
X962628Y-101626D01*
X964156Y-101917D01*
X965685Y-103375D01*
X966340Y-105417D01*
X966558Y-107459D01*
X966340Y-109501D01*
X965685Y-111542D01*
X964374Y-112709D01*
X962628Y-113292D01*
X961100Y-113000D01*
X959571Y-112126D01*
X958698Y-110959D01*
G01X976853Y-105417D02*
X983840D01*
X983185Y-103375D01*
X982093Y-102209D01*
X980565Y-101626D01*
X979036Y-101917D01*
X977726Y-102792D01*
X976853Y-104834D01*
X976416Y-106584D01*
Y-108334D01*
X976853Y-110084D01*
X977945Y-111834D01*
X979255Y-113000D01*
X980783Y-113292D01*
X982311Y-112709D01*
X983840Y-110959D01*
G01X1001558Y-95792D02*
Y-113292D01*
G01Y-110668D02*
X1000685Y-112126D01*
X999374Y-113000D01*
X997846Y-113292D01*
X996100Y-112709D01*
X994790Y-111251D01*
X993916Y-109501D01*
X993698Y-107459D01*
X993916Y-105417D01*
X994790Y-103667D01*
X996100Y-102209D01*
X997846Y-101626D01*
X999374Y-101917D01*
X1000466Y-102501D01*
X1001558Y-103667D01*
G01X1019058Y-113292D02*
Y-101626D01*
G01Y-103667D02*
X1018185Y-102501D01*
X1016874Y-101917D01*
X1015346Y-101626D01*
X1013818Y-102209D01*
X1012508Y-103375D01*
X1011634Y-105125D01*
X1011198Y-107459D01*
X1011634Y-109792D01*
X1012508Y-111542D01*
X1013818Y-112709D01*
X1015346Y-113292D01*
X1016874Y-113000D01*
X1018185Y-112126D01*
X1019058Y-110959D01*
G01X1028916Y-113292D02*
Y-101626D01*
G01Y-104542D02*
X1029790Y-103084D01*
X1031100Y-101917D01*
X1032846Y-101626D01*
X1034374Y-101917D01*
X1035685Y-103084D01*
X1036340Y-105125D01*
Y-113292D01*
G01X1053621Y-103084D02*
X1052093Y-101917D01*
X1050783Y-101626D01*
X1049036Y-102209D01*
X1047726Y-103375D01*
X1046853Y-105417D01*
X1046634Y-107459D01*
X1046853Y-109501D01*
X1047726Y-111251D01*
X1049036Y-112709D01*
X1050783Y-113292D01*
X1052311Y-112709D01*
X1053621Y-111542D01*
G01X1064353Y-105417D02*
X1071340D01*
X1070685Y-103375D01*
X1069593Y-102209D01*
X1068065Y-101626D01*
X1066536Y-101917D01*
X1065226Y-102792D01*
X1064353Y-104834D01*
X1063916Y-106584D01*
Y-108334D01*
X1064353Y-110084D01*
X1065445Y-111834D01*
X1066755Y-113000D01*
X1068283Y-113292D01*
X1069811Y-112709D01*
X1071340Y-110959D01*
G01X1102628Y-95792D02*
Y-113292D01*
G01X1099571Y-101626D02*
X1105685D01*
G01X1117071Y-113292D02*
Y-101626D01*
G01Y-103959D02*
X1118163Y-102792D01*
X1119255Y-101917D01*
X1120783Y-101626D01*
X1121874Y-101917D01*
X1123185Y-102792D01*
G01X1141558Y-113292D02*
Y-101626D01*
G01Y-103667D02*
X1140685Y-102501D01*
X1139374Y-101917D01*
X1137846Y-101626D01*
X1136318Y-102209D01*
X1135008Y-103375D01*
X1134134Y-105125D01*
X1133698Y-107459D01*
X1134134Y-109792D01*
X1135008Y-111542D01*
X1136318Y-112709D01*
X1137846Y-113292D01*
X1139374Y-113000D01*
X1140685Y-112126D01*
X1141558Y-110959D01*
G01X1158621Y-103084D02*
X1157093Y-101917D01*
X1155783Y-101626D01*
X1154036Y-102209D01*
X1152726Y-103375D01*
X1151853Y-105417D01*
X1151634Y-107459D01*
X1151853Y-109501D01*
X1152726Y-111251D01*
X1154036Y-112709D01*
X1155783Y-113292D01*
X1157311Y-112709D01*
X1158621Y-111542D01*
G01X1169353Y-105417D02*
X1176340D01*
X1175685Y-103375D01*
X1174593Y-102209D01*
X1173065Y-101626D01*
X1171536Y-101917D01*
X1170226Y-102792D01*
X1169353Y-104834D01*
X1168916Y-106584D01*
Y-108334D01*
X1169353Y-110084D01*
X1170445Y-111834D01*
X1171755Y-113000D01*
X1173283Y-113292D01*
X1174811Y-112709D01*
X1176340Y-110959D01*
G01X1186853Y-111251D02*
X1187945Y-112417D01*
X1189473Y-113292D01*
X1190783D01*
X1192093Y-112709D01*
X1192966Y-111834D01*
X1193403Y-110668D01*
X1193185Y-108917D01*
X1192311Y-108042D01*
X1188381Y-106292D01*
X1187508Y-104250D01*
X1187945Y-102792D01*
X1188818Y-101917D01*
X1190128Y-101626D01*
X1191438Y-101917D01*
X1192748Y-102792D01*
G01X1225128Y-101626D02*
Y-113292D01*
G01Y-96959D02*
X1224691Y-96667D01*
Y-96084D01*
X1225128Y-95792D01*
X1225565Y-96084D01*
Y-96667D01*
X1225128Y-96959D01*
G01X1238916Y-113292D02*
Y-101626D01*
G01Y-104542D02*
X1239790Y-103084D01*
X1241100Y-101917D01*
X1242846Y-101626D01*
X1244374Y-101917D01*
X1245685Y-103084D01*
X1246340Y-105125D01*
Y-113292D01*
G01X1277628D02*
Y-95792D01*
G01X1299058Y-113292D02*
Y-101626D01*
G01Y-103667D02*
X1298185Y-102501D01*
X1296874Y-101917D01*
X1295346Y-101626D01*
X1293818Y-102209D01*
X1292508Y-103375D01*
X1291634Y-105125D01*
X1291198Y-107459D01*
X1291634Y-109792D01*
X1292508Y-111542D01*
X1293818Y-112709D01*
X1295346Y-113292D01*
X1296874Y-113000D01*
X1298185Y-112126D01*
X1299058Y-110959D01*
G01X1308043Y-118542D02*
X1309353Y-119125D01*
X1311100Y-118542D01*
X1312191Y-117376D01*
X1313065Y-115917D01*
X1314374Y-111251D01*
X1317213Y-101626D01*
G01X1310226D02*
X1314374Y-111251D01*
G01X1326853Y-105417D02*
X1333840D01*
X1333185Y-103375D01*
X1332093Y-102209D01*
X1330565Y-101626D01*
X1329036Y-101917D01*
X1327726Y-102792D01*
X1326853Y-104834D01*
X1326416Y-106584D01*
Y-108334D01*
X1326853Y-110084D01*
X1327945Y-111834D01*
X1329255Y-113000D01*
X1330783Y-113292D01*
X1332311Y-112709D01*
X1333840Y-110959D01*
G01X1344571Y-113292D02*
Y-101626D01*
G01Y-103959D02*
X1345663Y-102792D01*
X1346755Y-101917D01*
X1348283Y-101626D01*
X1349374Y-101917D01*
X1350685Y-102792D01*
G01X1378261Y-95792D02*
Y-113292D01*
X1386995D01*
G01X1395325Y-109792D02*
X1396634Y-111834D01*
X1398381Y-113000D01*
X1400346Y-113292D01*
X1402093Y-113000D01*
X1403840Y-111542D01*
X1404931Y-109792D01*
X1405150Y-108042D01*
X1404713Y-106001D01*
X1403185Y-104542D01*
X1401656Y-103959D01*
X1399691D01*
G01X1401656D02*
X1402966Y-103084D01*
X1404058Y-101626D01*
X1404495Y-99876D01*
X1404058Y-98125D01*
X1402966Y-96667D01*
X1401001Y-95792D01*
X1399036Y-96084D01*
X1397071Y-97251D01*
G01X1417628Y-113875D02*
X1417191Y-113584D01*
Y-113000D01*
X1417628Y-112709D01*
X1418065Y-113000D01*
Y-113584D01*
X1417628Y-113875D01*
G01X2079178Y467898D02*
Y485398D01*
X2076558Y481898D01*
G01Y467898D02*
X2081798D01*
G01X2096678Y485398D02*
X2094931Y484815D01*
X2093621Y483356D01*
X2092748Y481607D01*
X2092093Y479273D01*
X2091875Y476648D01*
X2092093Y474023D01*
X2092748Y471689D01*
X2093621Y469939D01*
X2094931Y468481D01*
X2096678Y467898D01*
X2098424Y468481D01*
X2099735Y469939D01*
X2100608Y471689D01*
X2101263Y474023D01*
X2101481Y476648D01*
X2101263Y479273D01*
X2100608Y481607D01*
X2099735Y483356D01*
X2098424Y484815D01*
X2096678Y485398D01*
G01X2114178D02*
X2112431Y484815D01*
X2111121Y483356D01*
X2110248Y481607D01*
X2109593Y479273D01*
X2109375Y476648D01*
X2109593Y474023D01*
X2110248Y471689D01*
X2111121Y469939D01*
X2112431Y468481D01*
X2114178Y467898D01*
X2115924Y468481D01*
X2117235Y469939D01*
X2118108Y471689D01*
X2118763Y474023D01*
X2118981Y476648D01*
X2118763Y479273D01*
X2118108Y481607D01*
X2117235Y483356D01*
X2115924Y484815D01*
X2114178Y485398D01*
G01X2131678Y467315D02*
X2131241Y467606D01*
Y468190D01*
X2131678Y468481D01*
X2132115Y468190D01*
Y467606D01*
X2131678Y467315D01*
G01X2149178Y485398D02*
X2147431Y484815D01*
X2146121Y483356D01*
X2145248Y481607D01*
X2144593Y479273D01*
X2144375Y476648D01*
X2144593Y474023D01*
X2145248Y471689D01*
X2146121Y469939D01*
X2147431Y468481D01*
X2149178Y467898D01*
X2150924Y468481D01*
X2152235Y469939D01*
X2153108Y471689D01*
X2153763Y474023D01*
X2153981Y476648D01*
X2153763Y479273D01*
X2153108Y481607D01*
X2152235Y483356D01*
X2150924Y484815D01*
X2149178Y485398D01*
G01X2084216Y504589D02*
X2085745Y503131D01*
X2087491Y502548D01*
X2089238Y503131D01*
X2090766Y504881D01*
X2091858Y507506D01*
X2092295Y510131D01*
Y513339D01*
X2091858Y515964D01*
X2090766Y518298D01*
X2089456Y519465D01*
X2087928Y520048D01*
X2086181Y519465D01*
X2084871Y518298D01*
X2083998Y516548D01*
X2083561Y514214D01*
X2083998Y512173D01*
X2085090Y510131D01*
X2086400Y508964D01*
X2087928Y508673D01*
X2089674Y509256D01*
X2090985Y510715D01*
X2092295Y513339D01*
G01X2100625Y505172D02*
X2101934Y503714D01*
X2103463Y502840D01*
X2105428Y502548D01*
X2107393Y503131D01*
X2108921Y504298D01*
X2110013Y506339D01*
X2110231Y508673D01*
X2109795Y511006D01*
X2108703Y512465D01*
X2107174Y513631D01*
X2105646Y513923D01*
X2104118Y513631D01*
X2102153Y512465D01*
X2102808Y520048D01*
X2108703D01*
G01X2122928Y501965D02*
X2122491Y502256D01*
Y502840D01*
X2122928Y503131D01*
X2123365Y502840D01*
Y502256D01*
X2122928Y501965D01*
G01X2140428Y520048D02*
X2138681Y519465D01*
X2137371Y518006D01*
X2136498Y516257D01*
X2135843Y513923D01*
X2135625Y511298D01*
X2135843Y508673D01*
X2136498Y506339D01*
X2137371Y504589D01*
X2138681Y503131D01*
X2140428Y502548D01*
X2142174Y503131D01*
X2143485Y504589D01*
X2144358Y506339D01*
X2145013Y508673D01*
X2145231Y511298D01*
X2145013Y513923D01*
X2144358Y516257D01*
X2143485Y518006D01*
X2142174Y519465D01*
X2140428Y520048D01*
G01X2087928Y537198D02*
X2089456Y537490D01*
X2091203Y538364D01*
X2092295Y539822D01*
X2092731Y541865D01*
X2092295Y543906D01*
X2090985Y545656D01*
X2089020Y546531D01*
X2086836D01*
X2085526Y547115D01*
X2084434Y548573D01*
X2083998Y550614D01*
X2084653Y552656D01*
X2086181Y554115D01*
X2087928Y554698D01*
X2089674Y554115D01*
X2091203Y552656D01*
X2091858Y550614D01*
X2091421Y548573D01*
X2090330Y547115D01*
X2089020Y546531D01*
X2086836D01*
X2084871Y545656D01*
X2083561Y543906D01*
X2083125Y541865D01*
X2083561Y539822D01*
X2084653Y538364D01*
X2086400Y537490D01*
X2087928Y537198D01*
G01X2100625Y539822D02*
X2101934Y538364D01*
X2103463Y537490D01*
X2105428Y537198D01*
X2107393Y537781D01*
X2108921Y538948D01*
X2110013Y540989D01*
X2110231Y543323D01*
X2109795Y545656D01*
X2108703Y547115D01*
X2107174Y548281D01*
X2105646Y548573D01*
X2104118Y548281D01*
X2102153Y547115D01*
X2102808Y554698D01*
X2108703D01*
G01X2122928Y536615D02*
X2122491Y536906D01*
Y537490D01*
X2122928Y537781D01*
X2123365Y537490D01*
Y536906D01*
X2122928Y536615D01*
G01X2140428Y554698D02*
X2138681Y554115D01*
X2137371Y552656D01*
X2136498Y550907D01*
X2135843Y548573D01*
X2135625Y545948D01*
X2135843Y543323D01*
X2136498Y540989D01*
X2137371Y539239D01*
X2138681Y537781D01*
X2140428Y537198D01*
X2142174Y537781D01*
X2143485Y539239D01*
X2144358Y540989D01*
X2145013Y543323D01*
X2145231Y545948D01*
X2145013Y548573D01*
X2144358Y550907D01*
X2143485Y552656D01*
X2142174Y554115D01*
X2140428Y554698D01*
G01X2087491Y571848D02*
X2087928Y575639D01*
X2088583Y578848D01*
X2089456Y581765D01*
X2090548Y584973D01*
X2092295Y589348D01*
X2083561D01*
G01X2100625Y575348D02*
X2101934Y573306D01*
X2103681Y572140D01*
X2105646Y571848D01*
X2107393Y572140D01*
X2109140Y573598D01*
X2110231Y575348D01*
X2110450Y577098D01*
X2110013Y579139D01*
X2108485Y580598D01*
X2106956Y581181D01*
X2104991D01*
G01X2106956D02*
X2108266Y582056D01*
X2109358Y583514D01*
X2109795Y585264D01*
X2109358Y587015D01*
X2108266Y588473D01*
X2106301Y589348D01*
X2104336Y589056D01*
X2102371Y587889D01*
G01X2122928Y571265D02*
X2122491Y571556D01*
Y572140D01*
X2122928Y572431D01*
X2123365Y572140D01*
Y571556D01*
X2122928Y571265D01*
G01X2140428Y589348D02*
X2138681Y588765D01*
X2137371Y587306D01*
X2136498Y585557D01*
X2135843Y583223D01*
X2135625Y580598D01*
X2135843Y577973D01*
X2136498Y575639D01*
X2137371Y573889D01*
X2138681Y572431D01*
X2140428Y571848D01*
X2142174Y572431D01*
X2143485Y573889D01*
X2144358Y575639D01*
X2145013Y577973D01*
X2145231Y580598D01*
X2145013Y583223D01*
X2144358Y585557D01*
X2143485Y587306D01*
X2142174Y588765D01*
X2140428Y589348D01*
G01X2050308Y623998D02*
X2055548D01*
G01X2052928D02*
Y606498D01*
G01X2050308D02*
X2055548D01*
G01X2064751D02*
Y623998D01*
X2070428Y609415D01*
X2076105Y623998D01*
Y606498D01*
G01X2083561D02*
Y623998D01*
X2088801D01*
X2090548Y623123D01*
X2091858Y621081D01*
X2092295Y618748D01*
X2091858Y616415D01*
X2090766Y614665D01*
X2088801Y613789D01*
X2083561D01*
G01X2104336Y600665D02*
X2102153Y603581D01*
X2101061Y606498D01*
Y618164D01*
X2102153Y621081D01*
X2104336Y623998D01*
G01X2122928Y606498D02*
X2121181Y606790D01*
X2119653Y607956D01*
X2118343Y609706D01*
X2117469Y611748D01*
X2117033Y614081D01*
Y616415D01*
X2117469Y618748D01*
X2118343Y620790D01*
X2119653Y622539D01*
X2121181Y623706D01*
X2122928Y623998D01*
X2124674Y623706D01*
X2126203Y622539D01*
X2127513Y620790D01*
X2128387Y618748D01*
X2128823Y616415D01*
Y614081D01*
X2128387Y611748D01*
X2127513Y609706D01*
X2126203Y607956D01*
X2124674Y606790D01*
X2122928Y606498D01*
G01X2136716D02*
Y623998D01*
G01Y615540D02*
X2137808Y616998D01*
X2138900Y617873D01*
X2140646Y618164D01*
X2141956Y617873D01*
X2143485Y616706D01*
X2144140Y614956D01*
Y606498D01*
G01X2151378D02*
Y618164D01*
G01Y614956D02*
X2152033Y616415D01*
X2153125Y617581D01*
X2154653Y618164D01*
X2156181Y617581D01*
X2157273Y616415D01*
X2157928Y614956D01*
Y606498D01*
G01Y614956D02*
X2158583Y616415D01*
X2159674Y617581D01*
X2161203Y618164D01*
X2162731Y617581D01*
X2163823Y616415D01*
X2164478Y614665D01*
Y606498D01*
G01X2176520Y600665D02*
X2178703Y603581D01*
X2179795Y606498D01*
Y618164D01*
X2178703Y621081D01*
X2176520Y623998D01*
G01X2028425Y641148D02*
Y658648D01*
X2032791D01*
X2034538Y657773D01*
X2035848Y656606D01*
X2036940Y654857D01*
X2037813Y652814D01*
X2038031Y649898D01*
X2037813Y646981D01*
X2036940Y644939D01*
X2035848Y643189D01*
X2034538Y642023D01*
X2032791Y641148D01*
X2028425D01*
G01X2046361D02*
Y658648D01*
X2051601D01*
X2053348Y657773D01*
X2054658Y655731D01*
X2055095Y653398D01*
X2054658Y651065D01*
X2053566Y649315D01*
X2051601Y648439D01*
X2046361D01*
G01X2083108Y658648D02*
X2088348D01*
G01X2085728D02*
Y641148D01*
G01X2083108D02*
X2088348D01*
G01X2097551D02*
Y658648D01*
X2103228Y644065D01*
X2108905Y658648D01*
Y641148D01*
G01X2116361D02*
Y658648D01*
X2121601D01*
X2123348Y657773D01*
X2124658Y655731D01*
X2125095Y653398D01*
X2124658Y651065D01*
X2123566Y649315D01*
X2121601Y648439D01*
X2116361D01*
G01X2142595Y641148D02*
X2133861D01*
Y658648D01*
X2142595D01*
G01X2139101Y650190D02*
X2133861D01*
G01X2150925Y641148D02*
Y658648D01*
X2155291D01*
X2157038Y657773D01*
X2158348Y656606D01*
X2159440Y654857D01*
X2160313Y652814D01*
X2160531Y649898D01*
X2160313Y646981D01*
X2159440Y644939D01*
X2158348Y643189D01*
X2157038Y642023D01*
X2155291Y641148D01*
X2150925D01*
G01X2167769D02*
X2173228Y658648D01*
X2178687Y641148D01*
G01X2176721Y647273D02*
X2169734D01*
G01X2185706Y641148D02*
Y658648D01*
X2195750Y641148D01*
Y658648D01*
G01X2213031Y657189D02*
X2211721Y658065D01*
X2210193Y658648D01*
X2208446D01*
X2206481Y657773D01*
X2204953Y656315D01*
X2203861Y654564D01*
X2202988Y651648D01*
X2202769Y649023D01*
X2203206Y646398D01*
X2203861Y644648D01*
X2205171Y642898D01*
X2206700Y641731D01*
X2208228Y641148D01*
X2209756D01*
X2211285Y641731D01*
X2212595Y642606D01*
X2213687Y643772D01*
G01X2230095Y641148D02*
X2221361D01*
Y658648D01*
X2230095D01*
G01X2226601Y650190D02*
X2221361D01*
G01X2260728Y658648D02*
Y641148D01*
G01X2255706Y658648D02*
X2265750D01*
G01X2272769Y641148D02*
X2278228Y658648D01*
X2283687Y641148D01*
G01X2281721Y647273D02*
X2274734D01*
G01X2297474Y650481D02*
X2298348Y651356D01*
X2299003Y652814D01*
X2299440Y654857D01*
X2299003Y656606D01*
X2298130Y657773D01*
X2296601Y658648D01*
X2290706D01*
Y641148D01*
X2297911D01*
X2299440Y642314D01*
X2300313Y644065D01*
X2300750Y646106D01*
X2300313Y648148D01*
X2299003Y649898D01*
X2297474Y650481D01*
X2290706D01*
G01X2308861Y658648D02*
Y641148D01*
X2317595D01*
G01X2335095D02*
X2326361D01*
Y658648D01*
X2335095D01*
G01X2331601Y650190D02*
X2326361D01*
G01X2348228Y640565D02*
X2347791Y640856D01*
Y641440D01*
X2348228Y641731D01*
X2348665Y641440D01*
Y640856D01*
X2348228Y640565D01*
G01Y648439D02*
X2347791Y648731D01*
Y649315D01*
X2348228Y649606D01*
X2348665Y649315D01*
Y648731D01*
X2348228Y648439D01*
G01X2378861Y658648D02*
Y641148D01*
X2387595D01*
G01X2395925Y644648D02*
X2397234Y642606D01*
X2398981Y641440D01*
X2400946Y641148D01*
X2402693Y641440D01*
X2404440Y642898D01*
X2405531Y644648D01*
X2405750Y646398D01*
X2405313Y648439D01*
X2403785Y649898D01*
X2402256Y650481D01*
X2400291D01*
G01X2402256D02*
X2403566Y651356D01*
X2404658Y652814D01*
X2405095Y654564D01*
X2404658Y656315D01*
X2403566Y657773D01*
X2401601Y658648D01*
X2399636Y658356D01*
X2397671Y657189D01*
G01X2284375Y467315D02*
X2293981Y480148D01*
G01X2289178Y482481D02*
Y464981D01*
G01X2293981Y467315D02*
X2284375Y480148D01*
G01X2282628Y473731D02*
X2295728D01*
G01X2301875Y471398D02*
X2303184Y469356D01*
X2304931Y468190D01*
X2306896Y467898D01*
X2308643Y468190D01*
X2310390Y469648D01*
X2311481Y471398D01*
X2311700Y473148D01*
X2311263Y475189D01*
X2309735Y476648D01*
X2308206Y477231D01*
X2306241D01*
G01X2308206D02*
X2309516Y478106D01*
X2310608Y479564D01*
X2311045Y481314D01*
X2310608Y483065D01*
X2309516Y484523D01*
X2307551Y485398D01*
X2305586Y485106D01*
X2303621Y483939D01*
G01X2324178Y467315D02*
X2323741Y467606D01*
Y468190D01*
X2324178Y468481D01*
X2324615Y468190D01*
Y467606D01*
X2324178Y467315D01*
G01X2337966Y469939D02*
X2339495Y468481D01*
X2341241Y467898D01*
X2342988Y468481D01*
X2344516Y470231D01*
X2345608Y472856D01*
X2346045Y475481D01*
Y478689D01*
X2345608Y481314D01*
X2344516Y483648D01*
X2343206Y484815D01*
X2341678Y485398D01*
X2339931Y484815D01*
X2338621Y483648D01*
X2337748Y481898D01*
X2337311Y479564D01*
X2337748Y477523D01*
X2338840Y475481D01*
X2340150Y474314D01*
X2341678Y474023D01*
X2343424Y474606D01*
X2344735Y476065D01*
X2346045Y478689D01*
G01X2355466Y469939D02*
X2356995Y468481D01*
X2358741Y467898D01*
X2360488Y468481D01*
X2362016Y470231D01*
X2363108Y472856D01*
X2363545Y475481D01*
Y478689D01*
X2363108Y481314D01*
X2362016Y483648D01*
X2360706Y484815D01*
X2359178Y485398D01*
X2357431Y484815D01*
X2356121Y483648D01*
X2355248Y481898D01*
X2354811Y479564D01*
X2355248Y477523D01*
X2356340Y475481D01*
X2357650Y474314D01*
X2359178Y474023D01*
X2360924Y474606D01*
X2362235Y476065D01*
X2363545Y478689D01*
G01X2372748Y467315D02*
X2380608Y485398D01*
G01X2394178Y467898D02*
Y485398D01*
X2391558Y481898D01*
G01Y467898D02*
X2396798D01*
G01X2407530Y482481D02*
X2408840Y484231D01*
X2410368Y485106D01*
X2412115Y485398D01*
X2414298Y484815D01*
X2415826Y483356D01*
X2416263Y481607D01*
X2416045Y479856D01*
X2415171Y478398D01*
X2410805Y475481D01*
X2408840Y473440D01*
X2407530Y470522D01*
X2407093Y467898D01*
X2416263D01*
G01X2429178Y467315D02*
X2428741Y467606D01*
Y468190D01*
X2429178Y468481D01*
X2429615Y468190D01*
Y467606D01*
X2429178Y467315D01*
G01X2441875Y470522D02*
X2443184Y469064D01*
X2444713Y468190D01*
X2446678Y467898D01*
X2448643Y468481D01*
X2450171Y469648D01*
X2451263Y471689D01*
X2451481Y474023D01*
X2451045Y476356D01*
X2449953Y477815D01*
X2448424Y478981D01*
X2446896Y479273D01*
X2445368Y478981D01*
X2443403Y477815D01*
X2444058Y485398D01*
X2449953D01*
G01X2460030Y482481D02*
X2461340Y484231D01*
X2462868Y485106D01*
X2464615Y485398D01*
X2466798Y484815D01*
X2468326Y483356D01*
X2468763Y481607D01*
X2468545Y479856D01*
X2467671Y478398D01*
X2463305Y475481D01*
X2461340Y473440D01*
X2460030Y470522D01*
X2459593Y467898D01*
X2468763D01*
G01X2284375Y501965D02*
X2293981Y514798D01*
G01X2289178Y517131D02*
Y499631D01*
G01X2293981Y501965D02*
X2284375Y514798D01*
G01X2282628Y508381D02*
X2295728D01*
G01X2309298Y502548D02*
Y520048D01*
X2301219Y507506D01*
X2312137D01*
G01X2324178Y501965D02*
X2323741Y502256D01*
Y502840D01*
X2324178Y503131D01*
X2324615Y502840D01*
Y502256D01*
X2324178Y501965D01*
G01X2341678Y520048D02*
X2339931Y519465D01*
X2338621Y518006D01*
X2337748Y516257D01*
X2337093Y513923D01*
X2336875Y511298D01*
X2337093Y508673D01*
X2337748Y506339D01*
X2338621Y504589D01*
X2339931Y503131D01*
X2341678Y502548D01*
X2343424Y503131D01*
X2344735Y504589D01*
X2345608Y506339D01*
X2346263Y508673D01*
X2346481Y511298D01*
X2346263Y513923D01*
X2345608Y516257D01*
X2344735Y518006D01*
X2343424Y519465D01*
X2341678Y520048D01*
G01X2355030Y517131D02*
X2356340Y518881D01*
X2357868Y519756D01*
X2359615Y520048D01*
X2361798Y519465D01*
X2363326Y518006D01*
X2363763Y516257D01*
X2363545Y514506D01*
X2362671Y513048D01*
X2358305Y510131D01*
X2356340Y508090D01*
X2355030Y505172D01*
X2354593Y502548D01*
X2363763D01*
G01X2372748Y501965D02*
X2380608Y520048D01*
G01X2394178Y502548D02*
Y520048D01*
X2391558Y516548D01*
G01Y502548D02*
X2396798D01*
G01X2411678D02*
Y520048D01*
X2409058Y516548D01*
G01Y502548D02*
X2414298D01*
G01X2429178Y501965D02*
X2428741Y502256D01*
Y502840D01*
X2429178Y503131D01*
X2429615Y502840D01*
Y502256D01*
X2429178Y501965D01*
G01X2442966Y504589D02*
X2444495Y503131D01*
X2446241Y502548D01*
X2447988Y503131D01*
X2449516Y504881D01*
X2450608Y507506D01*
X2451045Y510131D01*
Y513339D01*
X2450608Y515964D01*
X2449516Y518298D01*
X2448206Y519465D01*
X2446678Y520048D01*
X2444931Y519465D01*
X2443621Y518298D01*
X2442748Y516548D01*
X2442311Y514214D01*
X2442748Y512173D01*
X2443840Y510131D01*
X2445150Y508964D01*
X2446678Y508673D01*
X2448424Y509256D01*
X2449735Y510715D01*
X2451045Y513339D01*
G01X2464178Y502548D02*
X2465706Y502840D01*
X2467453Y503714D01*
X2468545Y505172D01*
X2468981Y507215D01*
X2468545Y509256D01*
X2467235Y511006D01*
X2465270Y511881D01*
X2463086D01*
X2461776Y512465D01*
X2460684Y513923D01*
X2460248Y515964D01*
X2460903Y518006D01*
X2462431Y519465D01*
X2464178Y520048D01*
X2465924Y519465D01*
X2467453Y518006D01*
X2468108Y515964D01*
X2467671Y513923D01*
X2466580Y512465D01*
X2465270Y511881D01*
X2463086D01*
X2461121Y511006D01*
X2459811Y509256D01*
X2459375Y507215D01*
X2459811Y505172D01*
X2460903Y503714D01*
X2462650Y502840D01*
X2464178Y502548D01*
G01X2326798Y537198D02*
Y554698D01*
X2318719Y542156D01*
X2329637D01*
G01X2341678Y536615D02*
X2341241Y536906D01*
Y537490D01*
X2341678Y537781D01*
X2342115Y537490D01*
Y536906D01*
X2341678Y536615D01*
G01X2354375Y539822D02*
X2355684Y538364D01*
X2357213Y537490D01*
X2359178Y537198D01*
X2361143Y537781D01*
X2362671Y538948D01*
X2363763Y540989D01*
X2363981Y543323D01*
X2363545Y545656D01*
X2362453Y547115D01*
X2360924Y548281D01*
X2359396Y548573D01*
X2357868Y548281D01*
X2355903Y547115D01*
X2356558Y554698D01*
X2362453D01*
G01X2372748Y536615D02*
X2380608Y554698D01*
G01X2393741Y537198D02*
X2394178Y540989D01*
X2394833Y544198D01*
X2395706Y547115D01*
X2396798Y550323D01*
X2398545Y554698D01*
X2389811D01*
G01X2411678Y536615D02*
X2411241Y536906D01*
Y537490D01*
X2411678Y537781D01*
X2412115Y537490D01*
Y536906D01*
X2411678Y536615D01*
G01X2429178Y554698D02*
X2427431Y554115D01*
X2426121Y552656D01*
X2425248Y550907D01*
X2424593Y548573D01*
X2424375Y545948D01*
X2424593Y543323D01*
X2425248Y540989D01*
X2426121Y539239D01*
X2427431Y537781D01*
X2429178Y537198D01*
X2430924Y537781D01*
X2432235Y539239D01*
X2433108Y540989D01*
X2433763Y543323D01*
X2433981Y545948D01*
X2433763Y548573D01*
X2433108Y550907D01*
X2432235Y552656D01*
X2430924Y554115D01*
X2429178Y554698D01*
G01X2319375Y574472D02*
X2320684Y573014D01*
X2322213Y572140D01*
X2324178Y571848D01*
X2326143Y572431D01*
X2327671Y573598D01*
X2328763Y575639D01*
X2328981Y577973D01*
X2328545Y580306D01*
X2327453Y581765D01*
X2325924Y582931D01*
X2324396Y583223D01*
X2322868Y582931D01*
X2320903Y581765D01*
X2321558Y589348D01*
X2327453D01*
G01X2341678Y571265D02*
X2341241Y571556D01*
Y572140D01*
X2341678Y572431D01*
X2342115Y572140D01*
Y571556D01*
X2341678Y571265D01*
G01X2355030Y579139D02*
X2356558Y581181D01*
X2357868Y582348D01*
X2359615Y582931D01*
X2361143Y582348D01*
X2362235Y581181D01*
X2363108Y579431D01*
X2363326Y577390D01*
X2363108Y575639D01*
X2362235Y573889D01*
X2360924Y572431D01*
X2359396Y571848D01*
X2357650Y572431D01*
X2356121Y574181D01*
X2355248Y576806D01*
X2355030Y579723D01*
X2355466Y583514D01*
X2356121Y585557D01*
X2357213Y587598D01*
X2358741Y589056D01*
X2360270Y589348D01*
X2361798Y588765D01*
X2362890Y587306D01*
G01X2372748Y571265D02*
X2380608Y589348D01*
G01X2389375Y574472D02*
X2390684Y573014D01*
X2392213Y572140D01*
X2394178Y571848D01*
X2396143Y572431D01*
X2397671Y573598D01*
X2398763Y575639D01*
X2398981Y577973D01*
X2398545Y580306D01*
X2397453Y581765D01*
X2395924Y582931D01*
X2394396Y583223D01*
X2392868Y582931D01*
X2390903Y581765D01*
X2391558Y589348D01*
X2397453D01*
G01X2411678Y571265D02*
X2411241Y571556D01*
Y572140D01*
X2411678Y572431D01*
X2412115Y572140D01*
Y571556D01*
X2411678Y571265D01*
G01X2429178Y589348D02*
X2427431Y588765D01*
X2426121Y587306D01*
X2425248Y585557D01*
X2424593Y583223D01*
X2424375Y580598D01*
X2424593Y577973D01*
X2425248Y575639D01*
X2426121Y573889D01*
X2427431Y572431D01*
X2429178Y571848D01*
X2430924Y572431D01*
X2432235Y573889D01*
X2433108Y575639D01*
X2433763Y577973D01*
X2433981Y580598D01*
X2433763Y583223D01*
X2433108Y585557D01*
X2432235Y587306D01*
X2430924Y588765D01*
X2429178Y589348D01*
G01X2282628Y623998D02*
X2285684Y606498D01*
X2289178Y623998D01*
X2292671Y606498D01*
X2295728Y623998D01*
G01X2304058D02*
X2309298D01*
G01X2306678D02*
Y606498D01*
G01X2304058D02*
X2309298D01*
G01X2319375D02*
Y623998D01*
X2323741D01*
X2325488Y623123D01*
X2326798Y621956D01*
X2327890Y620207D01*
X2328763Y618164D01*
X2328981Y615248D01*
X2328763Y612331D01*
X2327890Y610289D01*
X2326798Y608539D01*
X2325488Y607373D01*
X2323741Y606498D01*
X2319375D01*
G01X2341678Y623998D02*
Y606498D01*
G01X2336656Y623998D02*
X2346700D01*
G01X2354593Y606498D02*
Y623998D01*
G01X2363763D02*
Y606498D01*
G01Y615248D02*
X2354593D01*
G01X2375586Y600665D02*
X2373403Y603581D01*
X2372311Y606498D01*
Y618164D01*
X2373403Y621081D01*
X2375586Y623998D01*
G01X2387628Y606498D02*
Y618164D01*
G01Y614956D02*
X2388283Y616415D01*
X2389375Y617581D01*
X2390903Y618164D01*
X2392431Y617581D01*
X2393523Y616415D01*
X2394178Y614956D01*
Y606498D01*
G01Y614956D02*
X2394833Y616415D01*
X2395924Y617581D01*
X2397453Y618164D01*
X2398981Y617581D01*
X2400073Y616415D01*
X2400728Y614665D01*
Y606498D01*
G01X2411678Y618164D02*
Y606498D01*
G01Y622831D02*
X2411241Y623123D01*
Y623706D01*
X2411678Y623998D01*
X2412115Y623706D01*
Y623123D01*
X2411678Y622831D01*
G01X2429178Y606498D02*
Y623998D01*
G01X2443403Y608539D02*
X2444495Y607373D01*
X2446023Y606498D01*
X2447333D01*
X2448643Y607081D01*
X2449516Y607956D01*
X2449953Y609122D01*
X2449735Y610873D01*
X2448861Y611748D01*
X2444931Y613498D01*
X2444058Y615540D01*
X2444495Y616998D01*
X2445368Y617873D01*
X2446678Y618164D01*
X2447988Y617873D01*
X2449298Y616998D01*
G01X2465270Y600665D02*
X2467453Y603581D01*
X2468545Y606498D01*
Y618164D01*
X2467453Y621081D01*
X2465270Y623998D01*
G01X2577928D02*
Y606498D01*
G01X2572906Y623998D02*
X2582950D01*
G01X2595428Y606498D02*
Y614373D01*
X2591061Y623998D01*
G01X2599795D02*
X2595428Y614373D01*
G01X2608561Y606498D02*
Y623998D01*
X2613801D01*
X2615548Y623123D01*
X2616858Y621081D01*
X2617295Y618748D01*
X2616858Y616415D01*
X2615766Y614665D01*
X2613801Y613789D01*
X2608561D01*
G01X2634795Y606498D02*
X2626061D01*
Y623998D01*
X2634795D01*
G01X2631301Y615540D02*
X2626061D01*
G01X2590625Y467898D02*
Y485398D01*
X2594991D01*
X2596738Y484523D01*
X2598048Y483356D01*
X2599140Y481607D01*
X2600013Y479564D01*
X2600231Y476648D01*
X2600013Y473731D01*
X2599140Y471689D01*
X2598048Y469939D01*
X2596738Y468773D01*
X2594991Y467898D01*
X2590625D01*
G01X2608561D02*
Y485398D01*
X2613801D01*
X2615548Y484523D01*
X2616858Y482481D01*
X2617295Y480148D01*
X2616858Y477815D01*
X2615766Y476065D01*
X2613801Y475189D01*
X2608561D01*
G01X2590625Y502548D02*
Y520048D01*
X2594991D01*
X2596738Y519173D01*
X2598048Y518006D01*
X2599140Y516257D01*
X2600013Y514214D01*
X2600231Y511298D01*
X2600013Y508381D01*
X2599140Y506339D01*
X2598048Y504589D01*
X2596738Y503423D01*
X2594991Y502548D01*
X2590625D01*
G01X2608561D02*
Y520048D01*
X2613801D01*
X2615548Y519173D01*
X2616858Y517131D01*
X2617295Y514798D01*
X2616858Y512465D01*
X2615766Y510715D01*
X2613801Y509839D01*
X2608561D01*
G01X2590625Y537198D02*
Y554698D01*
X2594991D01*
X2596738Y553823D01*
X2598048Y552656D01*
X2599140Y550907D01*
X2600013Y548864D01*
X2600231Y545948D01*
X2600013Y543031D01*
X2599140Y540989D01*
X2598048Y539239D01*
X2596738Y538073D01*
X2594991Y537198D01*
X2590625D01*
G01X2608561D02*
Y554698D01*
X2613801D01*
X2615548Y553823D01*
X2616858Y551781D01*
X2617295Y549448D01*
X2616858Y547115D01*
X2615766Y545365D01*
X2613801Y544489D01*
X2608561D01*
G01X2590625Y571848D02*
Y589348D01*
X2594991D01*
X2596738Y588473D01*
X2598048Y587306D01*
X2599140Y585557D01*
X2600013Y583514D01*
X2600231Y580598D01*
X2600013Y577681D01*
X2599140Y575639D01*
X2598048Y573889D01*
X2596738Y572723D01*
X2594991Y571848D01*
X2590625D01*
G01X2608561D02*
Y589348D01*
X2613801D01*
X2615548Y588473D01*
X2616858Y586431D01*
X2617295Y584098D01*
X2616858Y581765D01*
X2615766Y580015D01*
X2613801Y579139D01*
X2608561D01*
G01X2678561Y606498D02*
Y623998D01*
X2684020D01*
X2685766Y623123D01*
X2686858Y621956D01*
X2687295Y619623D01*
X2686858Y617289D01*
X2685548Y615831D01*
X2684020Y614956D01*
X2678561D01*
G01X2684020D02*
X2687295Y606498D01*
G01X2697153Y614373D02*
X2704140D01*
X2703485Y616415D01*
X2702393Y617581D01*
X2700865Y618164D01*
X2699336Y617873D01*
X2698026Y616998D01*
X2697153Y614956D01*
X2696716Y613206D01*
Y611456D01*
X2697153Y609706D01*
X2698245Y607956D01*
X2699555Y606790D01*
X2701083Y606498D01*
X2702611Y607081D01*
X2704140Y608831D01*
G01X2716618Y606498D02*
Y621373D01*
X2717055Y622831D01*
X2717928Y623706D01*
X2719238Y623998D01*
X2720548Y623415D01*
X2721203Y621956D01*
G01X2718583Y616998D02*
X2714216D01*
G01X2735428Y605915D02*
X2734991Y606206D01*
Y606790D01*
X2735428Y607081D01*
X2735865Y606790D01*
Y606206D01*
X2735428Y605915D01*
G01X2766061Y606498D02*
Y623998D01*
X2771301D01*
X2773048Y623123D01*
X2774358Y621081D01*
X2774795Y618748D01*
X2774358Y616415D01*
X2773266Y614665D01*
X2771301Y613789D01*
X2766061D01*
G01X2787928Y606498D02*
Y623998D01*
G01X2809358Y606498D02*
Y618164D01*
G01Y616123D02*
X2808485Y617289D01*
X2807174Y617873D01*
X2805646Y618164D01*
X2804118Y617581D01*
X2802808Y616415D01*
X2801934Y614665D01*
X2801498Y612331D01*
X2801934Y609998D01*
X2802808Y608248D01*
X2804118Y607081D01*
X2805646Y606498D01*
X2807174Y606790D01*
X2808485Y607664D01*
X2809358Y608831D01*
G01X2819216Y606498D02*
Y618164D01*
G01Y615248D02*
X2820090Y616706D01*
X2821400Y617873D01*
X2823146Y618164D01*
X2824674Y617873D01*
X2825985Y616706D01*
X2826640Y614665D01*
Y606498D01*
G01X2837153Y614373D02*
X2844140D01*
X2843485Y616415D01*
X2842393Y617581D01*
X2840865Y618164D01*
X2839336Y617873D01*
X2838026Y616998D01*
X2837153Y614956D01*
X2836716Y613206D01*
Y611456D01*
X2837153Y609706D01*
X2838245Y607956D01*
X2839555Y606790D01*
X2841083Y606498D01*
X2842611Y607081D01*
X2844140Y608831D01*
G01X2722311Y485398D02*
Y467898D01*
X2731045D01*
G01X2740030Y482481D02*
X2741340Y484231D01*
X2742868Y485106D01*
X2744615Y485398D01*
X2746798Y484815D01*
X2748326Y483356D01*
X2748763Y481607D01*
X2748545Y479856D01*
X2747671Y478398D01*
X2743305Y475481D01*
X2741340Y473440D01*
X2740030Y470522D01*
X2739593Y467898D01*
X2748763D01*
G01X2757748Y467315D02*
X2765608Y485398D01*
G01X2774811D02*
Y467898D01*
X2783545D01*
G01X2799298D02*
Y485398D01*
X2791219Y472856D01*
X2802137D01*
G01X2722311Y520048D02*
Y502548D01*
X2731045D01*
G01X2740030Y517131D02*
X2741340Y518881D01*
X2742868Y519756D01*
X2744615Y520048D01*
X2746798Y519465D01*
X2748326Y518006D01*
X2748763Y516257D01*
X2748545Y514506D01*
X2747671Y513048D01*
X2743305Y510131D01*
X2741340Y508090D01*
X2740030Y505172D01*
X2739593Y502548D01*
X2748763D01*
G01X2757748Y501965D02*
X2765608Y520048D01*
G01X2774811D02*
Y502548D01*
X2783545D01*
G01X2799298D02*
Y520048D01*
X2791219Y507506D01*
X2802137D01*
G01X2722311Y554698D02*
Y537198D01*
X2731045D01*
G01X2740030Y551781D02*
X2741340Y553531D01*
X2742868Y554406D01*
X2744615Y554698D01*
X2746798Y554115D01*
X2748326Y552656D01*
X2748763Y550907D01*
X2748545Y549156D01*
X2747671Y547698D01*
X2743305Y544781D01*
X2741340Y542740D01*
X2740030Y539822D01*
X2739593Y537198D01*
X2748763D01*
G01X2757748Y536615D02*
X2765608Y554698D01*
G01X2774811D02*
Y537198D01*
X2783545D01*
G01X2799298D02*
Y554698D01*
X2791219Y542156D01*
X2802137D01*
G01X2722311Y589348D02*
Y571848D01*
X2731045D01*
G01X2740030Y586431D02*
X2741340Y588181D01*
X2742868Y589056D01*
X2744615Y589348D01*
X2746798Y588765D01*
X2748326Y587306D01*
X2748763Y585557D01*
X2748545Y583806D01*
X2747671Y582348D01*
X2743305Y579431D01*
X2741340Y577390D01*
X2740030Y574472D01*
X2739593Y571848D01*
X2748763D01*
G01X2757748Y571265D02*
X2765608Y589348D01*
G01X2774811D02*
Y571848D01*
X2783545D01*
G01X2799298D02*
Y589348D01*
X2791219Y576806D01*
X2802137D01*
G01X2958228Y548864D02*
Y537198D01*
G01Y553531D02*
X2957791Y553823D01*
Y554406D01*
X2958228Y554698D01*
X2958665Y554406D01*
Y553823D01*
X2958228Y553531D01*
G01X2972016Y537198D02*
Y548864D01*
G01Y545948D02*
X2972890Y547406D01*
X2974200Y548573D01*
X2975946Y548864D01*
X2977474Y548573D01*
X2978785Y547406D01*
X2979440Y545365D01*
Y537198D01*
G01X2989953Y539239D02*
X2991045Y538073D01*
X2992573Y537198D01*
X2993883D01*
X2995193Y537781D01*
X2996066Y538656D01*
X2996503Y539822D01*
X2996285Y541573D01*
X2995411Y542448D01*
X2991481Y544198D01*
X2990608Y546240D01*
X2991045Y547698D01*
X2991918Y548573D01*
X2993228Y548864D01*
X2994538Y548573D01*
X2995848Y547698D01*
G01X3010728Y548864D02*
Y537198D01*
G01Y553531D02*
X3010291Y553823D01*
Y554406D01*
X3010728Y554698D01*
X3011165Y554406D01*
Y553823D01*
X3010728Y553531D01*
G01X3032158Y554698D02*
Y537198D01*
G01Y539822D02*
X3031285Y538364D01*
X3029974Y537490D01*
X3028446Y537198D01*
X3026700Y537781D01*
X3025390Y539239D01*
X3024516Y540989D01*
X3024298Y543031D01*
X3024516Y545073D01*
X3025390Y546823D01*
X3026700Y548281D01*
X3028446Y548864D01*
X3029974Y548573D01*
X3031066Y547989D01*
X3032158Y546823D01*
G01X3042453Y545073D02*
X3049440D01*
X3048785Y547115D01*
X3047693Y548281D01*
X3046165Y548864D01*
X3044636Y548573D01*
X3043326Y547698D01*
X3042453Y545656D01*
X3042016Y543906D01*
Y542156D01*
X3042453Y540406D01*
X3043545Y538656D01*
X3044855Y537490D01*
X3046383Y537198D01*
X3047911Y537781D01*
X3049440Y539531D01*
G01X3076798Y537198D02*
Y554698D01*
G01Y545948D02*
X3077890Y547698D01*
X3079200Y548573D01*
X3080510Y548864D01*
X3082474Y548281D01*
X3083785Y547115D01*
X3084658Y545073D01*
Y542740D01*
X3084221Y540406D01*
X3083348Y538656D01*
X3081820Y537490D01*
X3080510Y537198D01*
X3079200Y537490D01*
X3077890Y538364D01*
X3076798Y539822D01*
G01X3098228Y537198D02*
X3096918Y537490D01*
X3095608Y538656D01*
X3094734Y540698D01*
X3094298Y543031D01*
X3094734Y545365D01*
X3095608Y547406D01*
X3096918Y548573D01*
X3098228Y548864D01*
X3099538Y548573D01*
X3100848Y547406D01*
X3101721Y545365D01*
X3101940Y543031D01*
X3101721Y540698D01*
X3100848Y538656D01*
X3099538Y537490D01*
X3098228Y537198D01*
G01X3119658D02*
Y548864D01*
G01Y546823D02*
X3118785Y547989D01*
X3117474Y548573D01*
X3115946Y548864D01*
X3114418Y548281D01*
X3113108Y547115D01*
X3112234Y545365D01*
X3111798Y543031D01*
X3112234Y540698D01*
X3113108Y538948D01*
X3114418Y537781D01*
X3115946Y537198D01*
X3117474Y537490D01*
X3118785Y538364D01*
X3119658Y539531D01*
G01X3130171Y537198D02*
Y548864D01*
G01Y546531D02*
X3131263Y547698D01*
X3132355Y548573D01*
X3133883Y548864D01*
X3134974Y548573D01*
X3136285Y547698D01*
G01X3154658Y554698D02*
Y537198D01*
G01Y539822D02*
X3153785Y538364D01*
X3152474Y537490D01*
X3150946Y537198D01*
X3149200Y537781D01*
X3147890Y539239D01*
X3147016Y540989D01*
X3146798Y543031D01*
X3147016Y545073D01*
X3147890Y546823D01*
X3149200Y548281D01*
X3150946Y548864D01*
X3152474Y548573D01*
X3153566Y547989D01*
X3154658Y546823D01*
G01X3185728Y537198D02*
X3184418Y537490D01*
X3183108Y538656D01*
X3182234Y540698D01*
X3181798Y543031D01*
X3182234Y545365D01*
X3183108Y547406D01*
X3184418Y548573D01*
X3185728Y548864D01*
X3187038Y548573D01*
X3188348Y547406D01*
X3189221Y545365D01*
X3189440Y543031D01*
X3189221Y540698D01*
X3188348Y538656D01*
X3187038Y537490D01*
X3185728Y537198D01*
G01X3199516Y548864D02*
Y540698D01*
X3200390Y538656D01*
X3201700Y537490D01*
X3203228Y537198D01*
X3204756Y537490D01*
X3206066Y538656D01*
X3206940Y540698D01*
G01Y537198D02*
Y548864D01*
G01X3220728Y554698D02*
Y537198D01*
G01X3217671Y548864D02*
X3223785D01*
G01X3238228Y537198D02*
Y554698D01*
G01X3255728Y548864D02*
Y537198D01*
G01Y553531D02*
X3255291Y553823D01*
Y554406D01*
X3255728Y554698D01*
X3256165Y554406D01*
Y553823D01*
X3255728Y553531D01*
G01X3269516Y537198D02*
Y548864D01*
G01Y545948D02*
X3270390Y547406D01*
X3271700Y548573D01*
X3273446Y548864D01*
X3274974Y548573D01*
X3276285Y547406D01*
X3276940Y545365D01*
Y537198D01*
G01X3287453Y545073D02*
X3294440D01*
X3293785Y547115D01*
X3292693Y548281D01*
X3291165Y548864D01*
X3289636Y548573D01*
X3288326Y547698D01*
X3287453Y545656D01*
X3287016Y543906D01*
Y542156D01*
X3287453Y540406D01*
X3288545Y538656D01*
X3289855Y537490D01*
X3291383Y537198D01*
X3292911Y537781D01*
X3294440Y539531D01*
G01X3308228Y536615D02*
X3307791Y536906D01*
Y537490D01*
X3308228Y537781D01*
X3308665Y537490D01*
Y536906D01*
X3308228Y536615D01*
G01X2958228Y583514D02*
Y571848D01*
G01Y588181D02*
X2957791Y588473D01*
Y589056D01*
X2958228Y589348D01*
X2958665Y589056D01*
Y588473D01*
X2958228Y588181D01*
G01X2972453Y573889D02*
X2973545Y572723D01*
X2975073Y571848D01*
X2976383D01*
X2977693Y572431D01*
X2978566Y573306D01*
X2979003Y574472D01*
X2978785Y576223D01*
X2977911Y577098D01*
X2973981Y578848D01*
X2973108Y580890D01*
X2973545Y582348D01*
X2974418Y583223D01*
X2975728Y583514D01*
X2977038Y583223D01*
X2978348Y582348D01*
G01X3005706Y571848D02*
Y589348D01*
X3015750Y571848D01*
Y589348D01*
G01X3028228Y571848D02*
X3026481Y572140D01*
X3024953Y573306D01*
X3023643Y575056D01*
X3022769Y577098D01*
X3022333Y579431D01*
Y581765D01*
X3022769Y584098D01*
X3023643Y586140D01*
X3024953Y587889D01*
X3026481Y589056D01*
X3028228Y589348D01*
X3029974Y589056D01*
X3031503Y587889D01*
X3032813Y586140D01*
X3033687Y584098D01*
X3034123Y581765D01*
Y579431D01*
X3033687Y577098D01*
X3032813Y575056D01*
X3031503Y573306D01*
X3029974Y572140D01*
X3028228Y571848D01*
G01X3045728Y589348D02*
Y571848D01*
G01X3040706Y589348D02*
X3050750D01*
G01X3077016Y583514D02*
Y575348D01*
X3077890Y573306D01*
X3079200Y572140D01*
X3080728Y571848D01*
X3082256Y572140D01*
X3083566Y573306D01*
X3084440Y575348D01*
G01Y571848D02*
Y583514D01*
G01X3094953Y573889D02*
X3096045Y572723D01*
X3097573Y571848D01*
X3098883D01*
X3100193Y572431D01*
X3101066Y573306D01*
X3101503Y574472D01*
X3101285Y576223D01*
X3100411Y577098D01*
X3096481Y578848D01*
X3095608Y580890D01*
X3096045Y582348D01*
X3096918Y583223D01*
X3098228Y583514D01*
X3099538Y583223D01*
X3100848Y582348D01*
G01X3112453Y579723D02*
X3119440D01*
X3118785Y581765D01*
X3117693Y582931D01*
X3116165Y583514D01*
X3114636Y583223D01*
X3113326Y582348D01*
X3112453Y580306D01*
X3112016Y578556D01*
Y576806D01*
X3112453Y575056D01*
X3113545Y573306D01*
X3114855Y572140D01*
X3116383Y571848D01*
X3117911Y572431D01*
X3119440Y574181D01*
G01X3137158Y589348D02*
Y571848D01*
G01Y574472D02*
X3136285Y573014D01*
X3134974Y572140D01*
X3133446Y571848D01*
X3131700Y572431D01*
X3130390Y573889D01*
X3129516Y575639D01*
X3129298Y577681D01*
X3129516Y579723D01*
X3130390Y581473D01*
X3131700Y582931D01*
X3133446Y583514D01*
X3134974Y583223D01*
X3136066Y582639D01*
X3137158Y581473D01*
G01X3168228Y583514D02*
Y571848D01*
G01Y588181D02*
X3167791Y588473D01*
Y589056D01*
X3168228Y589348D01*
X3168665Y589056D01*
Y588473D01*
X3168228Y588181D01*
G01X3182016Y571848D02*
Y583514D01*
G01Y580598D02*
X3182890Y582056D01*
X3184200Y583223D01*
X3185946Y583514D01*
X3187474Y583223D01*
X3188785Y582056D01*
X3189440Y580015D01*
Y571848D01*
G01X3220728Y589348D02*
Y571848D01*
G01X3217671Y583514D02*
X3223785D01*
G01X3234516Y571848D02*
Y589348D01*
G01Y580890D02*
X3235608Y582348D01*
X3236700Y583223D01*
X3238446Y583514D01*
X3239756Y583223D01*
X3241285Y582056D01*
X3241940Y580306D01*
Y571848D01*
G01X3255728Y583514D02*
Y571848D01*
G01Y588181D02*
X3255291Y588473D01*
Y589056D01*
X3255728Y589348D01*
X3256165Y589056D01*
Y588473D01*
X3255728Y588181D01*
G01X3269953Y573889D02*
X3271045Y572723D01*
X3272573Y571848D01*
X3273883D01*
X3275193Y572431D01*
X3276066Y573306D01*
X3276503Y574472D01*
X3276285Y576223D01*
X3275411Y577098D01*
X3271481Y578848D01*
X3270608Y580890D01*
X3271045Y582348D01*
X3271918Y583223D01*
X3273228Y583514D01*
X3274538Y583223D01*
X3275848Y582348D01*
G01X3308228Y571848D02*
Y589348D01*
G01X3329658Y571848D02*
Y583514D01*
G01Y581473D02*
X3328785Y582639D01*
X3327474Y583223D01*
X3325946Y583514D01*
X3324418Y582931D01*
X3323108Y581765D01*
X3322234Y580015D01*
X3321798Y577681D01*
X3322234Y575348D01*
X3323108Y573598D01*
X3324418Y572431D01*
X3325946Y571848D01*
X3327474Y572140D01*
X3328785Y573014D01*
X3329658Y574181D01*
G01X3338643Y566598D02*
X3339953Y566015D01*
X3341700Y566598D01*
X3342791Y567764D01*
X3343665Y569223D01*
X3344974Y573889D01*
X3347813Y583514D01*
G01X3340826D02*
X3344974Y573889D01*
G01X3357453Y579723D02*
X3364440D01*
X3363785Y581765D01*
X3362693Y582931D01*
X3361165Y583514D01*
X3359636Y583223D01*
X3358326Y582348D01*
X3357453Y580306D01*
X3357016Y578556D01*
Y576806D01*
X3357453Y575056D01*
X3358545Y573306D01*
X3359855Y572140D01*
X3361383Y571848D01*
X3362911Y572431D01*
X3364440Y574181D01*
G01X3375171Y571848D02*
Y583514D01*
G01Y581181D02*
X3376263Y582348D01*
X3377355Y583223D01*
X3378883Y583514D01*
X3379974Y583223D01*
X3381285Y582348D01*
G01X2883425Y605915D02*
X2893031Y618748D01*
G01X2888228Y621081D02*
Y603581D01*
G01X2893031Y605915D02*
X2883425Y618748D01*
G01X2881678Y612331D02*
X2894778D01*
G01X2920390D02*
X2926066D01*
G01X2953425Y606498D02*
Y623998D01*
X2957791D01*
X2959538Y623123D01*
X2960848Y621956D01*
X2961940Y620207D01*
X2962813Y618164D01*
X2963031Y615248D01*
X2962813Y612331D01*
X2961940Y610289D01*
X2960848Y608539D01*
X2959538Y607373D01*
X2957791Y606498D01*
X2953425D01*
G01X2972453Y614373D02*
X2979440D01*
X2978785Y616415D01*
X2977693Y617581D01*
X2976165Y618164D01*
X2974636Y617873D01*
X2973326Y616998D01*
X2972453Y614956D01*
X2972016Y613206D01*
Y611456D01*
X2972453Y609706D01*
X2973545Y607956D01*
X2974855Y606790D01*
X2976383Y606498D01*
X2977911Y607081D01*
X2979440Y608831D01*
G01X2989516Y606498D02*
Y618164D01*
G01Y615248D02*
X2990390Y616706D01*
X2991700Y617873D01*
X2993446Y618164D01*
X2994974Y617873D01*
X2996285Y616706D01*
X2996940Y614665D01*
Y606498D01*
G01X3010728D02*
X3009418Y606790D01*
X3008108Y607956D01*
X3007234Y609998D01*
X3006798Y612331D01*
X3007234Y614665D01*
X3008108Y616706D01*
X3009418Y617873D01*
X3010728Y618164D01*
X3012038Y617873D01*
X3013348Y616706D01*
X3014221Y614665D01*
X3014440Y612331D01*
X3014221Y609998D01*
X3013348Y607956D01*
X3012038Y606790D01*
X3010728Y606498D01*
G01X3028228Y623998D02*
Y606498D01*
G01X3025171Y618164D02*
X3031285D01*
G01X3042453Y614373D02*
X3049440D01*
X3048785Y616415D01*
X3047693Y617581D01*
X3046165Y618164D01*
X3044636Y617873D01*
X3043326Y616998D01*
X3042453Y614956D01*
X3042016Y613206D01*
Y611456D01*
X3042453Y609706D01*
X3043545Y607956D01*
X3044855Y606790D01*
X3046383Y606498D01*
X3047911Y607081D01*
X3049440Y608831D01*
G01X3059953Y608539D02*
X3061045Y607373D01*
X3062573Y606498D01*
X3063883D01*
X3065193Y607081D01*
X3066066Y607956D01*
X3066503Y609122D01*
X3066285Y610873D01*
X3065411Y611748D01*
X3061481Y613498D01*
X3060608Y615540D01*
X3061045Y616998D01*
X3061918Y617873D01*
X3063228Y618164D01*
X3064538Y617873D01*
X3065848Y616998D01*
G01X3098228Y623998D02*
Y606498D01*
G01X3095171Y618164D02*
X3101285D01*
G01X3112016Y606498D02*
Y623998D01*
G01Y615540D02*
X3113108Y616998D01*
X3114200Y617873D01*
X3115946Y618164D01*
X3117256Y617873D01*
X3118785Y616706D01*
X3119440Y614956D01*
Y606498D01*
G01X3137158D02*
Y618164D01*
G01Y616123D02*
X3136285Y617289D01*
X3134974Y617873D01*
X3133446Y618164D01*
X3131918Y617581D01*
X3130608Y616415D01*
X3129734Y614665D01*
X3129298Y612331D01*
X3129734Y609998D01*
X3130608Y608248D01*
X3131918Y607081D01*
X3133446Y606498D01*
X3134974Y606790D01*
X3136285Y607664D01*
X3137158Y608831D01*
G01X3150728Y623998D02*
Y606498D01*
G01X3147671Y618164D02*
X3153785D01*
G01X3179178Y623998D02*
X3182234Y606498D01*
X3185728Y623998D01*
X3189221Y606498D01*
X3192278Y623998D01*
G01X3200608D02*
X3205848D01*
G01X3203228D02*
Y606498D01*
G01X3200608D02*
X3205848D01*
G01X3215925D02*
Y623998D01*
X3220291D01*
X3222038Y623123D01*
X3223348Y621956D01*
X3224440Y620207D01*
X3225313Y618164D01*
X3225531Y615248D01*
X3225313Y612331D01*
X3224440Y610289D01*
X3223348Y608539D01*
X3222038Y607373D01*
X3220291Y606498D01*
X3215925D01*
G01X3238228Y623998D02*
Y606498D01*
G01X3233206Y623998D02*
X3243250D01*
G01X3251143Y606498D02*
Y623998D01*
G01X3260313D02*
Y606498D01*
G01Y615248D02*
X3251143D01*
G01X-7874Y-31496D02*
X-19685D01*
G01X-7874D02*
X-19685D01*
G01D02*
G03X-23622Y-35433I0J-3937D01*
G01D02*
Y-59055D01*
G01Y-35433D02*
Y-59055D01*
G01X-19685Y-31496D02*
G03X-23622Y-35433I0J-3937D01*
G01Y-59055D02*
G03X-19685Y-62992I3937J0D01*
G01D02*
X1972441D01*
G01X-19685D02*
X1972441D01*
G01X-23622Y-59055D02*
G03X-19685Y-62992I3937J0D01*
G01Y-23622D02*
X1972441D01*
G01X-19685D02*
X1972441D01*
G01X-19685D02*
X1972441D01*
G01X-19685D02*
X1972441D01*
G01X-23622Y622441D02*
Y-19685D01*
G01Y622441D02*
Y-19685D01*
G01Y622441D02*
Y-19685D01*
G01Y622441D02*
Y-19685D01*
G01D02*
G03X-19685Y-23622I3937J0D01*
G01X-23622Y-19685D02*
G03X-19685Y-23622I3937J0D01*
G01X-23622Y-19685D02*
G03X-19685Y-23622I3937J0D01*
G01X-23622Y-19685D02*
G03X-19685Y-23622I3937J0D01*
G01X1972441Y626378D02*
X-19685D01*
G01X1972441D02*
X-19685D01*
G01X1972441D02*
X-19685D01*
G01X1972441D02*
X-19685D01*
G01D02*
G03X-23622Y622441I0J-3937D01*
G01X-19685Y626378D02*
G03X-23622Y622441I0J-3937D01*
G01X-19685Y626378D02*
G03X-23622Y622441I0J-3937D01*
G01X-19685Y626378D02*
G03X-23622Y622441I0J-3937D01*
G01X-19685Y634252D02*
X-7874D01*
G01X-19685D02*
X-7874D01*
G01X-23622Y661811D02*
Y638189D01*
G01Y661811D02*
Y638189D01*
G01D02*
G03X-19685Y634252I3937J0D01*
G01X-23622Y638189D02*
G03X-19685Y634252I3937J0D01*
G01X1972441Y665748D02*
X-19685D01*
G01X1972441D02*
X-19685D01*
G01D02*
G03X-23622Y661811I0J-3937D01*
G01X-19685Y665748D02*
G03X-23622Y661811I0J-3937D01*
G01X-7874Y-31496D02*
G03Y-23622I0J3937D01*
G01Y-31496D02*
G03Y-23622I0J3937D01*
G01X22835D02*
G03Y-31496I0J-3937D01*
G01X137795D02*
X22835D01*
G01X137795D02*
X22835D01*
G01Y-23622D02*
G03Y-31496I0J-3937D01*
G01X0Y616535D02*
G03Y604724I0J-5905D01*
G01Y616535D02*
G03Y604724I0J-5905D01*
G01Y616535D02*
X2646D01*
G01X2644D02*
X0D01*
G01Y604724D02*
X2644D01*
G01X2646D02*
X0D01*
G01X2646D02*
X0D01*
G01D02*
X2644D01*
G01Y616535D02*
X0D01*
G01D02*
X2646D01*
G01X0D02*
G03Y604724I0J-5905D01*
G01Y616535D02*
G03Y604724I0J-5905D01*
G01X2646Y616535D02*
G03X7595Y618285I0J7874D01*
G01X2644Y616535D02*
G03X7593Y618285I0J7874D01*
G01X2644Y616535D02*
G03X7593Y618285I0J7874D01*
G01X7595Y602975D02*
G03X2646Y604724I-4948J-6125D01*
G01X7593Y602975D02*
G03X2644Y604724I-4948J-6125D01*
G01X7593Y602975D02*
G03X2644Y604724I-4948J-6125D01*
G01X7593Y602975D02*
G03X2644Y604724I-4948J-6125D01*
G01X7593Y602975D02*
G03X2644Y604724I-4948J-6125D01*
G01X7595Y602975D02*
G03X2646Y604724I-4948J-6125D01*
G01X2644Y616535D02*
G03X7593Y618285I0J7874D01*
G01X2644Y616535D02*
G03X7593Y618285I0J7874D01*
G01X2646Y616535D02*
G03X7595Y618285I0J7874D01*
G01Y602975D02*
G03Y618285I6186J7655D01*
G01X7593Y602975D02*
G03Y618285I6187J7655D01*
G01Y602975D02*
G03Y618285I6187J7655D01*
G01Y602975D02*
G03Y618285I6187J7655D01*
G01Y602975D02*
G03Y618285I6187J7655D01*
G01X7595Y602975D02*
G03Y618285I6186J7655D01*
G01X-7874Y626378D02*
G03Y634252I0J3937D01*
G01Y626378D02*
G03Y634252I0J3937D01*
G01X22835D02*
G03Y626378I0J-3937D01*
G01Y634252D02*
X137795D01*
G01X22835D02*
X137795D01*
G01X22835D02*
G03Y626378I0J-3937D01*
G01X168504Y-23622D02*
G03Y-31496I0J-3937D01*
G01X137795D02*
G03Y-23622I0J3937D01*
G01X341732Y-31496D02*
X168504D01*
G01X341732D02*
X168504D01*
G01X137795D02*
G03Y-23622I0J3937D01*
G01X168504D02*
G03Y-31496I0J-3937D01*
G01Y634252D02*
G03Y626378I0J-3937D01*
G01X137795D02*
G03Y634252I0J3937D01*
G01X168504D02*
X341732D01*
G01X168504D02*
X341732D01*
G01X137795Y626378D02*
G03Y634252I0J3937D01*
G01X168504D02*
G03Y626378I0J-3937D01*
G01X341732Y-31496D02*
G03Y-23622I0J3937D01*
G01Y-31496D02*
G03Y-23622I0J3937D01*
G01Y626378D02*
G03Y634252I0J3937D01*
G01Y626378D02*
G03Y634252I0J3937D01*
G01X372441Y-23622D02*
G03Y-31496I0J-3937D01*
G01X529921D02*
X372441D01*
G01X529921D02*
X372441D01*
G01Y-23622D02*
G03Y-31496I0J-3937D01*
G01Y634252D02*
G03Y626378I0J-3937D01*
G01Y634252D02*
X529921D01*
G01X372441D02*
X529921D01*
G01X372441D02*
G03Y626378I0J-3937D01*
G01X529921Y-31496D02*
G03Y-23622I0J3937D01*
G01Y-31496D02*
G03Y-23622I0J3937D01*
G01Y626378D02*
G03Y634252I0J3937D01*
G01Y626378D02*
G03Y634252I0J3937D01*
G01X560630Y-23622D02*
G03Y-31496I0J-3937D01*
G01X788976D02*
X560630D01*
G01X788976D02*
X560630D01*
G01Y-23622D02*
G03Y-31496I0J-3937D01*
G01Y634252D02*
G03Y626378I0J-3937D01*
G01Y634252D02*
X788976D01*
G01X560630D02*
X788976D01*
G01X560630D02*
G03Y626378I0J-3937D01*
G01X684760Y-15529D02*
G03Y-219I6187J7655D01*
G01X684759Y-15529D02*
G03X679809Y-13780I-4948J-6125D01*
G01X679811Y-1969D02*
G03X684760Y-219I0J7874D01*
G01X677165Y-1969D02*
X679811D01*
G01X677165D02*
G03Y-13780I0J-5906D01*
G01D02*
X679809D01*
G01X684760Y602975D02*
G03Y618285I6187J7655D01*
G01X684759Y602975D02*
G03Y618285I6186J7655D01*
G01Y602975D02*
G03Y618285I6186J7655D01*
G01Y602975D02*
G03Y618285I6186J7655D01*
G01Y602975D02*
G03Y618285I6186J7655D01*
G01X684760Y602975D02*
G03Y618285I6187J7655D01*
G01X679811Y616535D02*
G03X684760Y618285I0J7874D01*
G01X679809Y616535D02*
G03X684759Y618285I0J7874D01*
G01X679809Y616535D02*
G03X684759Y618285I0J7874D01*
G01X684760Y602975D02*
G03X679811Y604724I-4948J-6125D01*
G01X684759Y602975D02*
G03X679809Y604724I-4948J-6125D01*
G01X684759Y602975D02*
G03X679809Y604724I-4948J-6125D01*
G01X684759Y602975D02*
G03X679809Y604724I-4948J-6125D01*
G01X684759Y602975D02*
G03X679809Y604724I-4948J-6125D01*
G01X684760Y602975D02*
G03X679811Y604724I-4948J-6125D01*
G01X679809Y616535D02*
G03X684759Y618285I0J7874D01*
G01X679809Y616535D02*
G03X684759Y618285I0J7874D01*
G01X679811Y616535D02*
G03X684760Y618285I0J7874D01*
G01X677165Y616535D02*
X679811D01*
G01X677165D02*
G03Y604724I0J-5905D01*
G01D02*
X679809D01*
G01X788976Y-31496D02*
G03Y-23622I0J3937D01*
G01Y-31496D02*
G03Y-23622I0J3937D01*
G01X819685D02*
G03Y-31496I0J-3937D01*
G01X975591D02*
X819685D01*
G01X975591D02*
X819685D01*
G01Y-23622D02*
G03Y-31496I0J-3937D01*
G01X788976Y626378D02*
G03Y634252I0J3937D01*
G01Y626378D02*
G03Y634252I0J3937D01*
G01X819685D02*
G03Y626378I0J-3937D01*
G01Y634252D02*
X975591D01*
G01X819685D02*
X975591D01*
G01X819685D02*
G03Y626378I0J-3937D01*
G01X975591Y-31496D02*
G03Y-23622I0J3937D01*
G01Y-31496D02*
G03Y-23622I0J3937D01*
G01X1006299D02*
G03Y-31496I0J-3937D01*
G01X1162205D02*
X1006299D01*
G01X1162205D02*
X1006299D01*
G01Y-23622D02*
G03Y-31496I0J-3937D01*
G01Y634252D02*
X1162205D01*
G01X1006299D02*
X1162205D01*
G01X975591Y626378D02*
G03Y634252I0J3937D01*
G01Y626378D02*
G03Y634252I0J3937D01*
G01X1006299D02*
G03Y626378I0J-3937D01*
G01Y634252D02*
G03Y626378I0J-3937D01*
G01X1162205Y-31496D02*
G03Y-23622I0J3937D01*
G01Y-31496D02*
G03Y-23622I0J3937D01*
G01X1192913D02*
G03Y-31496I0J-3937D01*
G01X1398425D02*
X1192913D01*
G01X1398425D02*
X1192913D01*
G01Y-23622D02*
G03Y-31496I0J-3937D01*
G01Y634252D02*
X1394488D01*
G01X1192913D02*
X1394488D01*
G01X1162205Y626378D02*
G03Y634252I0J3937D01*
G01Y626378D02*
G03Y634252I0J3937D01*
G01X1192913D02*
G03Y626378I0J-3937D01*
G01Y634252D02*
G03Y626378I0J-3937D01*
G01X1398425Y-31496D02*
G03Y-23622I0J3937D01*
G01Y-31496D02*
G03Y-23622I0J3937D01*
G01X1405512Y-1968D02*
G03Y-13779I0J-5906D01*
G01Y-1968D02*
G03Y-13779I0J-5906D01*
G01Y-1968D02*
G03Y-13779I0J-5906D01*
G01Y-1968D02*
G03Y-13779I0J-5906D01*
G01X1394488Y626378D02*
G03Y634252I0J3937D01*
G01Y626378D02*
G03Y634252I0J3937D01*
G01X1405512Y616535D02*
G03Y604724I0J-5905D01*
G01Y616535D02*
G03Y604724I0J-5905D01*
G01Y616535D02*
G03Y604724I0J-5905D01*
G01Y616535D02*
G03Y604724I0J-5905D01*
G01X1429134Y-23622D02*
G03Y-31496I0J-3937D01*
G01X1851181D02*
X1429134D01*
G01X1851181D02*
X1429134D01*
G01Y-23622D02*
G03Y-31496I0J-3937D01*
G01X1413107Y-15529D02*
G03Y-218I6186J7655D01*
G01X1413105Y-15529D02*
G03Y-218I6186J7655D01*
G01Y-15529D02*
G03Y-218I6186J7655D01*
G01Y-15529D02*
G03Y-218I6186J7655D01*
G01Y-15529D02*
G03Y-218I6186J7655D01*
G01X1413107Y-15529D02*
G03Y-218I6186J7655D01*
G01X1408157Y-1968D02*
G03X1413107Y-218I1J7874D01*
G01X1408156Y-1968D02*
G03X1413105Y-218I0J7874D01*
G01X1408156Y-1968D02*
G03X1413105Y-218I0J7874D01*
G01X1408156Y-1968D02*
G03X1413105Y-218I0J7874D01*
G01X1408156Y-1968D02*
G03X1413105Y-218I0J7874D01*
G01X1408157Y-1968D02*
G03X1413107Y-218I1J7874D01*
G01Y-15529D02*
G03X1408157Y-13779I-4949J-6124D01*
G01X1413105Y-15529D02*
G03X1408156Y-13779I-4949J-6124D01*
G01X1413105Y-15529D02*
G03X1408156Y-13779I-4949J-6124D01*
G01X1413105Y-15529D02*
G03X1408156Y-13779I-4949J-6124D01*
G01X1413105Y-15529D02*
G03X1408156Y-13779I-4949J-6124D01*
G01X1413107Y-15529D02*
G03X1408157Y-13779I-4949J-6124D01*
G01X1405512D02*
X1408156D01*
G01X1408157D02*
X1405512D01*
G01X1408157D02*
X1405512D01*
G01D02*
X1408156D01*
G01X1405512Y-1968D02*
X1408157D01*
G01X1408156D02*
X1405512D01*
G01X1408156D02*
X1405512D01*
G01D02*
X1408157D01*
G01X1425197Y634252D02*
X1851181D01*
G01X1425197D02*
X1851181D01*
G01X1425197D02*
G03Y626378I0J-3937D01*
G01Y634252D02*
G03Y626378I0J-3937D01*
G01X1408157Y616535D02*
G03X1413107Y618285I1J7874D01*
G01X1408156Y616535D02*
G03X1413105Y618285I0J7874D01*
G01X1408156Y616535D02*
G03X1413105Y618285I0J7874D01*
G01X1413107Y602975D02*
G03Y618285I6186J7655D01*
G01X1413105Y602975D02*
G03Y618285I6187J7655D01*
G01Y602975D02*
G03Y618285I6187J7655D01*
G01X1413107Y602975D02*
G03X1408157Y604724I-4948J-6125D01*
G01X1413105Y602975D02*
G03X1408156Y604724I-4948J-6125D01*
G01X1413105Y602975D02*
G03X1408156Y604724I-4948J-6125D01*
G01X1413105Y602975D02*
G03X1408156Y604724I-4948J-6125D01*
G01X1413105Y602975D02*
G03X1408156Y604724I-4948J-6125D01*
G01X1413107Y602975D02*
G03X1408157Y604724I-4948J-6125D01*
G01X1413105Y602975D02*
G03Y618285I6187J7655D01*
G01Y602975D02*
G03Y618285I6187J7655D01*
G01X1413107Y602975D02*
G03Y618285I6186J7655D01*
G01X1408156Y616535D02*
G03X1413105Y618285I0J7874D01*
G01X1408156Y616535D02*
G03X1413105Y618285I0J7874D01*
G01X1408157Y616535D02*
G03X1413107Y618285I1J7874D01*
G01X1405512Y616535D02*
X1408157D01*
G01X1408156D02*
X1405512D01*
G01Y604724D02*
X1408156D01*
G01X1408157D02*
X1405512D01*
G01X1408157D02*
X1405512D01*
G01D02*
X1408156D01*
G01Y616535D02*
X1405512D01*
G01D02*
X1408157D01*
G01X1685866Y267244D02*
X1883780D01*
G01X1685866D02*
X1883780D01*
G01X1685866D02*
X1883780D01*
G01X1685866D02*
X1883780D01*
G01X1681929Y271181D02*
G03X1685866Y267244I3937J0D01*
G01X1681929Y271181D02*
G03X1685866Y267244I3937J0D01*
G01X1681929Y271181D02*
G03X1685866Y267244I3937J0D01*
G01X1681929Y271181D02*
G03X1685866Y267244I3937J0D01*
G01X1681929Y428661D02*
Y271181D01*
G01Y428661D02*
Y271181D01*
G01Y428661D02*
Y271181D01*
G01Y428661D02*
Y271181D01*
G01X1685866Y432598D02*
G03X1681929Y428661I0J-3937D01*
G01X1685866Y432598D02*
G03X1681929Y428661I0J-3937D01*
G01X1972441Y432598D02*
X1685866D01*
G01X1972441D02*
X1685866D01*
G01X1972441D02*
X1685866D01*
G01X1972441D02*
X1685866D01*
G01D02*
G03X1681929Y428661I0J-3937D01*
G01X1685866Y432598D02*
G03X1681929Y428661I0J-3937D01*
G01X1851181Y-31496D02*
G03Y-23622I0J3937D01*
G01Y-31496D02*
G03Y-23622I0J3937D01*
G01X1881890D02*
G03Y-31496I0J-3937D01*
G01X1972441D02*
X1881890D01*
G01X1972441D02*
X1881890D01*
G01Y-23622D02*
G03Y-31496I0J-3937D01*
G01X1861926Y-15529D02*
G03X1856976Y-13780I-4948J-6125D01*
G01X1861924Y-15529D02*
G03X1856975Y-13780I-4948J-6125D01*
G01X1861924Y-15529D02*
G03X1856975Y-13780I-4948J-6125D01*
G01X1861924Y-15529D02*
G03X1856975Y-13780I-4948J-6125D01*
G01X1861924Y-15529D02*
G03X1856975Y-13780I-4948J-6125D01*
G01X1861926Y-15529D02*
G03X1856976Y-13780I-4948J-6125D01*
G01Y-1969D02*
G03X1861926Y-219I0J7874D01*
G01X1856975Y-1969D02*
G03X1861924Y-219I0J7874D01*
G01X1856975Y-1969D02*
G03X1861924Y-219I0J7874D01*
G01X1861926Y-15529D02*
G03Y-219I6186J7655D01*
G01X1861924Y-15529D02*
G03Y-219I6186J7655D01*
G01Y-15529D02*
G03Y-219I6186J7655D01*
G01Y-15529D02*
G03Y-219I6186J7655D01*
G01Y-15529D02*
G03Y-219I6186J7655D01*
G01X1861926Y-15529D02*
G03Y-219I6186J7655D01*
G01X1856975Y-1969D02*
G03X1861924Y-219I0J7874D01*
G01X1856975Y-1969D02*
G03X1861924Y-219I0J7874D01*
G01X1856976Y-1969D02*
G03X1861926Y-219I0J7874D01*
G01X1854331Y-1969D02*
G03Y-13780I0J-5906D01*
G01Y-1969D02*
G03Y-13780I0J-5906D01*
G01D02*
X1856975D01*
G01X1856976D02*
X1854331D01*
G01X1856976D02*
X1854331D01*
G01D02*
X1856975D01*
G01X1854331Y-1969D02*
G03Y-13780I0J-5906D01*
G01Y-1969D02*
G03Y-13780I0J-5906D01*
G01Y-1969D02*
X1856976D01*
G01X1856975D02*
X1854331D01*
G01X1856975D02*
X1854331D01*
G01D02*
X1856976D01*
G01X1891654Y246772D02*
X1972441D01*
G01X1891654D02*
X1972441D01*
G01X1891654D02*
X1972441D01*
G01X1891654D02*
X1972441D01*
G01X1887717Y250709D02*
G03X1891654Y246772I3937J0D01*
G01X1887717Y250709D02*
G03X1891654Y246772I3937J0D01*
G01X1887717Y263307D02*
Y250709D01*
G01Y263307D02*
Y250709D01*
G01Y263307D02*
Y250709D01*
G01Y263307D02*
Y250709D01*
G01D02*
G03X1891654Y246772I3937J0D01*
G01X1887717Y250709D02*
G03X1891654Y246772I3937J0D01*
G01X1887717Y263307D02*
G03X1883780Y267244I-3937J0D01*
G01X1887717Y263307D02*
G03X1883780Y267244I-3937J0D01*
G01X1887717Y263307D02*
G03X1883780Y267244I-3937J0D01*
G01X1887717Y263307D02*
G03X1883780Y267244I-3937J0D01*
G01X1881890Y634252D02*
G03Y626378I0J-3937D01*
G01Y634252D02*
X1972441D01*
G01X1881890D02*
X1972441D01*
G01X1881890D02*
G03Y626378I0J-3937D01*
G01X1851181D02*
G03Y634252I0J3937D01*
G01Y626378D02*
G03Y634252I0J3937D01*
G01X1856976Y616535D02*
G03X1861926Y618285I0J7874D01*
G01X1856975Y616535D02*
G03X1861924Y618285I0J7874D01*
G01X1856975Y616535D02*
G03X1861924Y618285I0J7874D01*
G01X1861926Y602975D02*
G03Y618285I6186J7655D01*
G01X1861924Y602975D02*
G03Y618285I6186J7655D01*
G01Y602975D02*
G03Y618285I6186J7655D01*
G01Y602975D02*
G03Y618285I6186J7655D01*
G01Y602975D02*
G03Y618285I6186J7655D01*
G01X1861926Y602975D02*
G03Y618285I6186J7655D01*
G01X1856975Y616535D02*
G03X1861924Y618285I0J7874D01*
G01X1856975Y616535D02*
G03X1861924Y618285I0J7874D01*
G01X1856976Y616535D02*
G03X1861926Y618285I0J7874D01*
G01Y602975D02*
G03X1856976Y604724I-4948J-6125D01*
G01X1861924Y602975D02*
G03X1856975Y604724I-4948J-6125D01*
G01X1861924Y602975D02*
G03X1856975Y604724I-4948J-6125D01*
G01X1861924Y602975D02*
G03X1856975Y604724I-4948J-6125D01*
G01X1861924Y602975D02*
G03X1856975Y604724I-4948J-6125D01*
G01X1861926Y602975D02*
G03X1856976Y604724I-4948J-6125D01*
G01X1854331Y616535D02*
G03Y604724I0J-5905D01*
G01Y616535D02*
G03Y604724I0J-5905D01*
G01D02*
X1856975D01*
G01X1856976D02*
X1854331D01*
G01X1856976D02*
X1854331D01*
G01D02*
X1856975D01*
G01X1854331Y616535D02*
G03Y604724I0J-5905D01*
G01Y616535D02*
G03Y604724I0J-5905D01*
G01Y616535D02*
X1856976D01*
G01X1856975D02*
X1854331D01*
G01X1856975D02*
X1854331D01*
G01D02*
X1856976D01*
G01X1972441Y-11811D02*
X1906890D01*
G01X1904921Y-9843D02*
G03X1906890Y-11811I1969J1D01*
G01X1904921Y53150D02*
Y-9843D01*
G01X1972441Y-11811D02*
X1906890D01*
G01X1904921Y-9843D02*
G03X1906890Y-11811I1969J1D01*
G01X1904921Y53150D02*
Y-9843D01*
G01X1923071Y53150D02*
Y-9843D01*
G01X1940787Y-3937D02*
X1972441D01*
G01X1940787D02*
G03X1938819Y-5906I0J-1968D01*
G01Y-9843D02*
Y-5906D01*
G01Y-9843D02*
G03X1940787Y-11811I1968J0D01*
G01X1921102D02*
G03X1923071Y-9843I0J1969D01*
G01X1906890Y55118D02*
G03X1904921Y53150I0J-1969D01*
G01X1972441Y55118D02*
X1906890D01*
G01X1972441D02*
X1906890D01*
G01X1972441D02*
X1906890D01*
G01X1972441D02*
X1906890D01*
G01D02*
G03X1904921Y53150I0J-1969D01*
G01X1923071D02*
G03X1921102Y55118I-1969J-1D01*
G01X1940787D02*
G03X1938819Y53150I0J-1968D01*
G01Y49213D02*
Y53150D01*
G01Y49213D02*
G03X1940787Y47244I1968J-1D01*
G01X1972441D02*
X1940787D01*
G01X1976378Y-35433D02*
G03X1972441Y-31496I-3937J0D01*
G01X1976378Y-59055D02*
Y-35433D01*
G01Y-59055D02*
Y-35433D01*
G01D02*
G03X1972441Y-31496I-3937J0D01*
G01Y-62992D02*
G03X1976378Y-59055I0J3937D01*
G01X1972441Y-62992D02*
G03X1976378Y-59055I0J3937D01*
G01X1972441Y-23622D02*
G03X1976378Y-19685I0J3937D01*
G01X1972441Y-23622D02*
G03X1976378Y-19685I0J3937D01*
G01X1972441Y-23622D02*
G03X1976378Y-19685I0J3937D01*
G01X1972441Y-23622D02*
G03X1976378Y-19685I0J3937D01*
G01D02*
Y-15748D01*
G01Y-19685D02*
Y-15748D01*
G01Y-19685D02*
Y-15748D01*
G01Y-19685D02*
Y-15748D01*
G01D02*
G03X1972441Y-11811I-3937J0D01*
G01X1976378Y-15748D02*
G03X1972441Y-11811I-3937J0D01*
G01X1976378Y-15748D02*
G03X1972441Y-11811I-3937J0D01*
G01X1976378Y-15748D02*
G03X1972441Y-11811I-3937J0D01*
G01X1976378Y0D02*
Y43307D01*
G01X1972441Y-3937D02*
G03X1976378Y0I0J3937D01*
G01X1972441Y55118D02*
G03X1976378Y59055I0J3937D01*
G01X1972441Y55118D02*
G03X1976378Y59055I0J3937D01*
G01X1972441Y55118D02*
G03X1976378Y59055I0J3937D01*
G01X1972441Y55118D02*
G03X1976378Y59055I0J3937D01*
G01D02*
Y242835D01*
G01Y59055D02*
Y242835D01*
G01Y59055D02*
Y242835D01*
G01Y59055D02*
Y242835D01*
G01Y43307D02*
G03X1972441Y47244I-3937J0D01*
G01X1976378Y242835D02*
G03X1972441Y246772I-3937J0D01*
G01X1976378Y242835D02*
G03X1972441Y246772I-3937J0D01*
G01X1976378Y242835D02*
G03X1972441Y246772I-3937J0D01*
G01X1976378Y242835D02*
G03X1972441Y246772I-3937J0D01*
G01Y432598D02*
G03X1976378Y436535I0J3937D01*
G01X1972441Y432598D02*
G03X1976378Y436535I0J3937D01*
G01X1972441Y432598D02*
G03X1976378Y436535I0J3937D01*
G01X1972441Y432598D02*
G03X1976378Y436535I0J3937D01*
G01D02*
Y622441D01*
G01Y436535D02*
Y622441D01*
G01Y436535D02*
Y622441D01*
G01Y436535D02*
Y622441D01*
G01D02*
G03X1972441Y626378I-3937J0D01*
G01X1976378Y622441D02*
G03X1972441Y626378I-3937J0D01*
G01X1976378Y622441D02*
G03X1972441Y626378I-3937J0D01*
G01X1976378Y622441D02*
G03X1972441Y626378I-3937J0D01*
G01Y634252D02*
G03X1976378Y638189I0J3937D01*
G01X1972441Y634252D02*
G03X1976378Y638189I0J3937D01*
G01D02*
Y661811D01*
G01Y638189D02*
Y661811D01*
G01D02*
G03X1972441Y665748I-3937J0D01*
G01X1976378Y661811D02*
G03X1972441Y665748I-3937J0D01*
G54D12*
G01X261585Y649219D02*
X262431D01*
G01D02*
X263497Y650029D01*
G01X268202Y654128D02*
X266718Y645722D01*
G01X266986Y653859D02*
X265502Y645452D01*
G01X266718Y645722D02*
X267085Y645198D01*
G01X265502Y645452D02*
X266415Y644148D01*
G01X267085Y645198D02*
X268119Y645015D01*
G01X266415Y644148D02*
X268388Y643799D01*
G01X267085Y645198D02*
X268119Y645015D01*
G01D02*
X268638Y645378D01*
G01X268388Y643799D02*
X269688Y644709D01*
G01X268638Y645378D02*
X270322Y654928D01*
G01X269688Y644709D02*
X271373Y654259D01*
G01X274509Y654189D02*
X273017Y645736D01*
G01X273293Y653921D02*
X271801Y645467D01*
G01X273017Y645736D02*
X273381Y645215D01*
G01X271801Y645467D02*
X272711Y644164D01*
G01X273381Y645215D02*
X274416Y645033D01*
G01X272711Y644164D02*
X274685Y643818D01*
G01X273381Y645215D02*
X274416Y645033D01*
G01D02*
X274939Y645398D01*
G01X274685Y643818D02*
X275989Y644728D01*
G01X274939Y645398D02*
X276617Y654932D01*
G01X275989Y644728D02*
X277668Y654262D01*
G01X280804Y654193D02*
X279313Y645737D01*
G01X279588Y653924D02*
X278097Y645468D01*
G01X279313Y645737D02*
X279677Y645216D01*
G01X278097Y645468D02*
X279007Y644165D01*
G01X279677Y645216D02*
X280711Y645034D01*
G01X279007Y644165D02*
X280981Y643819D01*
G01X279677Y645216D02*
X280711Y645034D01*
G01D02*
X281234Y645399D01*
G01X280981Y643819D02*
X282285Y644729D01*
G01X281234Y645399D02*
X282917Y654951D01*
G01X282285Y644729D02*
X283967Y654281D01*
G01X287104Y654215D02*
X285604Y645704D01*
G01X285888Y653944D02*
X284388Y645435D01*
G01X285604Y645704D02*
X285968Y645183D01*
G01X284388Y645435D02*
X285298Y644132D01*
G01X285968Y645183D02*
X287002Y645001D01*
G01X285298Y644132D02*
X287272Y643785D01*
G01X285968Y645183D02*
X287002Y645001D01*
G01D02*
X287522Y645365D01*
G01X287272Y643785D02*
X288572Y644696D01*
G01X287522Y645365D02*
X289212Y654946D01*
G01X288572Y644696D02*
X290263Y654278D01*
G01X293401Y654212D02*
X291901Y645705D01*
G01X292185Y653942D02*
X290685Y645434D01*
G01X291901Y645705D02*
X292264Y645183D01*
G01X290685Y645434D02*
X291594Y644133D01*
G01X292264Y645183D02*
X293298Y645000D01*
G01X291594Y644133D02*
X293567Y643785D01*
G01X292264Y645183D02*
X293298Y645000D01*
G01X261585Y649219D02*
X262431D01*
G01D02*
X263497Y650029D01*
G01X262431Y649219D02*
X263497Y650029D01*
G01X266986Y653859D02*
X265502Y645452D01*
G01X268202Y654128D02*
X266718Y645722D01*
G01X265502Y645452D02*
X266415Y644148D01*
G01X266718Y645722D02*
X267085Y645198D01*
G01X266415Y644148D02*
X268388Y643799D01*
G01D02*
X269688Y644709D01*
G01X267085Y645198D02*
X268119Y645015D01*
G01X268388Y643799D02*
X269688Y644709D01*
G01X268119Y645015D02*
X268638Y645378D01*
G01X269688Y644709D02*
X271373Y654259D01*
G01X268638Y645378D02*
X270322Y654928D01*
G01X273293Y653921D02*
X271801Y645467D01*
G01X274509Y654189D02*
X273017Y645736D01*
G01X271801Y645467D02*
X272711Y644164D01*
G01X273017Y645736D02*
X273381Y645215D01*
G01X272711Y644164D02*
X274685Y643818D01*
G01D02*
X275989Y644728D01*
G01X273381Y645215D02*
X274416Y645033D01*
G01X274685Y643818D02*
X275989Y644728D01*
G01X274416Y645033D02*
X274939Y645398D01*
G01X275989Y644728D02*
X277668Y654262D01*
G01X274939Y645398D02*
X276617Y654932D01*
G01X279588Y653924D02*
X278097Y645468D01*
G01X280804Y654193D02*
X279313Y645737D01*
G01X278097Y645468D02*
X279007Y644165D01*
G01X279313Y645737D02*
X279677Y645216D01*
G01X279007Y644165D02*
X280981Y643819D01*
G01D02*
X282285Y644729D01*
G01X279677Y645216D02*
X280711Y645034D01*
G01X280981Y643819D02*
X282285Y644729D01*
G01X280711Y645034D02*
X281234Y645399D01*
G01X282285Y644729D02*
X283967Y654281D01*
G01X281234Y645399D02*
X282917Y654951D01*
G01X285888Y653944D02*
X284388Y645435D01*
G01X287104Y654215D02*
X285604Y645704D01*
G01X284388Y645435D02*
X285298Y644132D01*
G01X285604Y645704D02*
X285968Y645183D01*
G01X285298Y644132D02*
X287272Y643785D01*
G01D02*
X288572Y644696D01*
G01X285968Y645183D02*
X287002Y645001D01*
G01X287272Y643785D02*
X288572Y644696D01*
G01X287002Y645001D02*
X287522Y645365D01*
G01X288572Y644696D02*
X290263Y654278D01*
G01X287522Y645365D02*
X289212Y654946D01*
G01X292185Y653942D02*
X290685Y645434D01*
G01X293401Y654212D02*
X291901Y645705D01*
G01X290685Y645434D02*
X291594Y644133D01*
G01X291901Y645705D02*
X292264Y645183D01*
G01X291594Y644133D02*
X293567Y643785D01*
G01X292264Y645183D02*
X293298Y645000D01*
G01X261565Y650369D02*
X262043D01*
G01X261565D02*
X262043D01*
G01D02*
X262673Y650848D01*
G01D02*
X263435Y651864D01*
G01X263497Y650029D02*
X264494Y651358D01*
G01X263435Y651864D02*
X263604Y652530D01*
G01X264494Y651358D02*
X264730Y652288D01*
G01X263604Y652530D02*
X264016Y654867D01*
G01X264730Y652288D02*
X265066Y654198D01*
G01X264016Y654867D02*
X265317Y655779D01*
G01X265066Y654198D02*
X265587Y654563D01*
G01X264016Y654867D02*
X265317Y655779D01*
G01D02*
X267291Y655432D01*
G01X265587Y654563D02*
X266621Y654381D01*
G01X267291Y655432D02*
X268202Y654128D01*
G01X266621Y654381D02*
X266986Y653859D01*
G01X270322Y654928D02*
X271626Y655842D01*
G01X271373Y654259D02*
X271896Y654626D01*
G01X270322Y654928D02*
X271626Y655842D01*
G01D02*
X273600Y655494D01*
G01X271896Y654626D02*
X272929Y654444D01*
G01X273600Y655494D02*
X274509Y654189D01*
G01X272929Y654444D02*
X273293Y653921D01*
G01X276617Y654932D02*
X277920Y655842D01*
G01X277668Y654262D02*
X278190Y654627D01*
G01X276617Y654932D02*
X277920Y655842D01*
G01D02*
X279892Y655497D01*
G01X278190Y654627D02*
X279223Y654446D01*
G01X279892Y655497D02*
X280804Y654193D01*
G01X279223Y654446D02*
X279588Y653924D01*
G01X282917Y654951D02*
X284220Y655860D01*
G01X283967Y654281D02*
X284489Y654645D01*
G01X282917Y654951D02*
X284220Y655860D01*
G01D02*
X286189Y655515D01*
G01X284489Y654645D02*
X285522Y654464D01*
G01X286189Y655515D02*
X287104Y654215D01*
G01X285522Y654464D02*
X285888Y653944D01*
G01X289212Y654946D02*
X290515Y655862D01*
G01X290263Y654278D02*
X290786Y654646D01*
G01X289212Y654946D02*
X290515Y655862D01*
G01D02*
X292489Y655513D01*
G01X290786Y654646D02*
X291820Y654463D01*
G01X292489Y655513D02*
X293401Y654212D01*
G01X291820Y654463D02*
X292185Y653942D01*
G01X261565Y650369D02*
X262043D01*
G01D02*
X262673Y650848D01*
G01X263497Y650029D02*
X264494Y651358D01*
G01X262673Y650848D02*
X263435Y651864D01*
G01X264494Y651358D02*
X264730Y652288D01*
G01X263435Y651864D02*
X263604Y652530D01*
G01X264730Y652288D02*
X265066Y654198D01*
G01X263604Y652530D02*
X264016Y654867D01*
G01X265066Y654198D02*
X265587Y654563D01*
G01D02*
X266621Y654381D01*
G01X264016Y654867D02*
X265317Y655779D01*
G01X265587Y654563D02*
X266621Y654381D01*
G01X265317Y655779D02*
X267291Y655432D01*
G01X266621Y654381D02*
X266986Y653859D01*
G01X267291Y655432D02*
X268202Y654128D01*
G01X271373Y654259D02*
X271896Y654626D01*
G01D02*
X272929Y654444D01*
G01X270322Y654928D02*
X271626Y655842D01*
G01X271896Y654626D02*
X272929Y654444D01*
G01X271626Y655842D02*
X273600Y655494D01*
G01X272929Y654444D02*
X273293Y653921D01*
G01X273600Y655494D02*
X274509Y654189D01*
G01X277668Y654262D02*
X278190Y654627D01*
G01D02*
X279223Y654446D01*
G01X276617Y654932D02*
X277920Y655842D01*
G01X278190Y654627D02*
X279223Y654446D01*
G01X277920Y655842D02*
X279892Y655497D01*
G01X279223Y654446D02*
X279588Y653924D01*
G01X279892Y655497D02*
X280804Y654193D01*
G01X283967Y654281D02*
X284489Y654645D01*
G01D02*
X285522Y654464D01*
G01X282917Y654951D02*
X284220Y655860D01*
G01X284489Y654645D02*
X285522Y654464D01*
G01X284220Y655860D02*
X286189Y655515D01*
G01X285522Y654464D02*
X285888Y653944D01*
G01X286189Y655515D02*
X287104Y654215D01*
G01X290263Y654278D02*
X290786Y654646D01*
G01D02*
X291820Y654463D01*
G01X289212Y654946D02*
X290515Y655862D01*
G01X290786Y654646D02*
X291820Y654463D01*
G01X290515Y655862D02*
X292489Y655513D01*
G01X291820Y654463D02*
X292185Y653942D01*
G01X292489Y655513D02*
X293401Y654212D01*
G01X293298Y645000D02*
X293820Y645365D01*
G01X293567Y643785D02*
X294870Y644695D01*
G01X293820Y645365D02*
X295488Y654834D01*
G01X294870Y644695D02*
X296539Y654165D01*
G01X299675Y654097D02*
X298198Y645721D01*
G01X298459Y653829D02*
X296982Y645452D01*
G01X298198Y645721D02*
X298562Y645200D01*
G01X296982Y645452D02*
X297892Y644149D01*
G01X298562Y645200D02*
X299596Y645019D01*
G01X297892Y644149D02*
X299865Y643804D01*
G01X298562Y645200D02*
X299596Y645019D01*
G01D02*
X300118Y645383D01*
G01X299865Y643804D02*
X301168Y644713D01*
G01X300118Y645383D02*
X301787Y654839D01*
G01X301168Y644713D02*
X302837Y654169D01*
G01X305971Y654098D02*
X304493Y645723D01*
G01X304755Y653829D02*
X303277Y645454D01*
G01X304493Y645723D02*
X304858Y645201D01*
G01X303277Y645454D02*
X304188Y644150D01*
G01X304858Y645201D02*
X305893Y645019D01*
G01X304188Y644150D02*
X306162Y643804D01*
G01X304858Y645201D02*
X305893Y645019D01*
G01D02*
X306415Y645383D01*
G01X306162Y643804D02*
X307465Y644713D01*
G01X306415Y645383D02*
X308081Y654856D01*
G01X307465Y644713D02*
X309132Y654185D01*
G01X312269Y654114D02*
X310783Y645690D01*
G01X311053Y653846D02*
X309567Y645421D01*
G01X310783Y645690D02*
X311148Y645168D01*
G01X309567Y645421D02*
X310478Y644117D01*
G01X311148Y645168D02*
X312183Y644986D01*
G01X310478Y644117D02*
X312452Y643771D01*
G01X311148Y645168D02*
X312183Y644986D01*
G01D02*
X312705Y645350D01*
G01X312452Y643771D02*
X313755Y644680D01*
G01X312705Y645350D02*
X314371Y654806D01*
G01X313755Y644680D02*
X315421Y654137D01*
G01X318556Y654068D02*
X317079Y645690D01*
G01X317340Y653799D02*
X315863Y645421D01*
G01X317079Y645690D02*
X317443Y645168D01*
G01X315863Y645421D02*
X316773Y644118D01*
G01X317443Y645168D02*
X318477Y644986D01*
G01X316773Y644118D02*
X318746Y643771D01*
G01X317443Y645168D02*
X318477Y644986D01*
G01D02*
X318999Y645351D01*
G01X318746Y643771D02*
X320049Y644681D01*
G01X318999Y645351D02*
X319759Y649663D01*
G01X320049Y644681D02*
X320908Y649553D01*
G01X319759Y649663D02*
X320637Y654611D01*
G01X320908Y649553D02*
X321687Y653941D01*
G01X324823Y653871D02*
X323346Y645493D01*
G01X323607Y653602D02*
X322130Y645224D01*
G01X323346Y645493D02*
X323737Y644933D01*
G01X322130Y645224D02*
X323067Y643882D01*
G01X323737Y644933D02*
X324705Y644763D01*
G01X323067Y643882D02*
X324975Y643547D01*
G01X323737Y644933D02*
X324705Y644763D01*
G01D02*
X325265Y645155D01*
G01X324975Y643547D02*
X326315Y644486D01*
G01X325265Y645155D02*
X326931Y654612D01*
G01X326315Y644486D02*
X327981Y653942D01*
G01X331119Y653871D02*
X329633Y645446D01*
G01X329903Y653602D02*
X328417Y645178D01*
G01X329633Y645446D02*
X329998Y644922D01*
G01X328417Y645178D02*
X329328Y643871D01*
G01X329998Y644922D02*
X331030Y644742D01*
G01X329328Y643871D02*
X331299Y643527D01*
G01X329998Y644922D02*
X331030Y644742D01*
G01D02*
X331554Y645107D01*
G01X331299Y643527D02*
X332605Y644436D01*
G01X331554Y645107D02*
X333221Y654579D01*
G01X332605Y644436D02*
X334271Y653909D01*
G01X337409Y653838D02*
X335931Y645463D01*
G01X336193Y653569D02*
X334715Y645194D01*
G01X335931Y645463D02*
X336296Y644941D01*
G01X334715Y645194D02*
X335626Y643890D01*
G01X336296Y644941D02*
X337328Y644759D01*
G01X335626Y643890D02*
X337597Y643543D01*
G01X336296Y644941D02*
X337328Y644759D01*
G01D02*
X337849Y645123D01*
G01X337597Y643543D02*
X338899Y644453D01*
G01X337849Y645123D02*
X339518Y654579D01*
G01X338899Y644453D02*
X340568Y653909D01*
G01X343704Y653840D02*
X342227Y645463D01*
G01X342488Y653571D02*
X341011Y645195D01*
G01X342227Y645463D02*
X342591Y644941D01*
G01X341011Y645195D02*
X341921Y643890D01*
G01X342591Y644941D02*
X343624Y644760D01*
G01X341921Y643890D02*
X343895Y643544D01*
G01X342591Y644941D02*
X343624Y644760D01*
G01D02*
X344147Y645127D01*
G01X343895Y643544D02*
X345198Y644458D01*
G01X344147Y645127D02*
X345816Y654597D01*
G01X345198Y644458D02*
X346866Y653927D01*
G01X350001Y653858D02*
X348501Y645350D01*
G01X348785Y653587D02*
X347285Y645080D01*
G01X348501Y645350D02*
X348866Y644829D01*
G01X347285Y645080D02*
X348197Y643779D01*
G01X348866Y644829D02*
X349900Y644646D01*
G01X348197Y643779D02*
X350171Y643430D01*
G01X348866Y644829D02*
X349900Y644646D01*
G01D02*
X350423Y645014D01*
G01X350171Y643430D02*
X351474Y644346D01*
G01X350423Y645014D02*
X352114Y654596D01*
G01X351474Y644346D02*
X353164Y653927D01*
G01X355082Y653588D02*
X353582Y645077D01*
G01D02*
X354497Y643777D01*
G01D02*
X356466Y643432D01*
G01X293567Y643785D02*
X294870Y644695D01*
G01X293567Y643785D02*
X294870Y644695D01*
G01X293298Y645000D02*
X293820Y645365D01*
G01X294870Y644695D02*
X296539Y654165D01*
G01X293820Y645365D02*
X295488Y654834D01*
G01X298459Y653829D02*
X296982Y645452D01*
G01X299675Y654097D02*
X298198Y645721D01*
G01X296982Y645452D02*
X297892Y644149D01*
G01X298198Y645721D02*
X298562Y645200D01*
G01X297892Y644149D02*
X299865Y643804D01*
G01D02*
X301168Y644713D01*
G01X298562Y645200D02*
X299596Y645019D01*
G01X299865Y643804D02*
X301168Y644713D01*
G01X299596Y645019D02*
X300118Y645383D01*
G01X301168Y644713D02*
X302837Y654169D01*
G01X300118Y645383D02*
X301787Y654839D01*
G01X304755Y653829D02*
X303277Y645454D01*
G01X305971Y654098D02*
X304493Y645723D01*
G01X303277Y645454D02*
X304188Y644150D01*
G01X304493Y645723D02*
X304858Y645201D01*
G01X304188Y644150D02*
X306162Y643804D01*
G01D02*
X307465Y644713D01*
G01X304858Y645201D02*
X305893Y645019D01*
G01X306162Y643804D02*
X307465Y644713D01*
G01X305893Y645019D02*
X306415Y645383D01*
G01X307465Y644713D02*
X309132Y654185D01*
G01X306415Y645383D02*
X308081Y654856D01*
G01X311053Y653846D02*
X309567Y645421D01*
G01X312269Y654114D02*
X310783Y645690D01*
G01X309567Y645421D02*
X310478Y644117D01*
G01X310783Y645690D02*
X311148Y645168D01*
G01X310478Y644117D02*
X312452Y643771D01*
G01D02*
X313755Y644680D01*
G01X311148Y645168D02*
X312183Y644986D01*
G01X312452Y643771D02*
X313755Y644680D01*
G01X312183Y644986D02*
X312705Y645350D01*
G01X313755Y644680D02*
X315421Y654137D01*
G01X312705Y645350D02*
X314371Y654806D01*
G01X317340Y653799D02*
X315863Y645421D01*
G01X318556Y654068D02*
X317079Y645690D01*
G01X315863Y645421D02*
X316773Y644118D01*
G01X317079Y645690D02*
X317443Y645168D01*
G01X316773Y644118D02*
X318746Y643771D01*
G01D02*
X320049Y644681D01*
G01X317443Y645168D02*
X318477Y644986D01*
G01X318746Y643771D02*
X320049Y644681D01*
G01X318477Y644986D02*
X318999Y645351D01*
G01X320049Y644681D02*
X320908Y649553D01*
G01X318999Y645351D02*
X319759Y649663D01*
G01X320908Y649553D02*
X321687Y653941D01*
G01X319759Y649663D02*
X320637Y654611D01*
G01X323607Y653602D02*
X322130Y645224D01*
G01X324823Y653871D02*
X323346Y645493D01*
G01X322130Y645224D02*
X323067Y643882D01*
G01X323346Y645493D02*
X323737Y644933D01*
G01X323067Y643882D02*
X324975Y643547D01*
G01D02*
X326315Y644486D01*
G01X323737Y644933D02*
X324705Y644763D01*
G01X324975Y643547D02*
X326315Y644486D01*
G01X324705Y644763D02*
X325265Y645155D01*
G01X326315Y644486D02*
X327981Y653942D01*
G01X325265Y645155D02*
X326931Y654612D01*
G01X329903Y653602D02*
X328417Y645178D01*
G01X331119Y653871D02*
X329633Y645446D01*
G01X328417Y645178D02*
X329328Y643871D01*
G01X329633Y645446D02*
X329998Y644922D01*
G01X329328Y643871D02*
X331299Y643527D01*
G01D02*
X332605Y644436D01*
G01X329998Y644922D02*
X331030Y644742D01*
G01X331299Y643527D02*
X332605Y644436D01*
G01X331030Y644742D02*
X331554Y645107D01*
G01X332605Y644436D02*
X334271Y653909D01*
G01X331554Y645107D02*
X333221Y654579D01*
G01X336193Y653569D02*
X334715Y645194D01*
G01X337409Y653838D02*
X335931Y645463D01*
G01X334715Y645194D02*
X335626Y643890D01*
G01X335931Y645463D02*
X336296Y644941D01*
G01X335626Y643890D02*
X337597Y643543D01*
G01D02*
X338899Y644453D01*
G01X336296Y644941D02*
X337328Y644759D01*
G01X337597Y643543D02*
X338899Y644453D01*
G01X337328Y644759D02*
X337849Y645123D01*
G01X338899Y644453D02*
X340568Y653909D01*
G01X337849Y645123D02*
X339518Y654579D01*
G01X342488Y653571D02*
X341011Y645195D01*
G01X343704Y653840D02*
X342227Y645463D01*
G01X341011Y645195D02*
X341921Y643890D01*
G01X342227Y645463D02*
X342591Y644941D01*
G01X341921Y643890D02*
X343895Y643544D01*
G01D02*
X345198Y644458D01*
G01X342591Y644941D02*
X343624Y644760D01*
G01X343895Y643544D02*
X345198Y644458D01*
G01X343624Y644760D02*
X344147Y645127D01*
G01X345198Y644458D02*
X346866Y653927D01*
G01X344147Y645127D02*
X345816Y654597D01*
G01X348785Y653587D02*
X347285Y645080D01*
G01X350001Y653858D02*
X348501Y645350D01*
G01X347285Y645080D02*
X348197Y643779D01*
G01X348501Y645350D02*
X348866Y644829D01*
G01X348197Y643779D02*
X350171Y643430D01*
G01D02*
X351474Y644346D01*
G01X348866Y644829D02*
X349900Y644646D01*
G01X350171Y643430D02*
X351474Y644346D01*
G01X349900Y644646D02*
X350423Y645014D01*
G01X351474Y644346D02*
X353164Y653927D01*
G01X350423Y645014D02*
X352114Y654596D01*
G01X355082Y653588D02*
X353582Y645077D01*
G01D02*
X354497Y643777D01*
G01D02*
X356466Y643432D01*
G01X295488Y654834D02*
X296791Y655748D01*
G01X296539Y654165D02*
X297062Y654532D01*
G01X295488Y654834D02*
X296791Y655748D01*
G01D02*
X298765Y655402D01*
G01X297062Y654532D02*
X298095Y654351D01*
G01X298765Y655402D02*
X299675Y654097D01*
G01X298095Y654351D02*
X298459Y653829D01*
G01X301787Y654839D02*
X303089Y655749D01*
G01X302837Y654169D02*
X303358Y654533D01*
G01X301787Y654839D02*
X303089Y655749D01*
G01D02*
X305060Y655402D01*
G01X303358Y654533D02*
X304390Y654351D01*
G01X305060Y655402D02*
X305971Y654098D01*
G01X304390Y654351D02*
X304755Y653829D01*
G01X308081Y654856D02*
X309387Y655765D01*
G01X309132Y654185D02*
X309656Y654550D01*
G01X308081Y654856D02*
X309387Y655765D01*
G01D02*
X311358Y655421D01*
G01X309656Y654550D02*
X310688Y654370D01*
G01X311358Y655421D02*
X312269Y654114D01*
G01X310688Y654370D02*
X311053Y653846D01*
G01X314371Y654806D02*
X315711Y655745D01*
G01X315421Y654137D02*
X315981Y654529D01*
G01X314371Y654806D02*
X315711Y655745D01*
G01D02*
X317619Y655410D01*
G01X315981Y654529D02*
X316949Y654359D01*
G01X317619Y655410D02*
X318556Y654068D01*
G01X316949Y654359D02*
X317340Y653799D01*
G01X320637Y654611D02*
X321940Y655521D01*
G01X321687Y653941D02*
X322209Y654306D01*
G01X320637Y654611D02*
X321940Y655521D01*
G01D02*
X323913Y655174D01*
G01X322209Y654306D02*
X323243Y654124D01*
G01X323913Y655174D02*
X324823Y653871D01*
G01X323243Y654124D02*
X323607Y653602D01*
G01X326931Y654612D02*
X328234Y655521D01*
G01X327981Y653942D02*
X328503Y654306D01*
G01X326931Y654612D02*
X328234Y655521D01*
G01D02*
X330208Y655175D01*
G01X328503Y654306D02*
X329538Y654124D01*
G01X330208Y655175D02*
X331119Y653871D01*
G01X329538Y654124D02*
X329903Y653602D01*
G01X333221Y654579D02*
X334524Y655488D01*
G01X334271Y653909D02*
X334793Y654273D01*
G01X333221Y654579D02*
X334524Y655488D01*
G01D02*
X336498Y655142D01*
G01X334793Y654273D02*
X335828Y654091D01*
G01X336498Y655142D02*
X337409Y653838D01*
G01X335828Y654091D02*
X336193Y653569D01*
G01X339518Y654579D02*
X340821Y655488D01*
G01X340568Y653909D02*
X341090Y654273D01*
G01X339518Y654579D02*
X340821Y655488D01*
G01D02*
X342794Y655143D01*
G01X341090Y654273D02*
X342124Y654092D01*
G01X342794Y655143D02*
X343704Y653840D01*
G01X342124Y654092D02*
X342488Y653571D01*
G01X345816Y654597D02*
X347119Y655507D01*
G01X346866Y653927D02*
X347388Y654292D01*
G01X345816Y654597D02*
X347119Y655507D01*
G01D02*
X349092Y655159D01*
G01X347388Y654292D02*
X348422Y654109D01*
G01X349092Y655159D02*
X350001Y653858D01*
G01X348422Y654109D02*
X348785Y653587D01*
G01X352114Y654596D02*
X353414Y655507D01*
G01X353164Y653927D02*
X353684Y654291D01*
G01X352114Y654596D02*
X353414Y655507D01*
G01D02*
X355388Y655160D01*
G01X353684Y654291D02*
X354718Y654109D01*
G01D02*
X355082Y653588D01*
G01X296539Y654165D02*
X297062Y654532D01*
G01D02*
X298095Y654351D01*
G01X295488Y654834D02*
X296791Y655748D01*
G01X297062Y654532D02*
X298095Y654351D01*
G01X296791Y655748D02*
X298765Y655402D01*
G01X298095Y654351D02*
X298459Y653829D01*
G01X298765Y655402D02*
X299675Y654097D01*
G01X302837Y654169D02*
X303358Y654533D01*
G01D02*
X304390Y654351D01*
G01X301787Y654839D02*
X303089Y655749D01*
G01X303358Y654533D02*
X304390Y654351D01*
G01X303089Y655749D02*
X305060Y655402D01*
G01X304390Y654351D02*
X304755Y653829D01*
G01X305060Y655402D02*
X305971Y654098D01*
G01X309132Y654185D02*
X309656Y654550D01*
G01D02*
X310688Y654370D01*
G01X308081Y654856D02*
X309387Y655765D01*
G01X309656Y654550D02*
X310688Y654370D01*
G01X309387Y655765D02*
X311358Y655421D01*
G01X310688Y654370D02*
X311053Y653846D01*
G01X311358Y655421D02*
X312269Y654114D01*
G01X315421Y654137D02*
X315981Y654529D01*
G01D02*
X316949Y654359D01*
G01X314371Y654806D02*
X315711Y655745D01*
G01X315981Y654529D02*
X316949Y654359D01*
G01X315711Y655745D02*
X317619Y655410D01*
G01X316949Y654359D02*
X317340Y653799D01*
G01X317619Y655410D02*
X318556Y654068D01*
G01X321687Y653941D02*
X322209Y654306D01*
G01D02*
X323243Y654124D01*
G01X320637Y654611D02*
X321940Y655521D01*
G01X322209Y654306D02*
X323243Y654124D01*
G01X321940Y655521D02*
X323913Y655174D01*
G01X323243Y654124D02*
X323607Y653602D01*
G01X323913Y655174D02*
X324823Y653871D01*
G01X327981Y653942D02*
X328503Y654306D01*
G01D02*
X329538Y654124D01*
G01X326931Y654612D02*
X328234Y655521D01*
G01X328503Y654306D02*
X329538Y654124D01*
G01X328234Y655521D02*
X330208Y655175D01*
G01X329538Y654124D02*
X329903Y653602D01*
G01X330208Y655175D02*
X331119Y653871D01*
G01X334271Y653909D02*
X334793Y654273D01*
G01D02*
X335828Y654091D01*
G01X333221Y654579D02*
X334524Y655488D01*
G01X334793Y654273D02*
X335828Y654091D01*
G01X334524Y655488D02*
X336498Y655142D01*
G01X335828Y654091D02*
X336193Y653569D01*
G01X336498Y655142D02*
X337409Y653838D01*
G01X340568Y653909D02*
X341090Y654273D01*
G01D02*
X342124Y654092D01*
G01X339518Y654579D02*
X340821Y655488D01*
G01X341090Y654273D02*
X342124Y654092D01*
G01X340821Y655488D02*
X342794Y655143D01*
G01X342124Y654092D02*
X342488Y653571D01*
G01X342794Y655143D02*
X343704Y653840D01*
G01X346866Y653927D02*
X347388Y654292D01*
G01D02*
X348422Y654109D01*
G01X345816Y654597D02*
X347119Y655507D01*
G01X347388Y654292D02*
X348422Y654109D01*
G01X347119Y655507D02*
X349092Y655159D01*
G01X348422Y654109D02*
X348785Y653587D01*
G01X349092Y655159D02*
X350001Y653858D01*
G01X353164Y653927D02*
X353684Y654291D01*
G01D02*
X354718Y654109D01*
G01X352114Y654596D02*
X353414Y655507D01*
G01X353684Y654291D02*
X354718Y654109D01*
G01X353414Y655507D02*
X355388Y655160D01*
G01X354718Y654109D02*
X355082Y653588D01*
G01X356298Y653857D02*
X354798Y645348D01*
G01D02*
X355164Y644828D01*
G01D02*
X356197Y644647D01*
G01X355164Y644828D02*
X356197Y644647D01*
G01D02*
X356719Y645011D01*
G01X356466Y643432D02*
X357769Y644341D01*
G01X356719Y645011D02*
X358401Y654563D01*
G01X357769Y644341D02*
X359452Y653893D01*
G01X362589Y653824D02*
X361098Y645368D01*
G01X361373Y653555D02*
X359882Y645099D01*
G01X361098Y645368D02*
X361463Y644846D01*
G01X359882Y645099D02*
X360794Y643795D01*
G01X361463Y644846D02*
X362496Y644665D01*
G01X360794Y643795D02*
X362766Y643450D01*
G01X361463Y644846D02*
X362496Y644665D01*
G01D02*
X363018Y645030D01*
G01X362766Y643450D02*
X364069Y644360D01*
G01X363018Y645030D02*
X364697Y654564D01*
G01X364069Y644360D02*
X365747Y653894D01*
G01X368885Y653825D02*
X367393Y645371D01*
G01X367669Y653556D02*
X366177Y645103D01*
G01X367393Y645371D02*
X367757Y644848D01*
G01X366177Y645103D02*
X367086Y643798D01*
G01X367757Y644848D02*
X368790Y644666D01*
G01X367086Y643798D02*
X369060Y643450D01*
G01X367757Y644848D02*
X368790Y644666D01*
G01D02*
X369313Y645033D01*
G01X369060Y643450D02*
X370364Y644364D01*
G01X369313Y645033D02*
X370998Y654583D01*
G01X370364Y644364D02*
X372048Y653914D01*
G01X375184Y653840D02*
X373700Y645433D01*
G01X373968Y653570D02*
X372484Y645164D01*
G01X373700Y645433D02*
X374065Y644911D01*
G01X372484Y645164D02*
X373395Y643860D01*
G01X374065Y644911D02*
X375099Y644729D01*
G01X373395Y643860D02*
X375369Y643513D01*
G01X374065Y644911D02*
X375099Y644729D01*
G01D02*
X375621Y645094D01*
G01X375369Y643513D02*
X376671Y644425D01*
G01X375621Y645094D02*
X375956Y647004D01*
G01X376671Y644425D02*
X377082Y646762D01*
G01X375956Y647004D02*
X376331Y648481D01*
G01X377082Y646762D02*
X377390Y647974D01*
G01X376331Y648481D02*
X376908Y649250D01*
G01X377390Y647974D02*
X377747Y648450D01*
G01X376908Y649250D02*
X378036Y650181D01*
G01X377747Y648450D02*
X378426Y649011D01*
G01X376908Y649250D02*
X378036Y650181D01*
G01X378426Y649011D02*
X379063Y648981D01*
G01X356298Y653857D02*
X354798Y645348D01*
G01D02*
X355164Y644828D01*
G01X356466Y643432D02*
X357769Y644341D01*
G01X355164Y644828D02*
X356197Y644647D01*
G01X356466Y643432D02*
X357769Y644341D01*
G01X356197Y644647D02*
X356719Y645011D01*
G01X357769Y644341D02*
X359452Y653893D01*
G01X356719Y645011D02*
X358401Y654563D01*
G01X361373Y653555D02*
X359882Y645099D01*
G01X362589Y653824D02*
X361098Y645368D01*
G01X359882Y645099D02*
X360794Y643795D01*
G01X361098Y645368D02*
X361463Y644846D01*
G01X360794Y643795D02*
X362766Y643450D01*
G01D02*
X364069Y644360D01*
G01X361463Y644846D02*
X362496Y644665D01*
G01X362766Y643450D02*
X364069Y644360D01*
G01X362496Y644665D02*
X363018Y645030D01*
G01X364069Y644360D02*
X365747Y653894D01*
G01X363018Y645030D02*
X364697Y654564D01*
G01X367669Y653556D02*
X366177Y645103D01*
G01X368885Y653825D02*
X367393Y645371D01*
G01X366177Y645103D02*
X367086Y643798D01*
G01X367393Y645371D02*
X367757Y644848D01*
G01X367086Y643798D02*
X369060Y643450D01*
G01D02*
X370364Y644364D01*
G01X367757Y644848D02*
X368790Y644666D01*
G01X369060Y643450D02*
X370364Y644364D01*
G01X368790Y644666D02*
X369313Y645033D01*
G01X370364Y644364D02*
X372048Y653914D01*
G01X369313Y645033D02*
X370998Y654583D01*
G01X373968Y653570D02*
X372484Y645164D01*
G01X375184Y653840D02*
X373700Y645433D01*
G01X372484Y645164D02*
X373395Y643860D01*
G01X373700Y645433D02*
X374065Y644911D01*
G01X373395Y643860D02*
X375369Y643513D01*
G01D02*
X376671Y644425D01*
G01X374065Y644911D02*
X375099Y644729D01*
G01X375369Y643513D02*
X376671Y644425D01*
G01X375099Y644729D02*
X375621Y645094D01*
G01X376671Y644425D02*
X377082Y646762D01*
G01X375621Y645094D02*
X375956Y647004D01*
G01X377082Y646762D02*
X377390Y647974D01*
G01X375956Y647004D02*
X376331Y648481D01*
G01X377390Y647974D02*
X377747Y648450D01*
G01X376331Y648481D02*
X376908Y649250D01*
G01X377747Y648450D02*
X378426Y649011D01*
G01D02*
X379063Y648981D01*
G01X376908Y649250D02*
X378036Y650181D01*
G01X378426Y649011D02*
X379063Y648981D01*
G01X355388Y655160D02*
X356298Y653857D01*
G01X358401Y654563D02*
X359705Y655473D01*
G01X359452Y653893D02*
X359975Y654258D01*
G01X358401Y654563D02*
X359705Y655473D01*
G01D02*
X361679Y655127D01*
G01X359975Y654258D02*
X361009Y654076D01*
G01X361679Y655127D02*
X362589Y653824D01*
G01X361009Y654076D02*
X361373Y653555D01*
G01X364697Y654564D02*
X366001Y655474D01*
G01X365747Y653894D02*
X366270Y654259D01*
G01X364697Y654564D02*
X366001Y655474D01*
G01D02*
X367975Y655128D01*
G01X366270Y654259D02*
X367305Y654077D01*
G01X367975Y655128D02*
X368885Y653825D01*
G01X367305Y654077D02*
X367669Y653556D01*
G01X370998Y654583D02*
X372298Y655493D01*
G01X372048Y653914D02*
X372567Y654277D01*
G01X370998Y654583D02*
X372298Y655493D01*
G01D02*
X374271Y655144D01*
G01X372567Y654277D02*
X373601Y654094D01*
G01X374271Y655144D02*
X375184Y653840D01*
G01X373601Y654094D02*
X373968Y653570D01*
G01X378036Y650181D02*
X379156Y650129D01*
G01X355388Y655160D02*
X356298Y653857D01*
G01X359452Y653893D02*
X359975Y654258D01*
G01D02*
X361009Y654076D01*
G01X358401Y654563D02*
X359705Y655473D01*
G01X359975Y654258D02*
X361009Y654076D01*
G01X359705Y655473D02*
X361679Y655127D01*
G01X361009Y654076D02*
X361373Y653555D01*
G01X361679Y655127D02*
X362589Y653824D01*
G01X365747Y653894D02*
X366270Y654259D01*
G01D02*
X367305Y654077D01*
G01X364697Y654564D02*
X366001Y655474D01*
G01X366270Y654259D02*
X367305Y654077D01*
G01X366001Y655474D02*
X367975Y655128D01*
G01X367305Y654077D02*
X367669Y653556D01*
G01X367975Y655128D02*
X368885Y653825D01*
G01X372048Y653914D02*
X372567Y654277D01*
G01D02*
X373601Y654094D01*
G01X370998Y654583D02*
X372298Y655493D01*
G01X372567Y654277D02*
X373601Y654094D01*
G01X372298Y655493D02*
X374271Y655144D01*
G01X373601Y654094D02*
X373968Y653570D01*
G01X374271Y655144D02*
X375184Y653840D01*
G01X378036Y650181D02*
X379156Y650129D01*
G01X599360Y154164D02*
X550481Y203043D01*
G01X550958Y204193D02*
X600510Y154641D01*
G01X599360Y116608D02*
Y154164D01*
G01X600510Y154641D02*
Y136661D01*
G01X599360Y116608D02*
Y154164D01*
G01X600510Y134773D02*
Y133873D01*
G01X599360Y116608D02*
Y154164D01*
G01X600510Y131985D02*
Y131085D01*
G01X599360Y116608D02*
Y154164D01*
G01X600510Y129197D02*
Y128175D01*
G01X599360Y116608D02*
Y154164D01*
G01X600510Y126551D02*
Y117085D01*
G01X601250Y114718D02*
X599360Y116608D01*
G01X600510Y117085D02*
X601727Y115868D01*
G01X603282Y114718D02*
X601250D01*
G01X603282D02*
X601250D01*
G01X600510Y117085D02*
X601727Y115868D01*
G01X601250Y114718D02*
X599360Y116608D01*
G01X600510Y154641D02*
Y136661D01*
G01Y134773D02*
Y133873D01*
G01Y131985D02*
Y131085D01*
G01Y129197D02*
Y128175D01*
G01Y126551D02*
Y117085D01*
G01X599360Y116608D02*
Y154164D01*
G01X550958Y204193D02*
X600510Y154641D01*
G01X599360Y154164D02*
X550481Y203043D01*
G01X550958Y204193D02*
X600510Y154641D01*
G01X550481Y203043D02*
X549330D01*
G01Y204193D02*
X550958D01*
G01X550481Y203043D02*
X549330D01*
G01Y204193D02*
X550958D01*
G01X550481Y203043D02*
X549330D01*
G01X553699Y207700D02*
X619073Y142326D01*
G01X617923Y141849D02*
X552886Y206886D01*
G01X617923Y141849D02*
X552886Y206886D01*
G01X553699Y207700D02*
X619073Y142326D01*
G01X601727Y115868D02*
X604040D01*
G01X601727D02*
X604040D01*
G01X620402Y116175D02*
X619490Y115263D01*
G01X618400Y115800D02*
X619252Y116652D01*
G01X620402Y120748D02*
Y116175D01*
G01X619252Y116652D02*
Y120271D01*
G01X619073Y122077D02*
X620402Y120748D01*
G01X619252Y120271D02*
X617923Y121600D01*
G01X619073Y142326D02*
Y122077D01*
G01X617923Y121600D02*
Y123000D01*
G01X619073Y142326D02*
Y122077D01*
G01X617923Y125400D02*
Y126600D01*
G01X619073Y142326D02*
Y122077D01*
G01X617923Y129000D02*
Y130350D01*
G01X619073Y142326D02*
Y122077D01*
G01X617923Y133000D02*
Y134350D01*
G01X619073Y142326D02*
Y122077D01*
G01X617923Y137000D02*
Y141849D01*
G01Y121600D02*
Y123000D01*
G01Y125400D02*
Y126600D01*
G01Y129000D02*
Y130350D01*
G01Y133000D02*
Y134350D01*
G01Y137000D02*
Y141849D01*
G01X619073Y142326D02*
Y122077D01*
G01X619252Y120271D02*
X617923Y121600D01*
G01X619073Y122077D02*
X620402Y120748D01*
G01X619252Y116652D02*
Y120271D01*
G01X620402Y120748D02*
Y116175D01*
G01X618400Y115800D02*
X619252Y116652D01*
G01X620402Y116175D02*
X619490Y115263D01*
G01X906382Y-46482D02*
X823409D01*
G01X905905Y-47632D02*
X823409D01*
G01X905905D02*
X823409D01*
G01X906382Y-46482D02*
X823409D01*
G01X1109042Y-49950D02*
X909850D01*
G01X1109042Y-51100D02*
X909373D01*
G01X909850Y-49950D02*
X906382Y-46482D01*
G01X909373Y-51100D02*
X905905Y-47632D01*
G01X1109042Y-51100D02*
X909373D01*
G01X1109042Y-49950D02*
X909850D01*
G01X909373Y-51100D02*
X905905Y-47632D01*
G01X909850Y-49950D02*
X906382Y-46482D01*
G01X1109142Y-42550D02*
X914500D01*
G01X1109142Y-43700D02*
X914500D01*
G01Y-42550D02*
G03Y-47400I0J-2425D01*
G01Y-43700D02*
G03Y-46250I0J-1275D01*
G01Y-47400D02*
X1109042D01*
G01X914500Y-46250D02*
X1109042D01*
G01X1109142Y-43700D02*
X914500D01*
G01X1109142Y-42550D02*
X914500D01*
G01Y-43700D02*
G03Y-46250I0J-1275D01*
G01Y-42550D02*
G03Y-47400I0J-2425D01*
G01Y-46250D02*
X1109042D01*
G01X914500Y-47400D02*
X1109042D01*
G01X970347Y644666D02*
X971381Y644484D01*
G01D02*
X971904Y644849D01*
G01X972955Y644179D02*
X971651Y643269D01*
G01X970347Y644666D02*
X971381Y644484D01*
G01X971651Y643269D02*
X969677Y643615D01*
G01X969983Y645187D02*
X970347Y644666D01*
G01X969677Y643615D02*
X968767Y644918D01*
G01X971474Y653643D02*
X969983Y645187D01*
G01X968767Y644918D02*
X970258Y653374D01*
G01X965609Y644848D02*
X967287Y654382D01*
G01X968338Y653712D02*
X966659Y644178D01*
G01X964051Y644665D02*
X965086Y644483D01*
G01D02*
X965609Y644848D01*
G01X966659Y644178D02*
X965355Y643268D01*
G01X964051Y644665D02*
X965086Y644483D01*
G01X965355Y643268D02*
X963381Y643614D01*
G01X963687Y645186D02*
X964051Y644665D01*
G01X963381Y643614D02*
X962471Y644917D01*
G01X965179Y653639D02*
X963687Y645186D01*
G01X962471Y644917D02*
X963963Y653371D01*
G01X959308Y644828D02*
X960992Y654378D01*
G01X962043Y653709D02*
X960358Y644159D01*
G01X957755Y644648D02*
X958789Y644465D01*
G01D02*
X959308Y644828D01*
G01X960358Y644159D02*
X959058Y643249D01*
G01X957755Y644648D02*
X958789Y644465D01*
G01X959058Y643249D02*
X957085Y643598D01*
G01X957388Y645172D02*
X957755Y644648D01*
G01X957085Y643598D02*
X956172Y644902D01*
G01X958872Y653578D02*
X957388Y645172D01*
G01X956172Y644902D02*
X957656Y653309D01*
G01X955156Y650777D02*
X954175Y649469D01*
G01X950371Y649467D02*
X953475Y650454D01*
G01X954175Y649469D02*
X950504Y648302D01*
G01X946096Y649809D02*
X950371Y649467D01*
G01X950504Y648302D02*
X946049Y648659D01*
G01D02*
X944308D01*
G01X946049D02*
X944308D01*
G01X950504Y648302D02*
X946049Y648659D01*
G01X946096Y649809D02*
X950371Y649467D01*
G01X954175Y649469D02*
X950504Y648302D01*
G01X950371Y649467D02*
X953475Y650454D01*
G01X955156Y650777D02*
X954175Y649469D01*
G01X956172Y644902D02*
X957656Y653309D01*
G01X958872Y653578D02*
X957388Y645172D01*
G01X957085Y643598D02*
X956172Y644902D01*
G01X957388Y645172D02*
X957755Y644648D01*
G01X960358Y644159D02*
X959058Y643249D01*
G01D02*
X957085Y643598D01*
G01X957755Y644648D02*
X958789Y644465D01*
G01X960358Y644159D02*
X959058Y643249D01*
G01X958789Y644465D02*
X959308Y644828D01*
G01X962043Y653709D02*
X960358Y644159D01*
G01X959308Y644828D02*
X960992Y654378D01*
G01X962471Y644917D02*
X963963Y653371D01*
G01X965179Y653639D02*
X963687Y645186D01*
G01X963381Y643614D02*
X962471Y644917D01*
G01X963687Y645186D02*
X964051Y644665D01*
G01X966659Y644178D02*
X965355Y643268D01*
G01D02*
X963381Y643614D01*
G01X964051Y644665D02*
X965086Y644483D01*
G01X966659Y644178D02*
X965355Y643268D01*
G01X965086Y644483D02*
X965609Y644848D01*
G01X968338Y653712D02*
X966659Y644178D01*
G01X965609Y644848D02*
X967287Y654382D01*
G01X968767Y644918D02*
X970258Y653374D01*
G01X971474Y653643D02*
X969983Y645187D01*
G01X969677Y643615D02*
X968767Y644918D01*
G01X969983Y645187D02*
X970347Y644666D01*
G01X972955Y644179D02*
X971651Y643269D01*
G01D02*
X969677Y643615D01*
G01X970347Y644666D02*
X971381Y644484D01*
G01X972955Y644179D02*
X971651Y643269D01*
G01X971381Y644484D02*
X971904Y644849D01*
G01X970562Y654947D02*
X971474Y653643D01*
G01X970258Y653374D02*
X969893Y653896D01*
G01X967287Y654382D02*
X968590Y655292D01*
G01D02*
X970562Y654947D01*
G01X969893Y653896D02*
X968860Y654077D01*
G01X967287Y654382D02*
X968590Y655292D01*
G01X968860Y654077D02*
X968338Y653712D01*
G01X964270Y654944D02*
X965179Y653639D01*
G01X963963Y653371D02*
X963599Y653894D01*
G01X960992Y654378D02*
X962296Y655292D01*
G01D02*
X964270Y654944D01*
G01X963599Y653894D02*
X962566Y654076D01*
G01X960992Y654378D02*
X962296Y655292D01*
G01X962566Y654076D02*
X962043Y653709D01*
G01X957961Y654882D02*
X958872Y653578D01*
G01X957656Y653309D02*
X957291Y653831D01*
G01X954685Y654317D02*
X955987Y655229D01*
G01D02*
X957961Y654882D01*
G01X957291Y653831D02*
X956257Y654013D01*
G01X954685Y654317D02*
X955987Y655229D01*
G01X956257Y654013D02*
X955736Y653648D01*
G01X954274Y651980D02*
X954685Y654317D01*
G01X955736Y653648D02*
X955400Y651738D01*
G01X954097Y651284D02*
X954274Y651980D01*
G01X955400Y651738D02*
X955156Y650777D01*
G01X953475Y650454D02*
X954097Y651284D01*
G01X944308Y649809D02*
X946096D01*
G01X944308D02*
X946096D01*
G01X953475Y650454D02*
X954097Y651284D01*
G01X955400Y651738D02*
X955156Y650777D01*
G01X954097Y651284D02*
X954274Y651980D01*
G01X955736Y653648D02*
X955400Y651738D01*
G01X954274Y651980D02*
X954685Y654317D01*
G01X957291Y653831D02*
X956257Y654013D01*
G01D02*
X955736Y653648D01*
G01X954685Y654317D02*
X955987Y655229D01*
G01X957291Y653831D02*
X956257Y654013D01*
G01X955987Y655229D02*
X957961Y654882D01*
G01X957656Y653309D02*
X957291Y653831D01*
G01X957961Y654882D02*
X958872Y653578D01*
G01X963599Y653894D02*
X962566Y654076D01*
G01D02*
X962043Y653709D01*
G01X960992Y654378D02*
X962296Y655292D01*
G01X963599Y653894D02*
X962566Y654076D01*
G01X962296Y655292D02*
X964270Y654944D01*
G01X963963Y653371D02*
X963599Y653894D01*
G01X964270Y654944D02*
X965179Y653639D01*
G01X969893Y653896D02*
X968860Y654077D01*
G01D02*
X968338Y653712D01*
G01X967287Y654382D02*
X968590Y655292D01*
G01X969893Y653896D02*
X968860Y654077D01*
G01X968590Y655292D02*
X970562Y654947D01*
G01X970258Y653374D02*
X969893Y653896D01*
G01X970562Y654947D02*
X971474Y653643D01*
G01X1033312Y644682D02*
X1034345Y644501D01*
G01X1033312Y644682D02*
X1034345Y644501D01*
G01X1034616Y643285D02*
X1032642Y643631D01*
G01X1032948Y645204D02*
X1033312Y644682D01*
G01X1032642Y643631D02*
X1031732Y644936D01*
G01X1034374Y653290D02*
X1032948Y645204D01*
G01X1031732Y644936D02*
X1033158Y653021D01*
G01X1028570Y644864D02*
X1030188Y654029D01*
G01X1031238Y653359D02*
X1029620Y644194D01*
G01X1027017Y644682D02*
X1028049Y644500D01*
G01D02*
X1028570Y644864D01*
G01X1029620Y644194D02*
X1028318Y643284D01*
G01X1027017Y644682D02*
X1028049Y644500D01*
G01X1028318Y643284D02*
X1026347Y643631D01*
G01X1026652Y645204D02*
X1027017Y644682D01*
G01X1026347Y643631D02*
X1025436Y644935D01*
G01X1028079Y653288D02*
X1026652Y645204D01*
G01X1025436Y644935D02*
X1026863Y653019D01*
G01X1022278Y644865D02*
X1023891Y654029D01*
G01X1024941Y653359D02*
X1023329Y644194D01*
G01X1020722Y644680D02*
X1021754Y644500D01*
G01D02*
X1022278Y644865D01*
G01X1023329Y644194D02*
X1022023Y643285D01*
G01X1020722Y644680D02*
X1021754Y644500D01*
G01X1022023Y643285D02*
X1020052Y643629D01*
G01X1020357Y645204D02*
X1020722Y644680D01*
G01X1020052Y643629D02*
X1019141Y644936D01*
G01X1021789Y653321D02*
X1020357Y645204D01*
G01X1019141Y644936D02*
X1020573Y653052D01*
G01X1015986Y644896D02*
X1017601Y654062D01*
G01X1018651Y653392D02*
X1017036Y644227D01*
G01X1014458Y644674D02*
X1015426Y644504D01*
G01D02*
X1015986Y644896D01*
G01X1017036Y644227D02*
X1015696Y643288D01*
G01X1014458Y644674D02*
X1015426Y644504D01*
G01X1015696Y643288D02*
X1013788Y643623D01*
G01X1014067Y645234D02*
X1014458Y644674D01*
G01X1013788Y643623D02*
X1012851Y644965D01*
G01X1015493Y653321D02*
X1014067Y645234D01*
G01X1012851Y644965D02*
X1014277Y653052D01*
G01X1009669Y644801D02*
X1011307Y654061D01*
G01X1012357Y653391D02*
X1010719Y644131D01*
G01X1008113Y644618D02*
X1009147Y644436D01*
G01D02*
X1009669Y644801D01*
G01X1010719Y644131D02*
X1009416Y643221D01*
G01X1008113Y644618D02*
X1009147Y644436D01*
G01X1009416Y643221D02*
X1007443Y643568D01*
G01X1007749Y645140D02*
X1008113Y644618D01*
G01X1007443Y643568D02*
X1006533Y644871D01*
G01X1009226Y653518D02*
X1007749Y645140D01*
G01X1006533Y644871D02*
X1008010Y653249D01*
G01X1003375Y644800D02*
X1005041Y654256D01*
G01X1006091Y653587D02*
X1004425Y644130D01*
G01X1001818Y644618D02*
X1002853Y644436D01*
G01D02*
X1003375Y644800D01*
G01X1004425Y644130D02*
X1003122Y643221D01*
G01X1001818Y644618D02*
X1002853Y644436D01*
G01X1003122Y643221D02*
X1001148Y643567D01*
G01X1001453Y645140D02*
X1001818Y644618D01*
G01X1001148Y643567D02*
X1000237Y644871D01*
G01X1002939Y653564D02*
X1001453Y645140D01*
G01X1000237Y644871D02*
X1001723Y653296D01*
G01X997085Y644833D02*
X998751Y654306D01*
G01X999802Y653635D02*
X998135Y644163D01*
G01X995528Y644651D02*
X996563Y644469D01*
G01D02*
X997085Y644833D01*
G01X998135Y644163D02*
X996832Y643254D01*
G01X995528Y644651D02*
X996563Y644469D01*
G01X996832Y643254D02*
X994858Y643600D01*
G01X995163Y645173D02*
X995528Y644651D01*
G01X994858Y643600D02*
X993947Y644904D01*
G01X996641Y653548D02*
X995163Y645173D01*
G01X993947Y644904D02*
X995425Y653279D01*
G01X990788Y644833D02*
X992457Y654289D01*
G01X993507Y653619D02*
X991838Y644163D01*
G01X989232Y644650D02*
X990266Y644469D01*
G01D02*
X990788Y644833D01*
G01X991838Y644163D02*
X990535Y643254D01*
G01X989232Y644650D02*
X990266Y644469D01*
G01X990535Y643254D02*
X988562Y643599D01*
G01X988868Y645171D02*
X989232Y644650D01*
G01X988562Y643599D02*
X987652Y644902D01*
G01X990345Y653547D02*
X988868Y645171D01*
G01X987652Y644902D02*
X989129Y653279D01*
G01X984490Y644815D02*
X986158Y654284D01*
G01X987209Y653615D02*
X985540Y644145D01*
G01X982934Y644633D02*
X983968Y644450D01*
G01D02*
X984490Y644815D01*
G01X985540Y644145D02*
X984237Y643235D01*
G01X982934Y644633D02*
X983968Y644450D01*
G01X984237Y643235D02*
X982264Y643583D01*
G01X982571Y645155D02*
X982934Y644633D01*
G01X982264Y643583D02*
X981355Y644884D01*
G01X984071Y653662D02*
X982571Y645155D01*
G01X981355Y644884D02*
X982855Y653392D01*
G01X978192Y644815D02*
X979882Y654396D01*
G01X980933Y653728D02*
X979242Y644146D01*
G01X976638Y644633D02*
X977672Y644451D01*
G01D02*
X978192Y644815D01*
G01X979242Y644146D02*
X977942Y643235D01*
G01X976638Y644633D02*
X977672Y644451D01*
G01X977942Y643235D02*
X975968Y643582D01*
G01X976274Y645154D02*
X976638Y644633D01*
G01X975968Y643582D02*
X975058Y644885D01*
G01X977774Y653665D02*
X976274Y645154D01*
G01X975058Y644885D02*
X976558Y653394D01*
G01X971904Y644849D02*
X973587Y654401D01*
G01X974637Y653731D02*
X972955Y644179D01*
G01X974637Y653731D02*
X972955Y644179D01*
G01X971904Y644849D02*
X973587Y654401D01*
G01X975058Y644885D02*
X976558Y653394D01*
G01X977774Y653665D02*
X976274Y645154D01*
G01X975968Y643582D02*
X975058Y644885D01*
G01X976274Y645154D02*
X976638Y644633D01*
G01X979242Y644146D02*
X977942Y643235D01*
G01D02*
X975968Y643582D01*
G01X976638Y644633D02*
X977672Y644451D01*
G01X979242Y644146D02*
X977942Y643235D01*
G01X977672Y644451D02*
X978192Y644815D01*
G01X980933Y653728D02*
X979242Y644146D01*
G01X978192Y644815D02*
X979882Y654396D01*
G01X981355Y644884D02*
X982855Y653392D01*
G01X984071Y653662D02*
X982571Y645155D01*
G01X982264Y643583D02*
X981355Y644884D01*
G01X982571Y645155D02*
X982934Y644633D01*
G01X985540Y644145D02*
X984237Y643235D01*
G01D02*
X982264Y643583D01*
G01X982934Y644633D02*
X983968Y644450D01*
G01X985540Y644145D02*
X984237Y643235D01*
G01X983968Y644450D02*
X984490Y644815D01*
G01X987209Y653615D02*
X985540Y644145D01*
G01X984490Y644815D02*
X986158Y654284D01*
G01X987652Y644902D02*
X989129Y653279D01*
G01X990345Y653547D02*
X988868Y645171D01*
G01X988562Y643599D02*
X987652Y644902D01*
G01X988868Y645171D02*
X989232Y644650D01*
G01X991838Y644163D02*
X990535Y643254D01*
G01D02*
X988562Y643599D01*
G01X989232Y644650D02*
X990266Y644469D01*
G01X991838Y644163D02*
X990535Y643254D01*
G01X990266Y644469D02*
X990788Y644833D01*
G01X993507Y653619D02*
X991838Y644163D01*
G01X990788Y644833D02*
X992457Y654289D01*
G01X993947Y644904D02*
X995425Y653279D01*
G01X996641Y653548D02*
X995163Y645173D01*
G01X994858Y643600D02*
X993947Y644904D01*
G01X995163Y645173D02*
X995528Y644651D01*
G01X998135Y644163D02*
X996832Y643254D01*
G01D02*
X994858Y643600D01*
G01X995528Y644651D02*
X996563Y644469D01*
G01X998135Y644163D02*
X996832Y643254D01*
G01X996563Y644469D02*
X997085Y644833D01*
G01X999802Y653635D02*
X998135Y644163D01*
G01X997085Y644833D02*
X998751Y654306D01*
G01X1000237Y644871D02*
X1001723Y653296D01*
G01X1002939Y653564D02*
X1001453Y645140D01*
G01X1001148Y643567D02*
X1000237Y644871D01*
G01X1001453Y645140D02*
X1001818Y644618D01*
G01X1004425Y644130D02*
X1003122Y643221D01*
G01D02*
X1001148Y643567D01*
G01X1001818Y644618D02*
X1002853Y644436D01*
G01X1004425Y644130D02*
X1003122Y643221D01*
G01X1002853Y644436D02*
X1003375Y644800D01*
G01X1006091Y653587D02*
X1004425Y644130D01*
G01X1003375Y644800D02*
X1005041Y654256D01*
G01X1006533Y644871D02*
X1008010Y653249D01*
G01X1009226Y653518D02*
X1007749Y645140D01*
G01X1007443Y643568D02*
X1006533Y644871D01*
G01X1007749Y645140D02*
X1008113Y644618D01*
G01X1010719Y644131D02*
X1009416Y643221D01*
G01D02*
X1007443Y643568D01*
G01X1008113Y644618D02*
X1009147Y644436D01*
G01X1010719Y644131D02*
X1009416Y643221D01*
G01X1009147Y644436D02*
X1009669Y644801D01*
G01X1012357Y653391D02*
X1010719Y644131D01*
G01X1009669Y644801D02*
X1011307Y654061D01*
G01X1012851Y644965D02*
X1014277Y653052D01*
G01X1015493Y653321D02*
X1014067Y645234D01*
G01X1013788Y643623D02*
X1012851Y644965D01*
G01X1014067Y645234D02*
X1014458Y644674D01*
G01X1017036Y644227D02*
X1015696Y643288D01*
G01D02*
X1013788Y643623D01*
G01X1014458Y644674D02*
X1015426Y644504D01*
G01X1017036Y644227D02*
X1015696Y643288D01*
G01X1015426Y644504D02*
X1015986Y644896D01*
G01X1018651Y653392D02*
X1017036Y644227D01*
G01X1015986Y644896D02*
X1017601Y654062D01*
G01X1019141Y644936D02*
X1020573Y653052D01*
G01X1021789Y653321D02*
X1020357Y645204D01*
G01X1020052Y643629D02*
X1019141Y644936D01*
G01X1020357Y645204D02*
X1020722Y644680D01*
G01X1023329Y644194D02*
X1022023Y643285D01*
G01D02*
X1020052Y643629D01*
G01X1020722Y644680D02*
X1021754Y644500D01*
G01X1023329Y644194D02*
X1022023Y643285D01*
G01X1021754Y644500D02*
X1022278Y644865D01*
G01X1024941Y653359D02*
X1023329Y644194D01*
G01X1022278Y644865D02*
X1023891Y654029D01*
G01X1025436Y644935D02*
X1026863Y653019D01*
G01X1028079Y653288D02*
X1026652Y645204D01*
G01X1026347Y643631D02*
X1025436Y644935D01*
G01X1026652Y645204D02*
X1027017Y644682D01*
G01X1029620Y644194D02*
X1028318Y643284D01*
G01D02*
X1026347Y643631D01*
G01X1027017Y644682D02*
X1028049Y644500D01*
G01X1029620Y644194D02*
X1028318Y643284D01*
G01X1028049Y644500D02*
X1028570Y644864D01*
G01X1031238Y653359D02*
X1029620Y644194D01*
G01X1028570Y644864D02*
X1030188Y654029D01*
G01X1031732Y644936D02*
X1033158Y653021D01*
G01X1034374Y653290D02*
X1032948Y645204D01*
G01X1032642Y643631D02*
X1031732Y644936D01*
G01X1032948Y645204D02*
X1033312Y644682D01*
G01X1034616Y643285D02*
X1032642Y643631D01*
G01X1033312Y644682D02*
X1034345Y644501D01*
G01X1033464Y654593D02*
X1034374Y653290D01*
G01X1033158Y653021D02*
X1032794Y653542D01*
G01X1030188Y654029D02*
X1031491Y654938D01*
G01D02*
X1033464Y654593D01*
G01X1032794Y653542D02*
X1031760Y653723D01*
G01X1030188Y654029D02*
X1031491Y654938D01*
G01X1031760Y653723D02*
X1031238Y653359D01*
G01X1027168Y654592D02*
X1028079Y653288D01*
G01X1026863Y653019D02*
X1026498Y653541D01*
G01X1023891Y654029D02*
X1025194Y654938D01*
G01D02*
X1027168Y654592D01*
G01X1026498Y653541D02*
X1025463Y653723D01*
G01X1023891Y654029D02*
X1025194Y654938D01*
G01X1025463Y653723D02*
X1024941Y653359D01*
G01X1020878Y654625D02*
X1021789Y653321D01*
G01X1020573Y653052D02*
X1020208Y653574D01*
G01X1017601Y654062D02*
X1018904Y654971D01*
G01D02*
X1020878Y654625D01*
G01X1020208Y653574D02*
X1019173Y653756D01*
G01X1017601Y654062D02*
X1018904Y654971D01*
G01X1019173Y653756D02*
X1018651Y653392D01*
G01X1014583Y654624D02*
X1015493Y653321D01*
G01X1014277Y653052D02*
X1013913Y653574D01*
G01X1011307Y654061D02*
X1012610Y654971D01*
G01D02*
X1014583Y654624D01*
G01X1013913Y653574D02*
X1012879Y653756D01*
G01X1011307Y654061D02*
X1012610Y654971D01*
G01X1012879Y653756D02*
X1012357Y653391D01*
G01X1008289Y654860D02*
X1009226Y653518D01*
G01X1008010Y653249D02*
X1007619Y653809D01*
G01X1005041Y654256D02*
X1006381Y655195D01*
G01D02*
X1008289Y654860D01*
G01X1007619Y653809D02*
X1006651Y653979D01*
G01X1005041Y654256D02*
X1006381Y655195D01*
G01X1006651Y653979D02*
X1006091Y653587D01*
G01X1002028Y654871D02*
X1002939Y653564D01*
G01X1001723Y653296D02*
X1001358Y653820D01*
G01X998751Y654306D02*
X1000057Y655215D01*
G01D02*
X1002028Y654871D01*
G01X1001358Y653820D02*
X1000326Y654000D01*
G01X998751Y654306D02*
X1000057Y655215D01*
G01X1000326Y654000D02*
X999802Y653635D01*
G01X995730Y654852D02*
X996641Y653548D01*
G01X995425Y653279D02*
X995060Y653801D01*
G01X992457Y654289D02*
X993759Y655199D01*
G01D02*
X995730Y654852D01*
G01X995060Y653801D02*
X994028Y653983D01*
G01X992457Y654289D02*
X993759Y655199D01*
G01X994028Y653983D02*
X993507Y653619D01*
G01X989435Y654852D02*
X990345Y653547D01*
G01X989129Y653279D02*
X988765Y653801D01*
G01X986158Y654284D02*
X987461Y655198D01*
G01D02*
X989435Y654852D01*
G01X988765Y653801D02*
X987732Y653982D01*
G01X986158Y654284D02*
X987461Y655198D01*
G01X987732Y653982D02*
X987209Y653615D01*
G01X983159Y654963D02*
X984071Y653662D01*
G01X982855Y653392D02*
X982490Y653913D01*
G01X979882Y654396D02*
X981185Y655312D01*
G01D02*
X983159Y654963D01*
G01X982490Y653913D02*
X981456Y654096D01*
G01X979882Y654396D02*
X981185Y655312D01*
G01X981456Y654096D02*
X980933Y653728D01*
G01X976859Y654965D02*
X977774Y653665D01*
G01X976558Y653394D02*
X976192Y653914D01*
G01X973587Y654401D02*
X974890Y655310D01*
G01D02*
X976859Y654965D01*
G01X976192Y653914D02*
X975159Y654095D01*
G01X973587Y654401D02*
X974890Y655310D01*
G01X975159Y654095D02*
X974637Y653731D01*
G01X976192Y653914D02*
X975159Y654095D01*
G01D02*
X974637Y653731D01*
G01X973587Y654401D02*
X974890Y655310D01*
G01X976192Y653914D02*
X975159Y654095D01*
G01X974890Y655310D02*
X976859Y654965D01*
G01X976558Y653394D02*
X976192Y653914D01*
G01X976859Y654965D02*
X977774Y653665D01*
G01X982490Y653913D02*
X981456Y654096D01*
G01D02*
X980933Y653728D01*
G01X979882Y654396D02*
X981185Y655312D01*
G01X982490Y653913D02*
X981456Y654096D01*
G01X981185Y655312D02*
X983159Y654963D01*
G01X982855Y653392D02*
X982490Y653913D01*
G01X983159Y654963D02*
X984071Y653662D01*
G01X988765Y653801D02*
X987732Y653982D01*
G01D02*
X987209Y653615D01*
G01X986158Y654284D02*
X987461Y655198D01*
G01X988765Y653801D02*
X987732Y653982D01*
G01X987461Y655198D02*
X989435Y654852D01*
G01X989129Y653279D02*
X988765Y653801D01*
G01X989435Y654852D02*
X990345Y653547D01*
G01X995060Y653801D02*
X994028Y653983D01*
G01D02*
X993507Y653619D01*
G01X992457Y654289D02*
X993759Y655199D01*
G01X995060Y653801D02*
X994028Y653983D01*
G01X993759Y655199D02*
X995730Y654852D01*
G01X995425Y653279D02*
X995060Y653801D01*
G01X995730Y654852D02*
X996641Y653548D01*
G01X1001358Y653820D02*
X1000326Y654000D01*
G01D02*
X999802Y653635D01*
G01X998751Y654306D02*
X1000057Y655215D01*
G01X1001358Y653820D02*
X1000326Y654000D01*
G01X1000057Y655215D02*
X1002028Y654871D01*
G01X1001723Y653296D02*
X1001358Y653820D01*
G01X1002028Y654871D02*
X1002939Y653564D01*
G01X1007619Y653809D02*
X1006651Y653979D01*
G01D02*
X1006091Y653587D01*
G01X1005041Y654256D02*
X1006381Y655195D01*
G01X1007619Y653809D02*
X1006651Y653979D01*
G01X1006381Y655195D02*
X1008289Y654860D01*
G01X1008010Y653249D02*
X1007619Y653809D01*
G01X1008289Y654860D02*
X1009226Y653518D01*
G01X1013913Y653574D02*
X1012879Y653756D01*
G01D02*
X1012357Y653391D01*
G01X1011307Y654061D02*
X1012610Y654971D01*
G01X1013913Y653574D02*
X1012879Y653756D01*
G01X1012610Y654971D02*
X1014583Y654624D01*
G01X1014277Y653052D02*
X1013913Y653574D01*
G01X1014583Y654624D02*
X1015493Y653321D01*
G01X1020208Y653574D02*
X1019173Y653756D01*
G01D02*
X1018651Y653392D01*
G01X1017601Y654062D02*
X1018904Y654971D01*
G01X1020208Y653574D02*
X1019173Y653756D01*
G01X1018904Y654971D02*
X1020878Y654625D01*
G01X1020573Y653052D02*
X1020208Y653574D01*
G01X1020878Y654625D02*
X1021789Y653321D01*
G01X1026498Y653541D02*
X1025463Y653723D01*
G01D02*
X1024941Y653359D01*
G01X1023891Y654029D02*
X1025194Y654938D01*
G01X1026498Y653541D02*
X1025463Y653723D01*
G01X1025194Y654938D02*
X1027168Y654592D01*
G01X1026863Y653019D02*
X1026498Y653541D01*
G01X1027168Y654592D02*
X1028079Y653288D01*
G01X1032794Y653542D02*
X1031760Y653723D01*
G01D02*
X1031238Y653359D01*
G01X1030188Y654029D02*
X1031491Y654938D01*
G01X1032794Y653542D02*
X1031760Y653723D01*
G01X1031491Y654938D02*
X1033464Y654593D01*
G01X1033158Y653021D02*
X1032794Y653542D01*
G01X1033464Y654593D02*
X1034374Y653290D01*
G01X1095590Y643554D02*
X1094675Y644854D01*
G01D02*
X1096107Y652977D01*
G01X1091517Y644791D02*
X1093139Y653985D01*
G01X1094189Y653316D02*
X1092568Y644123D01*
G01X1089959Y644606D02*
X1090993Y644423D01*
G01D02*
X1091517Y644791D01*
G01X1092568Y644123D02*
X1091264Y643207D01*
G01X1089959Y644606D02*
X1090993Y644423D01*
G01X1091264Y643207D02*
X1089290Y643556D01*
G01X1089594Y645127D02*
X1089959Y644606D01*
G01X1089290Y643556D02*
X1088378Y644857D01*
G01X1091026Y653247D02*
X1089594Y645127D01*
G01X1088378Y644857D02*
X1089810Y652976D01*
G01X1085223Y644807D02*
X1086841Y653986D01*
G01X1087891Y653316D02*
X1086274Y644138D01*
G01X1083667Y644621D02*
X1084700Y644440D01*
G01D02*
X1085223Y644807D01*
G01X1086274Y644138D02*
X1084971Y643224D01*
G01X1083667Y644621D02*
X1084700Y644440D01*
G01X1084971Y643224D02*
X1082997Y643570D01*
G01X1083303Y645143D02*
X1083667Y644621D01*
G01X1082997Y643570D02*
X1082087Y644875D01*
G01X1084729Y653229D02*
X1083303Y645143D01*
G01X1082087Y644875D02*
X1083513Y652960D01*
G01X1078925Y644803D02*
X1080543Y653968D01*
G01X1081593Y653298D02*
X1079975Y644133D01*
G01X1077372Y644621D02*
X1078404Y644439D01*
G01D02*
X1078925Y644803D01*
G01X1079975Y644133D02*
X1078673Y643223D01*
G01X1077372Y644621D02*
X1078404Y644439D01*
G01X1078673Y643223D02*
X1076702Y643570D01*
G01X1077007Y645143D02*
X1077372Y644621D01*
G01X1076702Y643570D02*
X1075791Y644874D01*
G01X1078434Y653227D02*
X1077007Y645143D01*
G01X1075791Y644874D02*
X1077218Y652958D01*
G01X1072633Y644804D02*
X1074246Y653968D01*
G01X1075296Y653298D02*
X1073684Y644133D01*
G01X1071077Y644619D02*
X1072109Y644439D01*
G01D02*
X1072633Y644804D01*
G01X1073684Y644133D02*
X1072378Y643224D01*
G01X1071077Y644619D02*
X1072109Y644439D01*
G01X1072378Y643224D02*
X1070407Y643568D01*
G01X1070712Y645143D02*
X1071077Y644619D01*
G01X1070407Y643568D02*
X1069496Y644875D01*
G01X1072144Y653260D02*
X1070712Y645143D01*
G01X1069496Y644875D02*
X1070928Y652991D01*
G01X1066341Y644835D02*
X1067956Y654001D01*
G01X1069006Y653331D02*
X1067391Y644166D01*
G01X1064786Y644652D02*
X1065820Y644470D01*
G01D02*
X1066341Y644835D01*
G01X1067391Y644166D02*
X1066090Y643254D01*
G01X1064786Y644652D02*
X1065820Y644470D01*
G01X1066090Y643254D02*
X1064116Y643601D01*
G01X1064421Y645174D02*
X1064786Y644652D01*
G01X1064116Y643601D02*
X1063205Y644905D01*
G01X1065854Y653290D02*
X1064421Y645174D01*
G01X1063205Y644905D02*
X1064638Y653020D01*
G01X1060052Y644871D02*
X1061668Y654033D01*
G01X1062718Y653364D02*
X1061102Y644202D01*
G01X1058496Y644685D02*
X1059528Y644504D01*
G01D02*
X1060052Y644871D01*
G01X1061102Y644202D02*
X1059798Y643288D01*
G01X1058496Y644685D02*
X1059528Y644504D01*
G01X1059798Y643288D02*
X1057824Y643636D01*
G01X1058131Y645208D02*
X1058496Y644685D01*
G01X1057824Y643636D02*
X1056915Y644940D01*
G01X1059555Y653275D02*
X1058131Y645208D01*
G01X1056915Y644940D02*
X1058339Y653006D01*
G01X1053756Y644868D02*
X1055367Y654014D01*
G01X1056417Y653344D02*
X1054807Y644198D01*
G01X1052201Y644684D02*
X1053234Y644503D01*
G01D02*
X1053756Y644868D01*
G01X1054807Y644198D02*
X1053504Y643288D01*
G01X1052201Y644684D02*
X1053234Y644503D01*
G01X1053504Y643288D02*
X1051532Y643633D01*
G01X1051836Y645206D02*
X1052201Y644684D01*
G01X1051532Y643633D02*
X1050620Y644937D01*
G01X1053259Y653274D02*
X1051836Y645206D01*
G01X1050620Y644937D02*
X1052043Y653005D01*
G01X1047457Y644849D02*
X1049071Y654013D01*
G01X1050122Y653343D02*
X1048507Y644179D01*
G01X1045902Y644666D02*
X1046935Y644485D01*
G01D02*
X1047457Y644849D01*
G01X1048507Y644179D02*
X1047204Y643270D01*
G01X1045902Y644666D02*
X1046935Y644485D01*
G01X1047204Y643270D02*
X1045235Y643615D01*
G01X1045536Y645186D02*
X1045902Y644666D01*
G01X1045235Y643615D02*
X1044320Y644915D01*
G01X1046968Y653307D02*
X1045536Y645186D01*
G01X1044320Y644915D02*
X1045752Y653038D01*
G01X1041147Y644772D02*
X1042784Y654046D01*
G01X1043834Y653377D02*
X1042198Y644104D01*
G01X1039590Y644587D02*
X1040624Y644404D01*
G01D02*
X1041147Y644772D01*
G01X1042198Y644104D02*
X1040895Y643188D01*
G01X1039590Y644587D02*
X1040624Y644404D01*
G01X1040895Y643188D02*
X1038921Y643537D01*
G01X1039225Y645108D02*
X1039590Y644587D01*
G01X1038921Y643537D02*
X1038009Y644838D01*
G01X1040671Y653308D02*
X1039225Y645108D01*
G01X1038009Y644838D02*
X1039455Y653037D01*
G01X1034868Y644868D02*
X1036486Y654047D01*
G01X1037536Y653377D02*
X1035919Y644199D01*
G01X1034345Y644501D02*
X1034868Y644868D01*
G01X1035919Y644199D02*
X1034616Y643285D01*
G01X1035919Y644199D02*
X1034616Y643285D01*
G01X1035919Y644199D02*
X1034616Y643285D01*
G01X1034345Y644501D02*
X1034868Y644868D01*
G01X1037536Y653377D02*
X1035919Y644199D01*
G01X1034868Y644868D02*
X1036486Y654047D01*
G01X1038009Y644838D02*
X1039455Y653037D01*
G01X1040671Y653308D02*
X1039225Y645108D01*
G01X1038921Y643537D02*
X1038009Y644838D01*
G01X1039225Y645108D02*
X1039590Y644587D01*
G01X1042198Y644104D02*
X1040895Y643188D01*
G01D02*
X1038921Y643537D01*
G01X1039590Y644587D02*
X1040624Y644404D01*
G01X1042198Y644104D02*
X1040895Y643188D01*
G01X1040624Y644404D02*
X1041147Y644772D01*
G01X1043834Y653377D02*
X1042198Y644104D01*
G01X1041147Y644772D02*
X1042784Y654046D01*
G01X1044320Y644915D02*
X1045752Y653038D01*
G01X1046968Y653307D02*
X1045536Y645186D01*
G01X1045235Y643615D02*
X1044320Y644915D01*
G01X1045536Y645186D02*
X1045902Y644666D01*
G01X1048507Y644179D02*
X1047204Y643270D01*
G01D02*
X1045235Y643615D01*
G01X1045902Y644666D02*
X1046935Y644485D01*
G01X1048507Y644179D02*
X1047204Y643270D01*
G01X1046935Y644485D02*
X1047457Y644849D01*
G01X1050122Y653343D02*
X1048507Y644179D01*
G01X1047457Y644849D02*
X1049071Y654013D01*
G01X1050620Y644937D02*
X1052043Y653005D01*
G01X1053259Y653274D02*
X1051836Y645206D01*
G01X1051532Y643633D02*
X1050620Y644937D01*
G01X1051836Y645206D02*
X1052201Y644684D01*
G01X1054807Y644198D02*
X1053504Y643288D01*
G01D02*
X1051532Y643633D01*
G01X1052201Y644684D02*
X1053234Y644503D01*
G01X1054807Y644198D02*
X1053504Y643288D01*
G01X1053234Y644503D02*
X1053756Y644868D01*
G01X1056417Y653344D02*
X1054807Y644198D01*
G01X1053756Y644868D02*
X1055367Y654014D01*
G01X1056915Y644940D02*
X1058339Y653006D01*
G01X1059555Y653275D02*
X1058131Y645208D01*
G01X1057824Y643636D02*
X1056915Y644940D01*
G01X1058131Y645208D02*
X1058496Y644685D01*
G01X1061102Y644202D02*
X1059798Y643288D01*
G01D02*
X1057824Y643636D01*
G01X1058496Y644685D02*
X1059528Y644504D01*
G01X1061102Y644202D02*
X1059798Y643288D01*
G01X1059528Y644504D02*
X1060052Y644871D01*
G01X1062718Y653364D02*
X1061102Y644202D01*
G01X1060052Y644871D02*
X1061668Y654033D01*
G01X1063205Y644905D02*
X1064638Y653020D01*
G01X1065854Y653290D02*
X1064421Y645174D01*
G01X1064116Y643601D02*
X1063205Y644905D01*
G01X1064421Y645174D02*
X1064786Y644652D01*
G01X1067391Y644166D02*
X1066090Y643254D01*
G01D02*
X1064116Y643601D01*
G01X1064786Y644652D02*
X1065820Y644470D01*
G01X1067391Y644166D02*
X1066090Y643254D01*
G01X1065820Y644470D02*
X1066341Y644835D01*
G01X1069006Y653331D02*
X1067391Y644166D01*
G01X1066341Y644835D02*
X1067956Y654001D01*
G01X1069496Y644875D02*
X1070928Y652991D01*
G01X1072144Y653260D02*
X1070712Y645143D01*
G01X1070407Y643568D02*
X1069496Y644875D01*
G01X1070712Y645143D02*
X1071077Y644619D01*
G01X1073684Y644133D02*
X1072378Y643224D01*
G01D02*
X1070407Y643568D01*
G01X1071077Y644619D02*
X1072109Y644439D01*
G01X1073684Y644133D02*
X1072378Y643224D01*
G01X1072109Y644439D02*
X1072633Y644804D01*
G01X1075296Y653298D02*
X1073684Y644133D01*
G01X1072633Y644804D02*
X1074246Y653968D01*
G01X1075791Y644874D02*
X1077218Y652958D01*
G01X1078434Y653227D02*
X1077007Y645143D01*
G01X1076702Y643570D02*
X1075791Y644874D01*
G01X1077007Y645143D02*
X1077372Y644621D01*
G01X1079975Y644133D02*
X1078673Y643223D01*
G01D02*
X1076702Y643570D01*
G01X1077372Y644621D02*
X1078404Y644439D01*
G01X1079975Y644133D02*
X1078673Y643223D01*
G01X1078404Y644439D02*
X1078925Y644803D01*
G01X1081593Y653298D02*
X1079975Y644133D01*
G01X1078925Y644803D02*
X1080543Y653968D01*
G01X1082087Y644875D02*
X1083513Y652960D01*
G01X1084729Y653229D02*
X1083303Y645143D01*
G01X1082997Y643570D02*
X1082087Y644875D01*
G01X1083303Y645143D02*
X1083667Y644621D01*
G01X1086274Y644138D02*
X1084971Y643224D01*
G01D02*
X1082997Y643570D01*
G01X1083667Y644621D02*
X1084700Y644440D01*
G01X1086274Y644138D02*
X1084971Y643224D01*
G01X1084700Y644440D02*
X1085223Y644807D01*
G01X1087891Y653316D02*
X1086274Y644138D01*
G01X1085223Y644807D02*
X1086841Y653986D01*
G01X1088378Y644857D02*
X1089810Y652976D01*
G01X1091026Y653247D02*
X1089594Y645127D01*
G01X1089290Y643556D02*
X1088378Y644857D01*
G01X1089594Y645127D02*
X1089959Y644606D01*
G01X1092568Y644123D02*
X1091264Y643207D01*
G01D02*
X1089290Y643556D01*
G01X1089959Y644606D02*
X1090993Y644423D01*
G01X1092568Y644123D02*
X1091264Y643207D01*
G01X1090993Y644423D02*
X1091517Y644791D01*
G01X1094189Y653316D02*
X1092568Y644123D01*
G01X1091517Y644791D02*
X1093139Y653985D01*
G01X1094675Y644854D02*
X1096107Y652977D01*
G01X1095590Y643554D02*
X1094675Y644854D01*
G01X1093139Y653985D02*
X1094439Y654896D01*
G01D02*
X1096413Y654549D01*
G01X1095743Y653498D02*
X1094709Y653680D01*
G01X1093139Y653985D02*
X1094439Y654896D01*
G01X1094709Y653680D02*
X1094189Y653316D01*
G01X1090117Y654548D02*
X1091026Y653247D01*
G01X1089810Y652976D02*
X1089447Y653498D01*
G01X1086841Y653986D02*
X1088144Y654896D01*
G01D02*
X1090117Y654548D01*
G01X1089447Y653498D02*
X1088413Y653681D01*
G01X1086841Y653986D02*
X1088144Y654896D01*
G01X1088413Y653681D02*
X1087891Y653316D01*
G01X1083819Y654532D02*
X1084729Y653229D01*
G01X1083513Y652960D02*
X1083149Y653481D01*
G01X1080543Y653968D02*
X1081846Y654877D01*
G01D02*
X1083819Y654532D01*
G01X1083149Y653481D02*
X1082115Y653662D01*
G01X1080543Y653968D02*
X1081846Y654877D01*
G01X1082115Y653662D02*
X1081593Y653298D01*
G01X1077523Y654531D02*
X1078434Y653227D01*
G01X1077218Y652958D02*
X1076853Y653480D01*
G01X1074246Y653968D02*
X1075549Y654877D01*
G01D02*
X1077523Y654531D01*
G01X1076853Y653480D02*
X1075818Y653662D01*
G01X1074246Y653968D02*
X1075549Y654877D01*
G01X1075818Y653662D02*
X1075296Y653298D01*
G01X1071233Y654564D02*
X1072144Y653260D01*
G01X1070928Y652991D02*
X1070563Y653513D01*
G01X1067956Y654001D02*
X1069259Y654910D01*
G01D02*
X1071233Y654564D01*
G01X1070563Y653513D02*
X1069528Y653695D01*
G01X1067956Y654001D02*
X1069259Y654910D01*
G01X1069528Y653695D02*
X1069006Y653331D01*
G01X1064941Y654594D02*
X1065854Y653290D01*
G01X1064638Y653020D02*
X1064271Y653544D01*
G01X1061668Y654033D02*
X1062968Y654943D01*
G01D02*
X1064941Y654594D01*
G01X1064271Y653544D02*
X1063237Y653727D01*
G01X1061668Y654033D02*
X1062968Y654943D01*
G01X1063237Y653727D02*
X1062718Y653364D01*
G01X1058645Y654578D02*
X1059555Y653275D01*
G01X1058339Y653006D02*
X1057975Y653527D01*
G01X1055367Y654014D02*
X1056671Y654924D01*
G01D02*
X1058645Y654578D01*
G01X1057975Y653527D02*
X1056940Y653709D01*
G01X1055367Y654014D02*
X1056671Y654924D01*
G01X1056940Y653709D02*
X1056417Y653344D01*
G01X1052349Y654577D02*
X1053259Y653274D01*
G01X1052043Y653005D02*
X1051679Y653526D01*
G01X1049071Y654013D02*
X1050375Y654923D01*
G01D02*
X1052349Y654577D01*
G01X1051679Y653526D02*
X1050645Y653708D01*
G01X1049071Y654013D02*
X1050375Y654923D01*
G01X1050645Y653708D02*
X1050122Y653343D01*
G01X1046058Y654610D02*
X1046968Y653307D01*
G01X1045752Y653038D02*
X1045388Y653559D01*
G01X1042784Y654046D02*
X1044084Y654957D01*
G01D02*
X1046058Y654610D01*
G01X1045388Y653559D02*
X1044354Y653741D01*
G01X1042784Y654046D02*
X1044084Y654957D01*
G01X1044354Y653741D02*
X1043834Y653377D01*
G01X1039762Y654609D02*
X1040671Y653308D01*
G01X1039455Y653037D02*
X1039092Y653559D01*
G01X1036486Y654047D02*
X1037789Y654957D01*
G01D02*
X1039762Y654609D01*
G01X1039092Y653559D02*
X1038058Y653742D01*
G01X1036486Y654047D02*
X1037789Y654957D01*
G01X1038058Y653742D02*
X1037536Y653377D01*
G01X1039092Y653559D02*
X1038058Y653742D01*
G01D02*
X1037536Y653377D01*
G01X1036486Y654047D02*
X1037789Y654957D01*
G01X1039092Y653559D02*
X1038058Y653742D01*
G01X1037789Y654957D02*
X1039762Y654609D01*
G01X1039455Y653037D02*
X1039092Y653559D01*
G01X1039762Y654609D02*
X1040671Y653308D01*
G01X1045388Y653559D02*
X1044354Y653741D01*
G01D02*
X1043834Y653377D01*
G01X1042784Y654046D02*
X1044084Y654957D01*
G01X1045388Y653559D02*
X1044354Y653741D01*
G01X1044084Y654957D02*
X1046058Y654610D01*
G01X1045752Y653038D02*
X1045388Y653559D01*
G01X1046058Y654610D02*
X1046968Y653307D01*
G01X1051679Y653526D02*
X1050645Y653708D01*
G01D02*
X1050122Y653343D01*
G01X1049071Y654013D02*
X1050375Y654923D01*
G01X1051679Y653526D02*
X1050645Y653708D01*
G01X1050375Y654923D02*
X1052349Y654577D01*
G01X1052043Y653005D02*
X1051679Y653526D01*
G01X1052349Y654577D02*
X1053259Y653274D01*
G01X1057975Y653527D02*
X1056940Y653709D01*
G01D02*
X1056417Y653344D01*
G01X1055367Y654014D02*
X1056671Y654924D01*
G01X1057975Y653527D02*
X1056940Y653709D01*
G01X1056671Y654924D02*
X1058645Y654578D01*
G01X1058339Y653006D02*
X1057975Y653527D01*
G01X1058645Y654578D02*
X1059555Y653275D01*
G01X1064271Y653544D02*
X1063237Y653727D01*
G01D02*
X1062718Y653364D01*
G01X1061668Y654033D02*
X1062968Y654943D01*
G01X1064271Y653544D02*
X1063237Y653727D01*
G01X1062968Y654943D02*
X1064941Y654594D01*
G01X1064638Y653020D02*
X1064271Y653544D01*
G01X1064941Y654594D02*
X1065854Y653290D01*
G01X1070563Y653513D02*
X1069528Y653695D01*
G01D02*
X1069006Y653331D01*
G01X1067956Y654001D02*
X1069259Y654910D01*
G01X1070563Y653513D02*
X1069528Y653695D01*
G01X1069259Y654910D02*
X1071233Y654564D01*
G01X1070928Y652991D02*
X1070563Y653513D01*
G01X1071233Y654564D02*
X1072144Y653260D01*
G01X1076853Y653480D02*
X1075818Y653662D01*
G01D02*
X1075296Y653298D01*
G01X1074246Y653968D02*
X1075549Y654877D01*
G01X1076853Y653480D02*
X1075818Y653662D01*
G01X1075549Y654877D02*
X1077523Y654531D01*
G01X1077218Y652958D02*
X1076853Y653480D01*
G01X1077523Y654531D02*
X1078434Y653227D01*
G01X1083149Y653481D02*
X1082115Y653662D01*
G01D02*
X1081593Y653298D01*
G01X1080543Y653968D02*
X1081846Y654877D01*
G01X1083149Y653481D02*
X1082115Y653662D01*
G01X1081846Y654877D02*
X1083819Y654532D01*
G01X1083513Y652960D02*
X1083149Y653481D01*
G01X1083819Y654532D02*
X1084729Y653229D01*
G01X1089447Y653498D02*
X1088413Y653681D01*
G01D02*
X1087891Y653316D01*
G01X1086841Y653986D02*
X1088144Y654896D01*
G01X1089447Y653498D02*
X1088413Y653681D01*
G01X1088144Y654896D02*
X1090117Y654548D01*
G01X1089810Y652976D02*
X1089447Y653498D01*
G01X1090117Y654548D02*
X1091026Y653247D01*
G01X1095743Y653498D02*
X1094709Y653680D01*
G01D02*
X1094189Y653316D01*
G01X1093139Y653985D02*
X1094439Y654896D01*
G01X1095743Y653498D02*
X1094709Y653680D01*
G01X1094439Y654896D02*
X1096413Y654549D01*
G01X1109042Y-47400D02*
G02Y-49950I0J-1275D01*
G01Y-46250D02*
G02Y-51100I0J-2425D01*
G01Y-46250D02*
G02Y-51100I0J-2425D01*
G01Y-47400D02*
G02Y-49950I0J-1275D01*
G01X1154486Y644821D02*
X1156155Y654277D01*
G01X1157205Y653607D02*
X1155536Y644151D01*
G01X1152933Y644639D02*
X1153965Y644457D01*
G01D02*
X1154486Y644821D01*
G01X1155536Y644151D02*
X1154234Y643241D01*
G01X1152933Y644639D02*
X1153965Y644457D01*
G01X1154234Y643241D02*
X1152263Y643588D01*
G01X1152568Y645161D02*
X1152933Y644639D01*
G01X1152263Y643588D02*
X1151352Y644892D01*
G01X1154046Y653536D02*
X1152568Y645161D01*
G01X1151352Y644892D02*
X1152830Y653267D01*
G01X1148191Y644805D02*
X1149858Y654277D01*
G01X1150908Y653607D02*
X1149242Y644134D01*
G01X1146635Y644620D02*
X1147667Y644440D01*
G01D02*
X1148191Y644805D01*
G01X1149242Y644134D02*
X1147936Y643225D01*
G01X1146635Y644620D02*
X1147667Y644440D01*
G01X1147936Y643225D02*
X1145965Y643569D01*
G01X1146270Y645144D02*
X1146635Y644620D01*
G01X1145965Y643569D02*
X1145054Y644876D01*
G01X1147756Y653569D02*
X1146270Y645144D01*
G01X1145054Y644876D02*
X1146540Y653300D01*
G01X1141902Y644853D02*
X1143568Y654310D01*
G01X1144618Y653640D02*
X1142952Y644184D01*
G01X1140374Y644631D02*
X1141342Y644461D01*
G01D02*
X1141902Y644853D01*
G01X1142952Y644184D02*
X1141612Y643245D01*
G01X1140374Y644631D02*
X1141342Y644461D01*
G01X1141612Y643245D02*
X1139704Y643580D01*
G01X1139983Y645191D02*
X1140374Y644631D01*
G01X1139704Y643580D02*
X1138767Y644922D01*
G01X1141458Y653564D02*
X1139983Y645191D01*
G01X1138767Y644922D02*
X1140243Y653296D01*
G01X1135617Y644957D02*
X1137270Y654302D01*
G01X1138320Y653633D02*
X1136667Y644287D01*
G01X1134062Y644774D02*
X1135096Y644592D01*
G01D02*
X1135617Y644957D01*
G01X1136667Y644287D02*
X1135366Y643376D01*
G01X1134062Y644774D02*
X1135096Y644592D01*
G01X1135366Y643376D02*
X1133392Y643723D01*
G01X1133697Y645296D02*
X1134062Y644774D01*
G01X1133392Y643723D02*
X1132481Y645027D01*
G01X1135130Y653412D02*
X1133697Y645296D01*
G01X1132481Y645027D02*
X1133914Y653142D01*
G01X1129310Y644896D02*
X1130944Y654155D01*
G01X1131994Y653486D02*
X1130361Y644227D01*
G01X1127755Y644713D02*
X1128789Y644531D01*
G01D02*
X1129310Y644896D01*
G01X1130361Y644227D02*
X1129059Y643315D01*
G01X1127755Y644713D02*
X1128789Y644531D01*
G01X1129059Y643315D02*
X1127085Y643662D01*
G01X1127390Y645235D02*
X1127755Y644713D01*
G01X1127085Y643662D02*
X1126174Y644966D01*
G01X1128823Y653351D02*
X1127390Y645235D01*
G01X1126174Y644966D02*
X1127607Y653081D01*
G01X1123023Y644949D02*
X1124637Y654094D01*
G01X1125687Y653425D02*
X1124074Y644280D01*
G01X1121468Y644766D02*
X1122502Y644584D01*
G01D02*
X1123023Y644949D01*
G01X1124074Y644280D02*
X1122772Y643368D01*
G01X1121468Y644766D02*
X1122502Y644584D01*
G01X1122772Y643368D02*
X1120798Y643715D01*
G01X1121103Y645288D02*
X1121468Y644766D01*
G01X1120798Y643715D02*
X1119887Y645019D01*
G01X1122516Y653290D02*
X1121103Y645288D01*
G01X1119887Y645019D02*
X1121300Y653020D01*
G01X1116714Y644871D02*
X1118330Y654033D01*
G01X1119380Y653364D02*
X1117764Y644202D01*
G01X1115159Y644687D02*
X1116192Y644506D01*
G01D02*
X1116714Y644871D01*
G01X1117764Y644202D02*
X1116462Y643290D01*
G01X1115159Y644687D02*
X1116192Y644506D01*
G01X1116462Y643290D02*
X1114488Y643637D01*
G01X1114794Y645210D02*
X1115159Y644687D01*
G01X1114488Y643637D02*
X1113577Y644940D01*
G01X1116209Y653229D02*
X1114794Y645210D01*
G01X1113577Y644940D02*
X1114993Y652959D01*
G01X1110407Y644810D02*
X1112023Y653972D01*
G01X1113073Y653303D02*
X1111457Y644141D01*
G01X1108851Y644624D02*
X1109883Y644443D01*
G01D02*
X1110407Y644810D01*
G01X1111457Y644141D02*
X1110153Y643227D01*
G01X1108851Y644624D02*
X1109883Y644443D01*
G01X1110153Y643227D02*
X1108179Y643575D01*
G01X1108486Y645147D02*
X1108851Y644624D01*
G01X1108179Y643575D02*
X1107270Y644879D01*
G01X1109910Y653214D02*
X1108486Y645147D01*
G01X1107270Y644879D02*
X1108694Y652945D01*
G01X1104114Y644824D02*
X1105722Y653953D01*
G01X1106772Y653283D02*
X1105165Y644154D01*
G01X1102559Y644640D02*
X1103592Y644459D01*
G01D02*
X1104114Y644824D01*
G01X1105165Y644154D02*
X1103862Y643244D01*
G01X1102559Y644640D02*
X1103592Y644459D01*
G01X1103862Y643244D02*
X1101890Y643589D01*
G01X1102194Y645162D02*
X1102559Y644640D01*
G01X1101890Y643589D02*
X1100978Y644893D01*
G01X1103614Y653213D02*
X1102194Y645162D01*
G01X1100978Y644893D02*
X1102398Y652944D01*
G01X1097812Y644788D02*
X1099426Y653952D01*
G01X1100477Y653282D02*
X1098862Y644118D01*
G01X1096257Y644605D02*
X1097290Y644424D01*
G01D02*
X1097812Y644788D01*
G01X1098862Y644118D02*
X1097559Y643209D01*
G01X1096257Y644605D02*
X1097290Y644424D01*
G01X1097559Y643209D02*
X1095590Y643554D01*
G01X1095891Y645125D02*
X1096257Y644605D01*
G01X1097323Y653246D02*
X1095891Y645125D01*
G01X1097323Y653246D02*
X1095891Y645125D01*
G01D02*
X1096257Y644605D01*
G01X1098862Y644118D02*
X1097559Y643209D01*
G01D02*
X1095590Y643554D01*
G01X1096257Y644605D02*
X1097290Y644424D01*
G01X1098862Y644118D02*
X1097559Y643209D01*
G01X1097290Y644424D02*
X1097812Y644788D01*
G01X1100477Y653282D02*
X1098862Y644118D01*
G01X1097812Y644788D02*
X1099426Y653952D01*
G01X1100978Y644893D02*
X1102398Y652944D01*
G01X1103614Y653213D02*
X1102194Y645162D01*
G01X1101890Y643589D02*
X1100978Y644893D01*
G01X1102194Y645162D02*
X1102559Y644640D01*
G01X1105165Y644154D02*
X1103862Y643244D01*
G01D02*
X1101890Y643589D01*
G01X1102559Y644640D02*
X1103592Y644459D01*
G01X1105165Y644154D02*
X1103862Y643244D01*
G01X1103592Y644459D02*
X1104114Y644824D01*
G01X1106772Y653283D02*
X1105165Y644154D01*
G01X1104114Y644824D02*
X1105722Y653953D01*
G01X1107270Y644879D02*
X1108694Y652945D01*
G01X1109910Y653214D02*
X1108486Y645147D01*
G01X1108179Y643575D02*
X1107270Y644879D01*
G01X1108486Y645147D02*
X1108851Y644624D01*
G01X1111457Y644141D02*
X1110153Y643227D01*
G01D02*
X1108179Y643575D01*
G01X1108851Y644624D02*
X1109883Y644443D01*
G01X1111457Y644141D02*
X1110153Y643227D01*
G01X1109883Y644443D02*
X1110407Y644810D01*
G01X1113073Y653303D02*
X1111457Y644141D01*
G01X1110407Y644810D02*
X1112023Y653972D01*
G01X1113577Y644940D02*
X1114993Y652959D01*
G01X1116209Y653229D02*
X1114794Y645210D01*
G01X1114488Y643637D02*
X1113577Y644940D01*
G01X1114794Y645210D02*
X1115159Y644687D01*
G01X1117764Y644202D02*
X1116462Y643290D01*
G01D02*
X1114488Y643637D01*
G01X1115159Y644687D02*
X1116192Y644506D01*
G01X1117764Y644202D02*
X1116462Y643290D01*
G01X1116192Y644506D02*
X1116714Y644871D01*
G01X1119380Y653364D02*
X1117764Y644202D01*
G01X1116714Y644871D02*
X1118330Y654033D01*
G01X1119887Y645019D02*
X1121300Y653020D01*
G01X1122516Y653290D02*
X1121103Y645288D01*
G01X1120798Y643715D02*
X1119887Y645019D01*
G01X1121103Y645288D02*
X1121468Y644766D01*
G01X1124074Y644280D02*
X1122772Y643368D01*
G01D02*
X1120798Y643715D01*
G01X1121468Y644766D02*
X1122502Y644584D01*
G01X1124074Y644280D02*
X1122772Y643368D01*
G01X1122502Y644584D02*
X1123023Y644949D01*
G01X1125687Y653425D02*
X1124074Y644280D01*
G01X1123023Y644949D02*
X1124637Y654094D01*
G01X1126174Y644966D02*
X1127607Y653081D01*
G01X1128823Y653351D02*
X1127390Y645235D01*
G01X1127085Y643662D02*
X1126174Y644966D01*
G01X1127390Y645235D02*
X1127755Y644713D01*
G01X1130361Y644227D02*
X1129059Y643315D01*
G01D02*
X1127085Y643662D01*
G01X1127755Y644713D02*
X1128789Y644531D01*
G01X1130361Y644227D02*
X1129059Y643315D01*
G01X1128789Y644531D02*
X1129310Y644896D01*
G01X1131994Y653486D02*
X1130361Y644227D01*
G01X1129310Y644896D02*
X1130944Y654155D01*
G01X1132481Y645027D02*
X1133914Y653142D01*
G01X1135130Y653412D02*
X1133697Y645296D01*
G01X1133392Y643723D02*
X1132481Y645027D01*
G01X1133697Y645296D02*
X1134062Y644774D01*
G01X1136667Y644287D02*
X1135366Y643376D01*
G01D02*
X1133392Y643723D01*
G01X1134062Y644774D02*
X1135096Y644592D01*
G01X1136667Y644287D02*
X1135366Y643376D01*
G01X1135096Y644592D02*
X1135617Y644957D01*
G01X1138320Y653633D02*
X1136667Y644287D01*
G01X1135617Y644957D02*
X1137270Y654302D01*
G01X1138767Y644922D02*
X1140243Y653296D01*
G01X1141458Y653564D02*
X1139983Y645191D01*
G01X1139704Y643580D02*
X1138767Y644922D01*
G01X1139983Y645191D02*
X1140374Y644631D01*
G01X1142952Y644184D02*
X1141612Y643245D01*
G01D02*
X1139704Y643580D01*
G01X1140374Y644631D02*
X1141342Y644461D01*
G01X1142952Y644184D02*
X1141612Y643245D01*
G01X1141342Y644461D02*
X1141902Y644853D01*
G01X1144618Y653640D02*
X1142952Y644184D01*
G01X1141902Y644853D02*
X1143568Y654310D01*
G01X1145054Y644876D02*
X1146540Y653300D01*
G01X1147756Y653569D02*
X1146270Y645144D01*
G01X1145965Y643569D02*
X1145054Y644876D01*
G01X1146270Y645144D02*
X1146635Y644620D01*
G01X1149242Y644134D02*
X1147936Y643225D01*
G01D02*
X1145965Y643569D01*
G01X1146635Y644620D02*
X1147667Y644440D01*
G01X1149242Y644134D02*
X1147936Y643225D01*
G01X1147667Y644440D02*
X1148191Y644805D01*
G01X1150908Y653607D02*
X1149242Y644134D01*
G01X1148191Y644805D02*
X1149858Y654277D01*
G01X1151352Y644892D02*
X1152830Y653267D01*
G01X1154046Y653536D02*
X1152568Y645161D01*
G01X1152263Y643588D02*
X1151352Y644892D01*
G01X1152568Y645161D02*
X1152933Y644639D01*
G01X1155536Y644151D02*
X1154234Y643241D01*
G01D02*
X1152263Y643588D01*
G01X1152933Y644639D02*
X1153965Y644457D01*
G01X1155536Y644151D02*
X1154234Y643241D01*
G01X1153965Y644457D02*
X1154486Y644821D01*
G01X1157205Y653607D02*
X1155536Y644151D01*
G01X1154486Y644821D02*
X1156155Y654277D01*
G01D02*
X1157458Y655186D01*
G01X1156155Y654277D02*
X1157458Y655186D01*
G01X1153135Y654840D02*
X1154046Y653536D01*
G01X1152830Y653267D02*
X1152465Y653789D01*
G01X1149858Y654277D02*
X1151161Y655186D01*
G01D02*
X1153135Y654840D01*
G01X1152465Y653789D02*
X1151430Y653971D01*
G01X1149858Y654277D02*
X1151161Y655186D01*
G01X1151430Y653971D02*
X1150908Y653607D01*
G01X1146845Y654873D02*
X1147756Y653569D01*
G01X1146540Y653300D02*
X1146175Y653822D01*
G01X1143568Y654310D02*
X1144871Y655219D01*
G01D02*
X1146845Y654873D01*
G01X1146175Y653822D02*
X1145140Y654004D01*
G01X1143568Y654310D02*
X1144871Y655219D01*
G01X1145140Y654004D02*
X1144618Y653640D01*
G01X1140550Y654869D02*
X1141458Y653564D01*
G01X1140243Y653296D02*
X1139879Y653819D01*
G01X1137270Y654302D02*
X1138575Y655217D01*
G01D02*
X1140550Y654869D01*
G01X1139879Y653819D02*
X1138845Y654001D01*
G01X1137270Y654302D02*
X1138575Y655217D01*
G01X1138845Y654001D02*
X1138320Y653633D01*
G01X1134217Y654716D02*
X1135130Y653412D01*
G01X1133914Y653142D02*
X1133547Y653666D01*
G01X1130944Y654155D02*
X1132244Y655065D01*
G01D02*
X1134217Y654716D01*
G01X1133547Y653666D02*
X1132513Y653849D01*
G01X1130944Y654155D02*
X1132244Y655065D01*
G01X1132513Y653849D02*
X1131994Y653486D01*
G01X1127910Y654655D02*
X1128823Y653351D01*
G01X1127607Y653081D02*
X1127240Y653605D01*
G01X1124637Y654094D02*
X1125937Y655004D01*
G01D02*
X1127910Y654655D01*
G01X1127240Y653605D02*
X1126206Y653788D01*
G01X1124637Y654094D02*
X1125937Y655004D01*
G01X1126206Y653788D02*
X1125687Y653425D01*
G01X1121603Y654594D02*
X1122516Y653290D01*
G01X1121300Y653020D02*
X1120933Y653544D01*
G01X1118330Y654033D02*
X1119630Y654943D01*
G01D02*
X1121603Y654594D01*
G01X1120933Y653544D02*
X1119899Y653727D01*
G01X1118330Y654033D02*
X1119630Y654943D01*
G01X1119899Y653727D02*
X1119380Y653364D01*
G01X1115296Y654533D02*
X1116209Y653229D01*
G01X1114993Y652959D02*
X1114626Y653483D01*
G01X1112023Y653972D02*
X1113323Y654882D01*
G01D02*
X1115296Y654533D01*
G01X1114626Y653483D02*
X1113592Y653666D01*
G01X1112023Y653972D02*
X1113323Y654882D01*
G01X1113592Y653666D02*
X1113073Y653303D01*
G01X1109000Y654517D02*
X1109910Y653214D01*
G01X1108694Y652945D02*
X1108330Y653466D01*
G01X1105722Y653953D02*
X1107026Y654863D01*
G01D02*
X1109000Y654517D01*
G01X1108330Y653466D02*
X1107295Y653648D01*
G01X1105722Y653953D02*
X1107026Y654863D01*
G01X1107295Y653648D02*
X1106772Y653283D01*
G01X1102704Y654516D02*
X1103614Y653213D01*
G01X1102398Y652944D02*
X1102034Y653465D01*
G01X1099426Y653952D02*
X1100730Y654862D01*
G01D02*
X1102704Y654516D01*
G01X1102034Y653465D02*
X1101000Y653647D01*
G01X1099426Y653952D02*
X1100730Y654862D01*
G01X1101000Y653647D02*
X1100477Y653282D01*
G01X1096413Y654549D02*
X1097323Y653246D01*
G01X1096107Y652977D02*
X1095743Y653498D01*
G01X1096107Y652977D02*
X1095743Y653498D01*
G01X1096413Y654549D02*
X1097323Y653246D01*
G01X1102034Y653465D02*
X1101000Y653647D01*
G01D02*
X1100477Y653282D01*
G01X1099426Y653952D02*
X1100730Y654862D01*
G01X1102034Y653465D02*
X1101000Y653647D01*
G01X1100730Y654862D02*
X1102704Y654516D01*
G01X1102398Y652944D02*
X1102034Y653465D01*
G01X1102704Y654516D02*
X1103614Y653213D01*
G01X1108330Y653466D02*
X1107295Y653648D01*
G01D02*
X1106772Y653283D01*
G01X1105722Y653953D02*
X1107026Y654863D01*
G01X1108330Y653466D02*
X1107295Y653648D01*
G01X1107026Y654863D02*
X1109000Y654517D01*
G01X1108694Y652945D02*
X1108330Y653466D01*
G01X1109000Y654517D02*
X1109910Y653214D01*
G01X1114626Y653483D02*
X1113592Y653666D01*
G01D02*
X1113073Y653303D01*
G01X1112023Y653972D02*
X1113323Y654882D01*
G01X1114626Y653483D02*
X1113592Y653666D01*
G01X1113323Y654882D02*
X1115296Y654533D01*
G01X1114993Y652959D02*
X1114626Y653483D01*
G01X1115296Y654533D02*
X1116209Y653229D01*
G01X1120933Y653544D02*
X1119899Y653727D01*
G01D02*
X1119380Y653364D01*
G01X1118330Y654033D02*
X1119630Y654943D01*
G01X1120933Y653544D02*
X1119899Y653727D01*
G01X1119630Y654943D02*
X1121603Y654594D01*
G01X1121300Y653020D02*
X1120933Y653544D01*
G01X1121603Y654594D02*
X1122516Y653290D01*
G01X1127240Y653605D02*
X1126206Y653788D01*
G01D02*
X1125687Y653425D01*
G01X1124637Y654094D02*
X1125937Y655004D01*
G01X1127240Y653605D02*
X1126206Y653788D01*
G01X1125937Y655004D02*
X1127910Y654655D01*
G01X1127607Y653081D02*
X1127240Y653605D01*
G01X1127910Y654655D02*
X1128823Y653351D01*
G01X1133547Y653666D02*
X1132513Y653849D01*
G01D02*
X1131994Y653486D01*
G01X1130944Y654155D02*
X1132244Y655065D01*
G01X1133547Y653666D02*
X1132513Y653849D01*
G01X1132244Y655065D02*
X1134217Y654716D01*
G01X1133914Y653142D02*
X1133547Y653666D01*
G01X1134217Y654716D02*
X1135130Y653412D01*
G01X1139879Y653819D02*
X1138845Y654001D01*
G01D02*
X1138320Y653633D01*
G01X1137270Y654302D02*
X1138575Y655217D01*
G01X1139879Y653819D02*
X1138845Y654001D01*
G01X1138575Y655217D02*
X1140550Y654869D01*
G01X1140243Y653296D02*
X1139879Y653819D01*
G01X1140550Y654869D02*
X1141458Y653564D01*
G01X1146175Y653822D02*
X1145140Y654004D01*
G01D02*
X1144618Y653640D01*
G01X1143568Y654310D02*
X1144871Y655219D01*
G01X1146175Y653822D02*
X1145140Y654004D01*
G01X1144871Y655219D02*
X1146845Y654873D01*
G01X1146540Y653300D02*
X1146175Y653822D01*
G01X1146845Y654873D02*
X1147756Y653569D01*
G01X1152465Y653789D02*
X1151430Y653971D01*
G01D02*
X1150908Y653607D01*
G01X1149858Y654277D02*
X1151161Y655186D01*
G01X1152465Y653789D02*
X1151430Y653971D01*
G01X1151161Y655186D02*
X1153135Y654840D01*
G01X1152830Y653267D02*
X1152465Y653789D01*
G01X1153135Y654840D02*
X1154046Y653536D01*
G01X1156155Y654277D02*
X1157458Y655186D01*
G01X1225205Y397890D02*
X1215213Y392050D01*
G01D02*
X1213777D01*
G01X1225994Y397019D02*
X1215525Y390900D01*
G01X1215213Y392050D02*
X1213777D01*
G01X1215525Y390900D02*
X1213777D01*
G01X1228074Y394449D02*
X1216834Y387880D01*
G01X1228074Y394449D02*
X1216834Y387880D01*
G01X1227285Y395320D02*
X1216522Y389030D01*
G01X1216834Y387880D02*
X1209621D01*
G01X1216522Y389030D02*
X1209534D01*
G01X1209870Y396971D02*
X1261528Y433930D01*
G01X1260700Y434752D02*
X1209500Y398121D01*
G01X1205296Y396971D02*
X1209870D01*
G01X1209500Y398121D02*
X1205296D01*
G01X1259260Y437462D02*
X1209577Y401916D01*
G01X1260087Y436639D02*
X1209947Y400766D01*
G01X1209577Y401916D02*
X1204732D01*
G01X1209947Y400766D02*
X1204732D01*
G01X1232514Y388074D02*
X1217972Y379340D01*
G01X1231720Y388940D02*
X1217653Y380490D01*
G01X1217972Y379340D02*
X1210128D01*
G01X1217653Y380490D02*
X1210128D01*
G01X1230514Y391173D02*
X1217342Y383266D01*
G01X1229723Y392044D02*
X1217023Y384416D01*
G01X1217342Y383266D02*
X1212490D01*
G01X1217023Y384416D02*
X1212490D01*
G01X1225994Y397019D02*
X1215525Y390900D01*
G01X1225205Y397890D02*
X1215213Y392050D01*
G01X1225994Y397019D02*
X1215525Y390900D01*
G01D02*
X1213777D01*
G01X1215213Y392050D02*
X1213777D01*
G01X1227285Y395320D02*
X1216522Y389030D01*
G01X1228074Y394449D02*
X1216834Y387880D01*
G01X1216522Y389030D02*
X1209534D01*
G01X1216834Y387880D02*
X1209621D01*
G01X1209500Y398121D02*
X1205296D01*
G01Y396971D02*
X1209870D01*
G01X1260700Y434752D02*
X1209500Y398121D01*
G01X1209870Y396971D02*
X1261528Y433930D01*
G01X1260087Y436639D02*
X1209947Y400766D01*
G01X1259260Y437462D02*
X1209577Y401916D01*
G01X1209947Y400766D02*
X1204732D01*
G01X1209577Y401916D02*
X1204732D01*
G01X1231720Y388940D02*
X1217653Y380490D01*
G01X1232514Y388074D02*
X1217972Y379340D01*
G01X1217653Y380490D02*
X1210128D01*
G01X1217972Y379340D02*
X1210128D01*
G01X1229723Y392044D02*
X1217023Y384416D01*
G01X1230514Y391173D02*
X1217342Y383266D01*
G01X1217023Y384416D02*
X1212490D01*
G01X1217342Y383266D02*
X1212490D01*
G01X1202637Y352550D02*
X1204990D01*
G01X1202637Y353700D02*
X1205297D01*
G01X1204990Y352550D02*
X1210671Y349294D01*
G01X1205297Y353700D02*
X1211090Y350380D01*
G01X1210671Y349294D02*
X1225136Y346124D01*
G01X1211090Y350380D02*
X1225645Y347190D01*
G01X1224878Y351444D02*
X1216212Y354070D01*
G01X1225424Y352481D02*
X1216383Y355220D01*
G01X1216212Y354070D02*
X1214487D01*
G01X1216383Y355220D02*
X1214487D01*
G01X1213674Y359100D02*
X1225944Y355295D01*
G01X1226493Y356329D02*
X1213850Y360250D01*
G01X1211497Y359100D02*
X1213674D01*
G01X1213850Y360250D02*
X1211497D01*
G01X1228881Y357490D02*
X1213831Y362155D01*
G01X1229430Y358524D02*
X1214016Y363302D01*
G01X1213831Y362155D02*
X1204187Y362171D01*
G01X1214007Y363305D02*
X1213833D01*
G01X1213831Y362155D02*
X1204187Y362171D01*
G01X1213833Y363305D02*
X1204665Y363321D01*
G01X1204187Y362171D02*
X1200588Y365771D01*
G01X1204665Y363321D02*
X1201065Y366921D01*
G01X1200588Y365771D02*
X1200187D01*
G01X1201065Y366921D02*
X1200187D01*
G01X1230528Y360185D02*
X1215702Y364779D01*
G01X1231077Y361219D02*
X1215877Y365929D01*
G01X1215702Y364779D02*
X1207479D01*
G01X1215877Y365929D02*
X1207479D01*
G01X1216876Y367313D02*
X1212440D01*
G01Y368463D02*
X1217051D01*
G01X1233574Y362138D02*
X1216876Y367313D01*
G01X1217051Y368463D02*
X1234123Y363172D01*
G01X1214247Y371622D02*
X1212007D01*
G01Y372772D02*
X1214422D01*
G01X1235226Y365111D02*
X1214247Y371622D01*
G01X1214422Y372772D02*
X1235775Y366145D01*
G01X1211174Y375764D02*
X1213314D01*
G01X1211174Y376914D02*
X1213489D01*
G01X1213314Y375764D02*
X1235404Y368885D01*
G01X1213489Y376914D02*
X1235954Y369919D01*
G01X1202637Y353700D02*
X1205297D01*
G01X1202637Y352550D02*
X1204990D01*
G01X1205297Y353700D02*
X1211090Y350380D01*
G01X1204990Y352550D02*
X1210671Y349294D01*
G01X1211090Y350380D02*
X1225645Y347190D01*
G01X1210671Y349294D02*
X1225136Y346124D01*
G01X1225424Y352481D02*
X1216383Y355220D01*
G01X1224878Y351444D02*
X1216212Y354070D01*
G01X1216383Y355220D02*
X1214487D01*
G01X1216212Y354070D02*
X1214487D01*
G01X1213850Y360250D02*
X1211497D01*
G01Y359100D02*
X1213674D01*
G01X1226493Y356329D02*
X1213850Y360250D01*
G01X1213674Y359100D02*
X1225944Y355295D01*
G01X1229430Y358524D02*
X1214016Y363302D01*
G01X1228881Y357490D02*
X1213831Y362155D01*
G01X1214007Y363305D02*
X1213833D01*
G01D02*
X1204665Y363321D01*
G01X1213831Y362155D02*
X1204187Y362171D01*
G01X1204665Y363321D02*
X1201065Y366921D01*
G01X1204187Y362171D02*
X1200588Y365771D01*
G01X1201065Y366921D02*
X1200187D01*
G01X1200588Y365771D02*
X1200187D01*
G01X1231077Y361219D02*
X1215877Y365929D01*
G01X1230528Y360185D02*
X1215702Y364779D01*
G01X1215877Y365929D02*
X1207479D01*
G01X1215702Y364779D02*
X1207479D01*
G01X1217051Y368463D02*
X1234123Y363172D01*
G01X1233574Y362138D02*
X1216876Y367313D01*
G01X1212440Y368463D02*
X1217051D01*
G01X1216876Y367313D02*
X1212440D01*
G01X1214422Y372772D02*
X1235775Y366145D01*
G01X1235226Y365111D02*
X1214247Y371622D01*
G01X1212007Y372772D02*
X1214422D01*
G01X1214247Y371622D02*
X1212007D01*
G01X1211174Y376914D02*
X1213489D01*
G01X1211174Y375764D02*
X1213314D01*
G01X1213489Y376914D02*
X1235954Y369919D01*
G01X1213314Y375764D02*
X1235404Y368885D01*
G01X1217201Y416877D02*
X1248032Y437488D01*
G01X1217841Y415921D02*
X1249027Y436769D01*
G01X1259209Y442114D02*
X1209679Y406675D01*
G01X1260039Y441293D02*
X1210049Y405525D01*
G01X1209679Y406675D02*
X1205798D01*
G01X1210049Y405525D02*
X1205798D01*
G01X1217841Y415921D02*
X1249027Y436769D01*
G01X1217201Y416877D02*
X1248032Y437488D01*
G01X1260039Y441293D02*
X1210049Y405525D01*
G01X1259209Y442114D02*
X1209679Y406675D01*
G01X1210049Y405525D02*
X1205798D01*
G01X1209679Y406675D02*
X1205798D01*
G01X1201944Y649781D02*
X1203685D01*
G01Y648631D02*
X1201897D01*
G01X1197489Y650138D02*
X1201944Y649781D01*
G01X1201897Y648631D02*
X1197622Y648973D01*
G01X1193818Y648971D02*
X1197489Y650138D01*
G01X1197622Y648973D02*
X1194518Y647986D01*
G01X1192837Y647663D02*
X1193818Y648971D01*
G01X1194518Y647986D02*
X1193896Y647156D01*
G01X1192593Y646702D02*
X1192837Y647663D01*
G01X1193896Y647156D02*
X1193719Y646460D01*
G01X1192257Y644792D02*
X1192593Y646702D01*
G01X1193719Y646460D02*
X1193308Y644123D01*
G01X1190702Y644609D02*
X1191736Y644427D01*
G01D02*
X1192257Y644792D01*
G01X1193308Y644123D02*
X1192006Y643211D01*
G01X1190702Y644609D02*
X1191736Y644427D01*
G01X1192006Y643211D02*
X1190032Y643558D01*
G01X1190337Y645131D02*
X1190702Y644609D01*
G01X1190032Y643558D02*
X1189121Y644862D01*
G01X1191821Y653538D02*
X1190337Y645131D01*
G01X1189121Y644862D02*
X1190605Y653268D01*
G01X1185950Y644731D02*
X1187635Y654281D01*
G01X1188685Y653612D02*
X1187001Y644062D01*
G01X1184394Y644546D02*
X1185427Y644364D01*
G01D02*
X1185950Y644731D01*
G01X1187001Y644062D02*
X1185697Y643148D01*
G01X1184394Y644546D02*
X1185427Y644364D01*
G01X1185697Y643148D02*
X1183723Y643496D01*
G01X1184030Y645069D02*
X1184394Y644546D01*
G01X1183723Y643496D02*
X1182814Y644801D01*
G01X1185522Y653523D02*
X1184030Y645069D01*
G01X1182814Y644801D02*
X1184306Y653254D01*
G01X1179655Y644728D02*
X1181334Y654262D01*
G01X1182384Y653592D02*
X1180706Y644058D01*
G01X1178100Y644544D02*
X1179133Y644363D01*
G01D02*
X1179655Y644728D01*
G01X1180706Y644058D02*
X1179403Y643148D01*
G01X1178100Y644544D02*
X1179133Y644363D01*
G01X1179403Y643148D02*
X1177431Y643493D01*
G01X1177735Y645066D02*
X1178100Y644544D01*
G01X1177431Y643493D02*
X1176519Y644797D01*
G01X1179226Y653522D02*
X1177735Y645066D01*
G01X1176519Y644797D02*
X1178010Y653253D01*
G01X1173356Y644709D02*
X1175038Y654261D01*
G01X1176089Y653591D02*
X1174406Y644039D01*
G01X1171801Y644526D02*
X1172834Y644345D01*
G01D02*
X1173356Y644709D01*
G01X1174406Y644039D02*
X1173103Y643130D01*
G01X1171801Y644526D02*
X1172834Y644345D01*
G01X1173103Y643130D02*
X1171134Y643475D01*
G01X1171435Y645046D02*
X1171801Y644526D01*
G01X1171134Y643475D02*
X1170219Y644775D01*
G01X1172935Y653555D02*
X1171435Y645046D01*
G01X1170219Y644775D02*
X1171719Y653286D01*
G01X1167060Y644712D02*
X1168751Y654294D01*
G01X1169801Y653625D02*
X1168111Y644044D01*
G01X1165503Y644527D02*
X1166537Y644344D01*
G01D02*
X1167060Y644712D01*
G01X1168111Y644044D02*
X1166808Y643128D01*
G01X1165503Y644527D02*
X1166537Y644344D01*
G01X1166808Y643128D02*
X1164834Y643477D01*
G01X1165138Y645048D02*
X1165503Y644527D01*
G01X1164834Y643477D02*
X1163922Y644778D01*
G01X1166638Y653556D02*
X1165138Y645048D01*
G01X1163922Y644778D02*
X1165422Y653285D01*
G01X1160784Y644825D02*
X1162453Y654295D01*
G01X1163503Y653625D02*
X1161835Y644156D01*
G01X1159228Y644639D02*
X1160261Y644458D01*
G01D02*
X1160784Y644825D01*
G01X1161835Y644156D02*
X1160532Y643242D01*
G01X1159228Y644639D02*
X1160261Y644458D01*
G01X1160532Y643242D02*
X1158558Y643588D01*
G01X1158864Y645161D02*
X1159228Y644639D01*
G01X1158558Y643588D02*
X1157648Y644893D01*
G01X1160341Y653538D02*
X1158864Y645161D01*
G01X1157648Y644893D02*
X1159125Y653269D01*
G01X1157648Y644893D02*
X1159125Y653269D01*
G01X1160341Y653538D02*
X1158864Y645161D01*
G01X1158558Y643588D02*
X1157648Y644893D01*
G01X1158864Y645161D02*
X1159228Y644639D01*
G01X1161835Y644156D02*
X1160532Y643242D01*
G01D02*
X1158558Y643588D01*
G01X1159228Y644639D02*
X1160261Y644458D01*
G01X1161835Y644156D02*
X1160532Y643242D01*
G01X1160261Y644458D02*
X1160784Y644825D01*
G01X1163503Y653625D02*
X1161835Y644156D01*
G01X1160784Y644825D02*
X1162453Y654295D01*
G01X1163922Y644778D02*
X1165422Y653285D01*
G01X1166638Y653556D02*
X1165138Y645048D01*
G01X1164834Y643477D02*
X1163922Y644778D01*
G01X1165138Y645048D02*
X1165503Y644527D01*
G01X1168111Y644044D02*
X1166808Y643128D01*
G01D02*
X1164834Y643477D01*
G01X1165503Y644527D02*
X1166537Y644344D01*
G01X1168111Y644044D02*
X1166808Y643128D01*
G01X1166537Y644344D02*
X1167060Y644712D01*
G01X1169801Y653625D02*
X1168111Y644044D01*
G01X1167060Y644712D02*
X1168751Y654294D01*
G01X1170219Y644775D02*
X1171719Y653286D01*
G01X1172935Y653555D02*
X1171435Y645046D01*
G01X1171134Y643475D02*
X1170219Y644775D01*
G01X1171435Y645046D02*
X1171801Y644526D01*
G01X1174406Y644039D02*
X1173103Y643130D01*
G01D02*
X1171134Y643475D01*
G01X1171801Y644526D02*
X1172834Y644345D01*
G01X1174406Y644039D02*
X1173103Y643130D01*
G01X1172834Y644345D02*
X1173356Y644709D01*
G01X1176089Y653591D02*
X1174406Y644039D01*
G01X1173356Y644709D02*
X1175038Y654261D01*
G01X1176519Y644797D02*
X1178010Y653253D01*
G01X1179226Y653522D02*
X1177735Y645066D01*
G01X1177431Y643493D02*
X1176519Y644797D01*
G01X1177735Y645066D02*
X1178100Y644544D01*
G01X1180706Y644058D02*
X1179403Y643148D01*
G01D02*
X1177431Y643493D01*
G01X1178100Y644544D02*
X1179133Y644363D01*
G01X1180706Y644058D02*
X1179403Y643148D01*
G01X1179133Y644363D02*
X1179655Y644728D01*
G01X1182384Y653592D02*
X1180706Y644058D01*
G01X1179655Y644728D02*
X1181334Y654262D01*
G01X1182814Y644801D02*
X1184306Y653254D01*
G01X1185522Y653523D02*
X1184030Y645069D01*
G01X1183723Y643496D02*
X1182814Y644801D01*
G01X1184030Y645069D02*
X1184394Y644546D01*
G01X1187001Y644062D02*
X1185697Y643148D01*
G01D02*
X1183723Y643496D01*
G01X1184394Y644546D02*
X1185427Y644364D01*
G01X1187001Y644062D02*
X1185697Y643148D01*
G01X1185427Y644364D02*
X1185950Y644731D01*
G01X1188685Y653612D02*
X1187001Y644062D01*
G01X1185950Y644731D02*
X1187635Y654281D01*
G01X1189121Y644862D02*
X1190605Y653268D01*
G01X1191821Y653538D02*
X1190337Y645131D01*
G01X1190032Y643558D02*
X1189121Y644862D01*
G01X1190337Y645131D02*
X1190702Y644609D01*
G01X1193308Y644123D02*
X1192006Y643211D01*
G01D02*
X1190032Y643558D01*
G01X1190702Y644609D02*
X1191736Y644427D01*
G01X1193308Y644123D02*
X1192006Y643211D01*
G01X1191736Y644427D02*
X1192257Y644792D01*
G01X1193719Y646460D02*
X1193308Y644123D01*
G01X1192257Y644792D02*
X1192593Y646702D01*
G01X1193896Y647156D02*
X1193719Y646460D01*
G01X1192593Y646702D02*
X1192837Y647663D01*
G01X1194518Y647986D02*
X1193896Y647156D01*
G01X1192837Y647663D02*
X1193818Y648971D01*
G01X1197622Y648973D02*
X1194518Y647986D01*
G01X1193818Y648971D02*
X1197489Y650138D01*
G01X1201897Y648631D02*
X1197622Y648973D01*
G01X1197489Y650138D02*
X1201944Y649781D01*
G01X1203685Y648631D02*
X1201897D01*
G01X1201944Y649781D02*
X1203685D01*
G01X1190908Y654842D02*
X1191821Y653538D01*
G01X1190605Y653268D02*
X1190238Y653792D01*
G01X1187635Y654281D02*
X1188935Y655191D01*
G01D02*
X1190908Y654842D01*
G01X1190238Y653792D02*
X1189204Y653975D01*
G01X1187635Y654281D02*
X1188935Y655191D01*
G01X1189204Y653975D02*
X1188685Y653612D01*
G01X1184612Y654826D02*
X1185522Y653523D01*
G01X1184306Y653254D02*
X1183942Y653775D01*
G01X1181334Y654262D02*
X1182638Y655172D01*
G01D02*
X1184612Y654826D01*
G01X1183942Y653775D02*
X1182907Y653957D01*
G01X1181334Y654262D02*
X1182638Y655172D01*
G01X1182907Y653957D02*
X1182384Y653592D01*
G01X1178316Y654825D02*
X1179226Y653522D01*
G01X1178010Y653253D02*
X1177646Y653774D01*
G01X1175038Y654261D02*
X1176342Y655171D01*
G01D02*
X1178316Y654825D01*
G01X1177646Y653774D02*
X1176612Y653956D01*
G01X1175038Y654261D02*
X1176342Y655171D01*
G01X1176612Y653956D02*
X1176089Y653591D01*
G01X1172025Y654858D02*
X1172935Y653555D01*
G01X1171719Y653286D02*
X1171355Y653807D01*
G01X1168751Y654294D02*
X1170051Y655205D01*
G01D02*
X1172025Y654858D01*
G01X1171355Y653807D02*
X1170321Y653989D01*
G01X1168751Y654294D02*
X1170051Y655205D01*
G01X1170321Y653989D02*
X1169801Y653625D01*
G01X1165729Y654857D02*
X1166638Y653556D01*
G01X1165422Y653285D02*
X1165059Y653807D01*
G01X1162453Y654295D02*
X1163756Y655205D01*
G01D02*
X1165729Y654857D01*
G01X1165059Y653807D02*
X1164025Y653990D01*
G01X1162453Y654295D02*
X1163756Y655205D01*
G01X1164025Y653990D02*
X1163503Y653625D01*
G01X1159431Y654841D02*
X1160341Y653538D01*
G01X1159125Y653269D02*
X1158761Y653790D01*
G01X1157458Y655186D02*
X1159431Y654841D01*
G01X1158761Y653790D02*
X1157727Y653971D01*
G01D02*
X1157205Y653607D01*
G01X1158761Y653790D02*
X1157727Y653971D01*
G01D02*
X1157205Y653607D01*
G01X1158761Y653790D02*
X1157727Y653971D01*
G01X1157458Y655186D02*
X1159431Y654841D01*
G01X1159125Y653269D02*
X1158761Y653790D01*
G01X1159431Y654841D02*
X1160341Y653538D01*
G01X1165059Y653807D02*
X1164025Y653990D01*
G01D02*
X1163503Y653625D01*
G01X1162453Y654295D02*
X1163756Y655205D01*
G01X1165059Y653807D02*
X1164025Y653990D01*
G01X1163756Y655205D02*
X1165729Y654857D01*
G01X1165422Y653285D02*
X1165059Y653807D01*
G01X1165729Y654857D02*
X1166638Y653556D01*
G01X1171355Y653807D02*
X1170321Y653989D01*
G01D02*
X1169801Y653625D01*
G01X1168751Y654294D02*
X1170051Y655205D01*
G01X1171355Y653807D02*
X1170321Y653989D01*
G01X1170051Y655205D02*
X1172025Y654858D01*
G01X1171719Y653286D02*
X1171355Y653807D01*
G01X1172025Y654858D02*
X1172935Y653555D01*
G01X1177646Y653774D02*
X1176612Y653956D01*
G01D02*
X1176089Y653591D01*
G01X1175038Y654261D02*
X1176342Y655171D01*
G01X1177646Y653774D02*
X1176612Y653956D01*
G01X1176342Y655171D02*
X1178316Y654825D01*
G01X1178010Y653253D02*
X1177646Y653774D01*
G01X1178316Y654825D02*
X1179226Y653522D01*
G01X1183942Y653775D02*
X1182907Y653957D01*
G01D02*
X1182384Y653592D01*
G01X1181334Y654262D02*
X1182638Y655172D01*
G01X1183942Y653775D02*
X1182907Y653957D01*
G01X1182638Y655172D02*
X1184612Y654826D01*
G01X1184306Y653254D02*
X1183942Y653775D01*
G01X1184612Y654826D02*
X1185522Y653523D01*
G01X1190238Y653792D02*
X1189204Y653975D01*
G01D02*
X1188685Y653612D01*
G01X1187635Y654281D02*
X1188935Y655191D01*
G01X1190238Y653792D02*
X1189204Y653975D01*
G01X1188935Y655191D02*
X1190908Y654842D01*
G01X1190605Y653268D02*
X1190238Y653792D01*
G01X1190908Y654842D02*
X1191821Y653538D01*
G01X1282131Y146723D02*
X1278657Y143249D01*
G01X1282608Y145573D02*
X1279134Y142099D01*
G01X1278657Y143249D02*
X1276563D01*
G01X1279134Y142099D02*
X1276086D01*
G01X1276563Y143249D02*
X1275251Y144561D01*
G01X1276086Y142099D02*
X1274774Y143411D01*
G01X1275251Y144561D02*
X1271739D01*
G01X1274774Y143411D02*
X1271262D01*
G01X1271739Y144561D02*
X1270773Y145527D01*
G01X1271262Y143411D02*
X1270296Y144377D01*
G01X1270773Y145527D02*
X1265127D01*
G01X1270296Y144377D02*
X1265604D01*
G01X1265127Y145527D02*
X1256323Y136723D01*
G01X1265604Y144377D02*
X1257473Y136246D01*
G01X1256323Y136723D02*
Y123775D01*
G01X1257473Y136246D02*
Y134896D01*
G01X1256323Y136723D02*
Y123775D01*
G01X1257473Y132246D02*
Y130896D01*
G01X1256323Y136723D02*
Y123775D01*
G01X1257473Y128246D02*
Y126896D01*
G01X1256323Y136723D02*
Y123775D01*
G01X1257473Y124246D02*
Y123298D01*
G01X1256323Y123775D02*
X1252477Y119929D01*
G01X1257473Y123298D02*
X1253627Y119452D01*
G01X1252477Y119929D02*
Y114323D01*
G01X1253627Y119452D02*
Y114800D01*
G01X1252477Y114323D02*
X1253600Y113200D01*
G01X1253627Y114800D02*
X1254077Y114350D01*
G01X1253600Y113200D02*
X1254900D01*
G01X1254077Y114350D02*
X1254900D01*
G01X1282608Y145573D02*
X1279134Y142099D01*
G01X1282131Y146723D02*
X1278657Y143249D01*
G01X1279134Y142099D02*
X1276086D01*
G01X1278657Y143249D02*
X1276563D01*
G01X1276086Y142099D02*
X1274774Y143411D01*
G01X1276563Y143249D02*
X1275251Y144561D01*
G01X1274774Y143411D02*
X1271262D01*
G01X1275251Y144561D02*
X1271739D01*
G01X1271262Y143411D02*
X1270296Y144377D01*
G01X1271739Y144561D02*
X1270773Y145527D01*
G01X1270296Y144377D02*
X1265604D01*
G01X1270773Y145527D02*
X1265127D01*
G01X1265604Y144377D02*
X1257473Y136246D01*
G01X1265127Y145527D02*
X1256323Y136723D01*
G01X1257473Y136246D02*
Y134896D01*
G01Y132246D02*
Y130896D01*
G01Y128246D02*
Y126896D01*
G01Y124246D02*
Y123298D01*
G01X1256323Y136723D02*
Y123775D01*
G01X1257473Y123298D02*
X1253627Y119452D01*
G01X1256323Y123775D02*
X1252477Y119929D01*
G01X1253627Y119452D02*
Y114800D01*
G01X1252477Y119929D02*
Y114323D01*
G01X1253627Y114800D02*
X1254077Y114350D01*
G01X1252477Y114323D02*
X1253600Y113200D01*
G01X1254077Y114350D02*
X1254900D01*
G01X1253600Y113200D02*
X1254900D01*
G01X1259627Y279507D02*
X1259976Y278151D01*
G01X1260649Y275536D02*
X1260998Y274180D01*
G01X1248010Y329281D02*
X1262048Y274718D01*
G01X1260998Y274180D02*
X1285266Y245053D01*
G01X1262048Y274718D02*
X1285300Y246811D01*
G01X1260998Y274180D02*
X1285266Y245053D01*
G01X1285801Y248823D02*
X1265122Y273643D01*
G01X1286522Y249756D02*
X1266172Y274181D01*
G01X1265122Y273643D02*
X1264773Y274999D01*
G01X1264100Y277614D02*
X1263751Y278970D01*
G01X1266172Y274181D02*
X1251360Y331712D01*
G01X1269985Y271714D02*
X1286778Y251558D01*
G01X1287499Y252491D02*
X1271035Y272252D01*
G01X1268289Y278306D02*
X1268625Y276999D01*
G01X1269286Y274432D02*
X1269985Y271714D01*
G01X1271035Y272252D02*
X1255344Y333229D01*
G01X1288155Y253977D02*
X1273947Y271031D01*
G01X1288876Y254910D02*
X1274997Y271569D01*
G01X1273947Y271031D02*
X1270482Y284485D01*
G01X1274997Y271569D02*
X1258623Y335149D01*
G01X1289539Y256420D02*
X1277750Y270570D01*
G01X1290260Y257353D02*
X1278800Y271108D01*
G01X1277750Y270570D02*
X1277401Y271926D01*
G01X1276728Y274541D02*
X1276379Y275896D01*
G01X1275706Y278511D02*
X1275357Y279867D01*
G01X1278800Y271108D02*
X1261979Y336473D01*
G01X1281496Y270384D02*
X1277565Y285651D01*
G01X1248010Y329281D02*
X1262048Y274718D01*
G01X1248010Y329281D02*
X1262048Y274718D01*
G01X1248010Y329281D02*
X1262048Y274718D01*
G01X1259627Y279507D02*
X1259976Y278151D01*
G01X1248010Y329281D02*
X1262048Y274718D01*
G01X1260649Y275536D02*
X1260998Y274180D01*
G01X1262048Y274718D02*
X1285300Y246811D01*
G01X1260998Y274180D02*
X1285266Y245053D01*
G01X1286522Y249756D02*
X1266172Y274181D01*
G01X1285801Y248823D02*
X1265122Y273643D01*
G01X1266172Y274181D02*
X1251360Y331712D01*
G01X1265122Y273643D02*
X1264773Y274999D01*
G01X1266172Y274181D02*
X1251360Y331712D01*
G01X1264100Y277614D02*
X1263751Y278970D01*
G01X1266172Y274181D02*
X1251360Y331712D01*
G01X1266172Y274181D02*
X1251360Y331712D01*
G01X1266172Y274181D02*
X1251360Y331712D01*
G01X1271035Y272252D02*
X1255344Y333229D01*
G01X1271035Y272252D02*
X1255344Y333229D01*
G01X1271035Y272252D02*
X1255344Y333229D01*
G01X1268289Y278306D02*
X1268625Y276999D01*
G01X1271035Y272252D02*
X1255344Y333229D01*
G01X1269286Y274432D02*
X1269985Y271714D01*
G01X1287499Y252491D02*
X1271035Y272252D01*
G01X1269985Y271714D02*
X1286778Y251558D01*
G01X1288876Y254910D02*
X1274997Y271569D01*
G01X1288155Y253977D02*
X1273947Y271031D01*
G01X1274997Y271569D02*
X1258623Y335149D01*
G01X1273947Y271031D02*
X1270482Y284485D01*
G01X1274997Y271569D02*
X1258623Y335149D01*
G01X1274997Y271569D02*
X1258623Y335149D01*
G01X1274997Y271569D02*
X1258623Y335149D01*
G01X1290260Y257353D02*
X1278800Y271108D01*
G01X1289539Y256420D02*
X1277750Y270570D01*
G01X1278800Y271108D02*
X1261979Y336473D01*
G01X1277750Y270570D02*
X1277401Y271926D01*
G01X1278800Y271108D02*
X1261979Y336473D01*
G01X1276728Y274541D02*
X1276379Y275896D01*
G01X1278800Y271108D02*
X1261979Y336473D01*
G01X1275706Y278511D02*
X1275357Y279867D01*
G01X1278800Y271108D02*
X1261979Y336473D01*
G01X1278800Y271108D02*
X1261979Y336473D01*
G01X1281496Y270384D02*
X1277565Y285651D01*
G01X1225136Y346124D02*
X1246991Y328623D01*
G01X1225645Y347190D02*
X1248010Y329281D01*
G01X1246991Y328623D02*
X1257933Y286093D01*
G01X1258605Y283478D02*
X1258954Y282122D01*
G01X1263078Y281585D02*
X1262729Y282941D01*
G01X1262056Y285555D02*
X1261707Y286911D01*
G01X1261034Y289525D02*
X1250341Y331053D01*
G01D02*
X1224878Y351444D01*
G01X1251360Y331712D02*
X1225424Y352481D01*
G01X1254325Y332569D02*
X1266593Y284892D01*
G01X1267267Y282277D02*
X1267616Y280921D01*
G01X1225944Y355295D02*
X1254326Y332569D01*
G01D02*
X1254325D01*
G01X1255344Y333229D02*
X1226493Y356329D01*
G01X1269808Y287099D02*
X1269459Y288455D01*
G01X1268786Y291069D02*
X1268449Y292376D01*
G01X1267788Y294943D02*
X1257604Y334490D01*
G01D02*
X1228881Y357490D01*
G01X1258623Y335149D02*
X1229430Y358524D01*
G01X1274684Y282482D02*
X1274335Y283837D01*
G01X1273662Y286452D02*
X1260960Y335814D01*
G01D02*
X1230528Y360185D01*
G01X1261979Y336473D02*
X1231077Y361219D01*
G01X1264184Y337627D02*
X1233574Y362138D01*
G01X1234123Y363172D02*
X1265203Y338286D01*
G01X1276905Y288218D02*
X1276568Y289525D01*
G01X1275907Y292091D02*
X1275571Y293399D01*
G01X1274910Y295965D02*
X1264184Y337627D01*
G01X1265203Y338286D02*
X1282546Y270923D01*
G01X1267371Y339371D02*
X1235226Y365111D01*
G01X1235775Y366145D02*
X1268390Y340030D01*
G01X1280915Y286739D02*
X1267371Y339371D01*
G01X1268390Y340030D02*
X1286051Y271400D01*
G01X1235404Y368885D02*
X1271221Y340204D01*
G01X1235954Y369919D02*
X1272240Y340863D01*
G01X1271221Y340204D02*
X1285693Y283967D01*
G01X1272240Y340863D02*
X1290195Y271091D01*
G01X1225645Y347190D02*
X1248010Y329281D01*
G01X1225136Y346124D02*
X1246991Y328623D01*
G01D02*
X1257933Y286093D01*
G01X1258605Y283478D02*
X1258954Y282122D01*
G01X1263078Y281585D02*
X1262729Y282941D01*
G01X1262056Y285555D02*
X1261707Y286911D01*
G01X1261034Y289525D02*
X1250341Y331053D01*
G01X1251360Y331712D02*
X1225424Y352481D01*
G01X1250341Y331053D02*
X1224878Y351444D01*
G01X1255344Y333229D02*
X1226493Y356329D01*
G01X1225944Y355295D02*
X1254326Y332569D01*
G01X1255344Y333229D02*
X1226493Y356329D01*
G01X1254326Y332569D02*
X1254325D01*
G01D02*
X1266593Y284892D01*
G01X1267267Y282277D02*
X1267616Y280921D01*
G01X1269808Y287099D02*
X1269459Y288455D01*
G01X1268786Y291069D02*
X1268449Y292376D01*
G01X1267788Y294943D02*
X1257604Y334490D01*
G01X1258623Y335149D02*
X1229430Y358524D01*
G01X1257604Y334490D02*
X1228881Y357490D01*
G01X1274684Y282482D02*
X1274335Y283837D01*
G01X1273662Y286452D02*
X1260960Y335814D01*
G01X1261979Y336473D02*
X1231077Y361219D01*
G01X1260960Y335814D02*
X1230528Y360185D01*
G01X1265203Y338286D02*
X1282546Y270923D01*
G01X1265203Y338286D02*
X1282546Y270923D01*
G01X1276905Y288218D02*
X1276568Y289525D01*
G01X1265203Y338286D02*
X1282546Y270923D01*
G01X1275907Y292091D02*
X1275571Y293399D01*
G01X1265203Y338286D02*
X1282546Y270923D01*
G01X1274910Y295965D02*
X1264184Y337627D01*
G01X1234123Y363172D02*
X1265203Y338286D01*
G01X1264184Y337627D02*
X1233574Y362138D01*
G01X1268390Y340030D02*
X1286051Y271400D01*
G01X1268390Y340030D02*
X1286051Y271400D01*
G01X1268390Y340030D02*
X1286051Y271400D01*
G01X1280915Y286739D02*
X1267371Y339371D01*
G01X1235775Y366145D02*
X1268390Y340030D01*
G01X1267371Y339371D02*
X1235226Y365111D01*
G01X1235954Y369919D02*
X1272240Y340863D01*
G01X1235404Y368885D02*
X1271221Y340204D01*
G01X1272240Y340863D02*
X1290195Y271091D01*
G01X1271221Y340204D02*
X1285693Y283967D01*
G01X1272240Y340863D02*
X1290195Y271091D01*
G01X1272240Y340863D02*
X1290195Y271091D01*
G01X1272240Y340863D02*
X1290195Y271091D01*
G01X1230827Y405636D02*
X1225205Y397890D01*
G01X1231629Y404782D02*
X1225994Y397019D01*
G01X1273198Y427372D02*
X1234222Y402918D01*
G01D02*
X1228074Y394449D01*
G01X1233422Y403774D02*
X1227284Y395320D01*
G01D02*
X1227285D01*
G01X1275337Y420936D02*
X1240509Y399087D01*
G01X1274793Y421953D02*
X1239709Y399943D01*
G01X1240509Y399087D02*
X1232514Y388074D01*
G01X1239709Y399943D02*
X1231720Y388940D01*
G01X1273917Y423996D02*
X1237971Y401447D01*
G01X1273364Y425008D02*
X1237171Y402303D01*
G01X1237971Y401447D02*
X1230514Y391173D01*
G01X1237171Y402303D02*
X1229723Y392044D01*
G01X1231629Y404782D02*
X1225994Y397019D01*
G01X1230827Y405636D02*
X1225205Y397890D01*
G01X1273198Y427372D02*
X1234222Y402918D01*
G01X1233422Y403774D02*
X1227284Y395320D01*
G01X1234222Y402918D02*
X1228074Y394449D01*
G01X1227284Y395320D02*
X1227285D01*
G01X1274793Y421953D02*
X1239709Y399943D01*
G01X1275337Y420936D02*
X1240509Y399087D01*
G01X1239709Y399943D02*
X1231720Y388940D01*
G01X1240509Y399087D02*
X1232514Y388074D01*
G01X1273364Y425008D02*
X1237171Y402303D01*
G01X1273917Y423996D02*
X1237971Y401447D01*
G01X1237171Y402303D02*
X1229723Y392044D01*
G01X1237971Y401447D02*
X1230514Y391173D01*
G01X1284280Y461509D02*
X1277387Y435133D01*
G01X1285341Y461017D02*
X1278386Y434403D01*
G01X1277387Y435133D02*
X1231014Y405754D01*
G01D02*
X1231013D01*
G01D02*
X1230827Y405636D01*
G01X1278386Y434403D02*
X1231629Y404782D01*
G01X1288540Y434405D02*
X1273198Y427372D01*
G01X1287808Y435335D02*
X1272649Y428386D01*
G01D02*
X1233422Y403774D01*
G01X1279089Y448365D02*
X1281322Y459340D01*
G01X1281048Y463762D02*
X1278006Y448814D01*
G01X1275773Y443355D02*
X1279089Y448365D01*
G01X1278006Y448814D02*
X1274943Y444185D01*
G01X1261542Y433928D02*
X1275773Y443355D01*
G01X1274943Y444185D02*
X1260700Y434752D01*
G01X1283268Y469945D02*
X1279169Y464307D01*
G01X1278111Y464809D02*
X1277812Y463673D01*
G01X1279169Y464307D02*
X1278872Y463178D01*
G01X1277812Y463673D02*
X1259260Y437462D01*
G01X1278872Y463178D02*
X1260087Y436639D01*
G01X1248032Y437488D02*
X1254608Y461274D01*
G01X1249027Y436769D02*
X1255665Y460778D01*
G01X1254608Y461274D02*
X1260086Y469162D01*
G01X1255665Y460778D02*
X1260785Y468151D01*
G01X1280136Y470355D02*
X1275951Y464600D01*
G01X1274893Y465101D02*
X1274651Y464179D01*
G01X1275951Y464600D02*
X1275712Y463688D01*
G01X1274651Y464179D02*
X1259209Y442114D01*
G01X1275712Y463688D02*
X1260039Y441293D01*
G01X1292882Y428822D02*
X1275337Y420936D01*
G01X1292217Y429785D02*
X1274793Y421953D01*
G01X1291250Y431999D02*
X1273917Y423996D01*
G01X1290497Y432919D02*
X1273364Y425008D01*
G01X1285341Y461017D02*
X1278386Y434403D01*
G01X1284280Y461509D02*
X1277387Y435133D01*
G01X1278386Y434403D02*
X1231629Y404782D01*
G01X1277387Y435133D02*
X1231014Y405754D01*
G01X1278386Y434403D02*
X1231629Y404782D01*
G01X1231014Y405754D02*
X1231013D01*
G01X1278386Y434403D02*
X1231629Y404782D01*
G01X1231013Y405754D02*
X1230827Y405636D01*
G01X1287808Y435335D02*
X1272649Y428386D01*
G01X1288540Y434405D02*
X1273198Y427372D01*
G01X1272649Y428386D02*
X1233422Y403774D01*
G01X1274943Y444185D02*
X1260700Y434752D01*
G01X1261542Y433928D02*
X1275773Y443355D01*
G01X1278006Y448814D02*
X1274943Y444185D01*
G01X1275773Y443355D02*
X1279089Y448365D01*
G01X1281048Y463762D02*
X1278006Y448814D01*
G01X1279089Y448365D02*
X1281322Y459340D01*
G01X1281048Y463762D02*
X1278006Y448814D01*
G01X1283268Y469945D02*
X1279169Y464307D01*
G01D02*
X1278872Y463178D01*
G01X1278111Y464809D02*
X1277812Y463673D01*
G01X1278872Y463178D02*
X1260087Y436639D01*
G01X1277812Y463673D02*
X1259260Y437462D01*
G01X1249027Y436769D02*
X1255665Y460778D01*
G01X1248032Y437488D02*
X1254608Y461274D01*
G01X1255665Y460778D02*
X1260785Y468151D01*
G01X1254608Y461274D02*
X1260086Y469162D01*
G01X1280136Y470355D02*
X1275951Y464600D01*
G01D02*
X1275712Y463688D01*
G01X1274893Y465101D02*
X1274651Y464179D01*
G01X1275712Y463688D02*
X1260039Y441293D01*
G01X1274651Y464179D02*
X1259209Y442114D01*
G01X1292217Y429785D02*
X1274793Y421953D01*
G01X1292882Y428822D02*
X1275337Y420936D01*
G01X1290497Y432919D02*
X1273364Y425008D01*
G01X1291250Y431999D02*
X1273917Y423996D01*
G01X1282238Y470485D02*
X1278111Y464809D01*
G01X1260086Y469162D02*
X1266980Y470891D01*
G01X1260785Y468151D02*
X1266840Y469670D01*
G01X1266980Y470891D02*
X1270635Y469016D01*
G01X1266840Y469670D02*
X1270511Y467786D01*
G01X1270635Y469016D02*
X1274525Y470107D01*
G01X1270511Y467786D02*
X1275209Y469103D01*
G01X1274525Y470107D02*
X1276334Y472496D01*
G01X1275209Y469103D02*
X1277360Y471945D01*
G01X1276334Y472496D02*
X1281644Y487630D01*
G01X1277360Y471945D02*
X1282673Y487089D01*
G01X1283984Y484800D02*
X1279106Y470895D01*
G01X1285013Y484259D02*
X1280136Y470355D01*
G01X1279106Y470895D02*
X1274893Y465101D01*
G01X1282238Y470485D02*
X1278111Y464809D01*
G01X1260785Y468151D02*
X1266840Y469670D01*
G01X1260086Y469162D02*
X1266980Y470891D01*
G01X1266840Y469670D02*
X1270511Y467786D01*
G01X1266980Y470891D02*
X1270635Y469016D01*
G01X1270511Y467786D02*
X1275209Y469103D01*
G01X1270635Y469016D02*
X1274525Y470107D01*
G01X1275209Y469103D02*
X1277360Y471945D01*
G01X1274525Y470107D02*
X1276334Y472496D01*
G01X1277360Y471945D02*
X1282673Y487089D01*
G01X1276334Y472496D02*
X1281644Y487630D01*
G01X1285013Y484259D02*
X1280136Y470355D01*
G01X1283984Y484800D02*
X1279106Y470895D01*
G01D02*
X1274893Y465101D01*
G01X1323358Y145450D02*
Y146827D01*
G01X1322208Y145500D02*
Y146350D01*
G01X1323358Y146827D02*
X1321825Y148360D01*
G01X1322208Y146350D02*
X1321348Y147210D01*
G01X1321825Y148360D02*
X1313093D01*
G01X1321348Y147210D02*
X1313570D01*
G01X1313093Y148360D02*
X1311736Y147003D01*
G01X1313570Y147210D02*
X1312213Y145853D01*
G01X1311736Y147003D02*
X1307123D01*
G01X1312213Y145853D02*
X1307600D01*
G01X1307123Y147003D02*
X1301234Y141114D01*
G01X1307600Y145853D02*
X1301711Y139964D01*
G01X1301234Y141114D02*
X1292120D01*
G01X1301711Y139964D02*
X1291643D01*
G01X1292120Y141114D02*
X1286511Y146723D01*
G01X1291643Y139964D02*
X1286034Y145573D01*
G01X1286511Y146723D02*
X1282131D01*
G01X1286034Y145573D02*
X1282608D01*
G01X1322208Y145500D02*
Y146350D01*
G01X1323358Y145450D02*
Y146827D01*
G01X1322208Y146350D02*
X1321348Y147210D01*
G01X1323358Y146827D02*
X1321825Y148360D01*
G01X1321348Y147210D02*
X1313570D01*
G01X1321825Y148360D02*
X1313093D01*
G01X1313570Y147210D02*
X1312213Y145853D01*
G01X1313093Y148360D02*
X1311736Y147003D01*
G01X1312213Y145853D02*
X1307600D01*
G01X1311736Y147003D02*
X1307123D01*
G01X1307600Y145853D02*
X1301711Y139964D01*
G01X1307123Y147003D02*
X1301234Y141114D01*
G01X1301711Y139964D02*
X1291643D01*
G01X1301234Y141114D02*
X1292120D01*
G01X1291643Y139964D02*
X1286034Y145573D01*
G01X1292120Y141114D02*
X1286511Y146723D01*
G01X1286034Y145573D02*
X1282608D01*
G01X1286511Y146723D02*
X1282131D01*
G01X1337593Y218645D02*
X1362419Y213798D01*
G01X1337593Y218645D02*
X1362419Y213798D01*
G01X1285300Y246811D02*
X1285987Y245986D01*
G01X1285266Y245053D02*
X1295587Y240202D01*
G01X1285987Y245986D02*
X1296025Y241268D01*
G01X1295587Y240202D02*
X1307402Y236025D01*
G01X1296025Y241268D02*
X1307600Y237175D01*
G01X1307402Y236025D02*
X1311023D01*
G01X1307600Y237175D02*
X1310546D01*
G01X1311023Y236025D02*
X1313175Y238177D01*
G01X1310546Y237175D02*
X1312025Y238654D01*
G01X1313175Y238177D02*
Y239175D01*
G01X1312025Y238654D02*
Y239652D01*
G01X1313175Y239175D02*
X1314052Y240052D01*
G01X1312025Y239652D02*
X1313575Y241202D01*
G01X1314052Y240052D02*
X1316228D01*
G01X1313575Y241202D02*
X1316705D01*
G01X1316228Y240052D02*
X1317075Y239205D01*
G01X1316705Y241202D02*
X1318225Y239682D01*
G01X1317075Y239205D02*
Y238350D01*
G01X1318225Y239682D02*
Y238350D01*
G01X1328075Y238671D02*
Y239602D01*
G01X1329225Y238350D02*
Y240079D01*
G01X1328075Y239602D02*
X1327157Y240520D01*
G01X1329225Y240079D02*
X1327634Y241670D01*
G01X1327157Y240520D02*
X1319297D01*
G01X1327634Y241670D02*
X1319774D01*
G01X1319297Y240520D02*
X1317191Y242626D01*
G01X1319774Y241670D02*
X1317668Y243776D01*
G01X1317191Y242626D02*
X1298981D01*
G01X1317668Y243776D02*
X1299238D01*
G01X1298981Y242626D02*
X1285801Y248823D01*
G01X1299238Y243776D02*
X1286522Y249756D01*
G01X1339075Y239600D02*
Y238350D01*
G01X1340225D02*
Y240077D01*
G01X1338077Y240598D02*
X1339075Y239600D01*
G01X1340225Y240077D02*
X1338554Y241748D01*
G01X1331517Y240598D02*
X1338077D01*
G01X1338554Y241748D02*
X1331994D01*
G01X1329095Y243020D02*
X1331517Y240598D01*
G01X1331994Y241748D02*
X1329572Y244170D01*
G01X1320334Y243020D02*
X1329095D01*
G01X1329572Y244170D02*
X1320811D01*
G01X1318228Y245126D02*
X1320334Y243020D01*
G01X1320811Y244170D02*
X1318705Y246276D01*
G01X1300459Y245126D02*
X1318228D01*
G01X1318705Y246276D02*
X1300716D01*
G01X1286778Y251558D02*
X1300459Y245126D01*
G01X1300716Y246276D02*
X1287499Y252491D01*
G01X1348311Y243152D02*
X1332500D01*
G01X1348788Y244302D02*
X1332977D01*
G01X1332500Y243152D02*
X1330132Y245520D01*
G01X1332977Y244302D02*
X1330609Y246670D01*
G01X1330132Y245520D02*
X1321371D01*
G01X1330609Y246670D02*
X1321848D01*
G01X1321371Y245520D02*
X1319265Y247626D01*
G01X1321848Y246670D02*
X1319742Y248776D01*
G01X1319265Y247626D02*
X1301666D01*
G01X1319742Y248776D02*
X1301923D01*
G01X1301666Y247626D02*
X1288155Y253977D01*
G01X1301923Y248776D02*
X1288876Y254910D01*
G01X1356990Y245652D02*
X1333537D01*
G01X1357467Y246802D02*
X1334014D01*
G01X1333537Y245652D02*
X1331169Y248020D01*
G01X1334014Y246802D02*
X1331646Y249170D01*
G01X1331169Y248020D02*
X1322408D01*
G01X1331646Y249170D02*
X1322885D01*
G01X1322408Y248020D02*
X1320302Y250126D01*
G01X1322885Y249170D02*
X1320779Y251276D01*
G01X1320302Y250126D02*
X1302927D01*
G01X1320779Y251276D02*
X1303184D01*
G01X1302927Y250126D02*
X1289539Y256420D01*
G01X1303184Y251276D02*
X1290260Y257353D01*
G01X1291479Y258406D02*
X1281496Y270384D01*
G01X1282546Y270923D02*
X1292200Y259339D01*
G01X1303777Y252626D02*
X1291479Y258406D01*
G01X1292200Y259339D02*
X1304034Y253776D01*
G01X1321339Y252626D02*
X1303777D01*
G01X1304034Y253776D02*
X1321816D01*
G01X1323445Y250520D02*
X1321339Y252626D01*
G01X1321816Y253776D02*
X1323922Y251670D01*
G01X1332206Y250520D02*
X1323445D01*
G01X1323922Y251670D02*
X1332683D01*
G01X1334574Y248152D02*
X1332206Y250520D01*
G01X1332683Y251670D02*
X1335051Y249302D01*
G01X1367820Y248152D02*
X1334574D01*
G01X1335051Y249302D02*
X1368297D01*
G01X1285003Y270857D02*
X1282610Y280154D01*
G01X1294043Y260233D02*
X1285003Y270857D01*
G01X1286051Y271400D02*
X1294719Y261215D01*
G01X1300168Y258063D02*
X1294043Y260233D01*
G01X1294719Y261215D02*
X1300166Y259285D01*
G01X1306400Y260300D02*
X1305129Y259844D01*
G01X1302635Y258949D02*
X1300168Y258063D01*
G01X1300166Y259285D02*
X1306366Y261510D01*
G01X1308760Y259600D02*
X1306400Y260300D01*
G01X1306366Y261510D02*
X1309170Y260678D01*
G01X1318280Y255126D02*
X1308760Y259600D01*
G01X1309170Y260678D02*
X1318537Y256276D01*
G01X1322376Y255126D02*
X1318280D01*
G01X1318537Y256276D02*
X1322853D01*
G01X1324482Y253020D02*
X1322376Y255126D01*
G01X1322853Y256276D02*
X1324959Y254170D01*
G01X1333243Y253020D02*
X1324482D01*
G01X1324959Y254170D02*
X1333720D01*
G01X1335611Y250652D02*
X1333243Y253020D01*
G01X1333720Y254170D02*
X1336088Y251802D01*
G01X1372250Y250652D02*
X1335611D01*
G01X1336088Y251802D02*
X1372727D01*
G01X1287388Y277381D02*
X1287737Y276025D01*
G01X1288410Y273410D02*
X1289145Y270553D01*
G01D02*
X1296052Y262277D01*
G01X1290195Y271091D02*
X1296733Y263256D01*
G01X1296052Y262277D02*
X1300081Y260847D01*
G01X1296733Y263256D02*
X1300079Y262069D01*
G01X1300081Y260847D02*
X1306323Y263088D01*
G01X1300079Y262069D02*
X1306289Y264298D01*
G01X1306323Y263088D02*
X1308960Y262305D01*
G01X1306289Y264298D02*
X1309370Y263383D01*
G01X1308960Y262305D02*
X1318918Y257626D01*
G01X1309370Y263383D02*
X1319175Y258776D01*
G01X1318918Y257626D02*
X1323413D01*
G01X1319175Y258776D02*
X1323890D01*
G01X1323413Y257626D02*
X1325519Y255520D01*
G01X1323890Y258776D02*
X1325996Y256670D01*
G01X1325519Y255520D02*
X1334280D01*
G01X1325996Y256670D02*
X1334757D01*
G01X1334280Y255520D02*
X1336648Y253152D01*
G01X1334757Y256670D02*
X1337125Y254302D01*
G01X1336648Y253152D02*
X1379847D01*
G01X1337125Y254302D02*
X1380324D01*
G01X1285300Y246811D02*
X1285987Y245986D01*
G01D02*
X1296025Y241268D01*
G01X1285266Y245053D02*
X1295587Y240202D01*
G01X1296025Y241268D02*
X1307600Y237175D01*
G01X1295587Y240202D02*
X1307402Y236025D01*
G01X1307600Y237175D02*
X1310546D01*
G01X1307402Y236025D02*
X1311023D01*
G01X1310546Y237175D02*
X1312025Y238654D01*
G01X1311023Y236025D02*
X1313175Y238177D01*
G01X1312025Y238654D02*
Y239652D01*
G01X1313175Y238177D02*
Y239175D01*
G01X1312025Y239652D02*
X1313575Y241202D01*
G01X1313175Y239175D02*
X1314052Y240052D01*
G01X1313575Y241202D02*
X1316705D01*
G01X1314052Y240052D02*
X1316228D01*
G01X1316705Y241202D02*
X1318225Y239682D01*
G01X1316228Y240052D02*
X1317075Y239205D01*
G01X1318225Y239682D02*
Y238350D01*
G01X1317075Y239205D02*
Y238350D01*
G01X1329225D02*
Y240079D01*
G01X1328075Y238671D02*
Y239602D01*
G01X1329225Y240079D02*
X1327634Y241670D01*
G01X1328075Y239602D02*
X1327157Y240520D01*
G01X1327634Y241670D02*
X1319774D01*
G01X1327157Y240520D02*
X1319297D01*
G01X1319774Y241670D02*
X1317668Y243776D01*
G01X1319297Y240520D02*
X1317191Y242626D01*
G01X1317668Y243776D02*
X1299238D01*
G01X1317191Y242626D02*
X1298981D01*
G01X1299238Y243776D02*
X1286522Y249756D01*
G01X1298981Y242626D02*
X1285801Y248823D01*
G01X1300716Y246276D02*
X1287499Y252491D01*
G01X1286778Y251558D02*
X1300459Y245126D01*
G01X1318705Y246276D02*
X1300716D01*
G01X1300459Y245126D02*
X1318228D01*
G01X1320811Y244170D02*
X1318705Y246276D01*
G01X1318228Y245126D02*
X1320334Y243020D01*
G01X1329572Y244170D02*
X1320811D01*
G01X1320334Y243020D02*
X1329095D01*
G01X1331994Y241748D02*
X1329572Y244170D01*
G01X1329095Y243020D02*
X1331517Y240598D01*
G01X1338554Y241748D02*
X1331994D01*
G01X1331517Y240598D02*
X1338077D01*
G01X1340225Y240077D02*
X1338554Y241748D01*
G01X1338077Y240598D02*
X1339075Y239600D01*
G01X1340225Y238350D02*
Y240077D01*
G01X1339075Y239600D02*
Y238350D01*
G01X1348788Y244302D02*
X1332977D01*
G01X1348311Y243152D02*
X1332500D01*
G01X1332977Y244302D02*
X1330609Y246670D01*
G01X1332500Y243152D02*
X1330132Y245520D01*
G01X1330609Y246670D02*
X1321848D01*
G01X1330132Y245520D02*
X1321371D01*
G01X1321848Y246670D02*
X1319742Y248776D01*
G01X1321371Y245520D02*
X1319265Y247626D01*
G01X1319742Y248776D02*
X1301923D01*
G01X1319265Y247626D02*
X1301666D01*
G01X1301923Y248776D02*
X1288876Y254910D01*
G01X1301666Y247626D02*
X1288155Y253977D01*
G01X1357467Y246802D02*
X1334014D01*
G01X1356990Y245652D02*
X1333537D01*
G01X1334014Y246802D02*
X1331646Y249170D01*
G01X1333537Y245652D02*
X1331169Y248020D01*
G01X1331646Y249170D02*
X1322885D01*
G01X1331169Y248020D02*
X1322408D01*
G01X1322885Y249170D02*
X1320779Y251276D01*
G01X1322408Y248020D02*
X1320302Y250126D01*
G01X1320779Y251276D02*
X1303184D01*
G01X1320302Y250126D02*
X1302927D01*
G01X1303184Y251276D02*
X1290260Y257353D01*
G01X1302927Y250126D02*
X1289539Y256420D01*
G01X1335051Y249302D02*
X1368297D01*
G01X1367820Y248152D02*
X1334574D01*
G01X1332683Y251670D02*
X1335051Y249302D01*
G01X1334574Y248152D02*
X1332206Y250520D01*
G01X1323922Y251670D02*
X1332683D01*
G01X1332206Y250520D02*
X1323445D01*
G01X1321816Y253776D02*
X1323922Y251670D01*
G01X1323445Y250520D02*
X1321339Y252626D01*
G01X1304034Y253776D02*
X1321816D01*
G01X1321339Y252626D02*
X1303777D01*
G01X1292200Y259339D02*
X1304034Y253776D01*
G01X1303777Y252626D02*
X1291479Y258406D01*
G01X1282546Y270923D02*
X1292200Y259339D01*
G01X1291479Y258406D02*
X1281496Y270384D01*
G01X1336088Y251802D02*
X1372727D01*
G01X1372250Y250652D02*
X1335611D01*
G01X1333720Y254170D02*
X1336088Y251802D01*
G01X1335611Y250652D02*
X1333243Y253020D01*
G01X1324959Y254170D02*
X1333720D01*
G01X1333243Y253020D02*
X1324482D01*
G01X1322853Y256276D02*
X1324959Y254170D01*
G01X1324482Y253020D02*
X1322376Y255126D01*
G01X1318537Y256276D02*
X1322853D01*
G01X1322376Y255126D02*
X1318280D01*
G01X1309170Y260678D02*
X1318537Y256276D01*
G01X1318280Y255126D02*
X1308760Y259600D01*
G01X1306366Y261510D02*
X1309170Y260678D01*
G01X1308760Y259600D02*
X1306400Y260300D01*
G01X1300166Y259285D02*
X1306366Y261510D01*
G01X1306400Y260300D02*
X1305129Y259844D01*
G01X1300166Y259285D02*
X1306366Y261510D01*
G01X1302635Y258949D02*
X1300168Y258063D01*
G01X1294719Y261215D02*
X1300166Y259285D01*
G01X1300168Y258063D02*
X1294043Y260233D01*
G01X1286051Y271400D02*
X1294719Y261215D01*
G01X1294043Y260233D02*
X1285003Y270857D01*
G01D02*
X1282610Y280154D01*
G01X1287388Y277381D02*
X1287737Y276025D01*
G01X1288410Y273410D02*
X1289145Y270553D01*
G01X1290195Y271091D02*
X1296733Y263256D01*
G01X1289145Y270553D02*
X1296052Y262277D01*
G01X1296733Y263256D02*
X1300079Y262069D01*
G01X1296052Y262277D02*
X1300081Y260847D01*
G01X1300079Y262069D02*
X1306289Y264298D01*
G01X1300081Y260847D02*
X1306323Y263088D01*
G01X1306289Y264298D02*
X1309370Y263383D01*
G01X1306323Y263088D02*
X1308960Y262305D01*
G01X1309370Y263383D02*
X1319175Y258776D01*
G01X1308960Y262305D02*
X1318918Y257626D01*
G01X1319175Y258776D02*
X1323890D01*
G01X1318918Y257626D02*
X1323413D01*
G01X1323890Y258776D02*
X1325996Y256670D01*
G01X1323413Y257626D02*
X1325519Y255520D01*
G01X1325996Y256670D02*
X1334757D01*
G01X1325519Y255520D02*
X1334280D01*
G01X1334757Y256670D02*
X1337125Y254302D01*
G01X1334280Y255520D02*
X1336648Y253152D01*
G01X1337125Y254302D02*
X1380324D01*
G01X1336648Y253152D02*
X1379847D01*
G01X1318225Y231668D02*
Y230775D01*
G01X1317075Y231668D02*
Y230473D01*
G01X1318225Y230775D02*
X1318937Y229511D01*
G01X1317075Y230473D02*
X1318070Y228706D01*
G01X1318937Y229511D02*
X1318938D01*
G01D02*
X1330055Y222101D01*
G01X1318070Y228706D02*
X1322944Y225457D01*
G01X1318938Y229511D02*
X1330055Y222101D01*
G01X1324248Y223807D02*
X1325149Y223987D01*
G01X1318938Y229511D02*
X1330055Y222101D01*
G01X1325149Y223987D02*
X1329602Y221019D01*
G01X1330055Y222101D02*
X1336149Y220884D01*
G01X1329606Y221017D02*
X1335700Y219800D01*
G01X1336149Y220884D02*
X1337813Y219774D01*
G01X1335700Y219800D02*
X1337367Y218689D01*
G01X1337813Y219774D02*
X1363110Y214835D01*
G01X1337367Y218689D02*
X1337592Y218645D01*
G01X1337813Y219774D02*
X1363110Y214835D01*
G01X1337592Y218645D02*
X1337593D01*
G01X1337813Y219774D02*
X1363110Y214835D01*
G01X1324468Y278929D02*
Y277619D01*
G01X1325618Y278038D02*
Y277199D01*
G01X1324468Y277619D02*
X1323985Y277044D01*
G01X1325618Y277199D02*
X1324595Y275982D01*
G01X1323985Y277044D02*
X1322822Y276842D01*
G01X1324595Y275982D02*
X1322661Y275646D01*
G01X1323985Y277044D02*
X1322822Y276842D01*
G01D02*
X1320961Y277716D01*
G01X1318563Y278843D02*
X1312901Y281504D01*
G01X1322661Y275646D02*
X1311939Y280684D01*
G01X1331100Y274427D02*
X1330648Y273975D01*
G01X1332723Y274423D02*
X1331125Y272825D01*
G01X1330648Y273975D02*
X1322530D01*
G01X1331125Y272825D02*
X1322273D01*
G01X1322530Y273975D02*
X1307456Y281066D01*
G01X1322273Y272825D02*
X1306495Y280247D01*
G01X1337658Y270545D02*
Y269935D01*
G01X1338808Y270315D02*
Y269458D01*
G01X1337658Y269935D02*
X1337208Y269485D01*
G01X1338808Y269458D02*
X1337685Y268335D01*
G01X1337208Y269485D02*
X1332451D01*
G01X1337685Y268335D02*
X1331974D01*
G01X1332451Y269485D02*
X1330536Y271400D01*
G01X1331974Y268335D02*
X1330059Y270250D01*
G01X1330536Y271400D02*
X1322040D01*
G01X1330059Y270250D02*
X1321782D01*
G01X1322040Y271400D02*
X1305217Y279315D01*
G01X1321782Y270250D02*
X1304255Y278496D01*
G01X1305217Y279315D02*
X1303690Y284623D01*
G01X1304255Y278496D02*
X1302509Y284567D01*
G01X1341914Y265068D02*
X1344119D01*
G01X1344596Y263918D02*
X1341437D01*
G01X1339997Y266985D02*
X1341914Y265068D01*
G01X1341437Y263918D02*
X1339520Y265835D01*
G01X1331398Y266985D02*
X1339997D01*
G01X1339520Y265835D02*
X1330921D01*
G01X1329492Y268891D02*
X1331398Y266985D01*
G01X1330921Y265835D02*
X1329015Y267741D01*
G01X1321412Y268891D02*
X1329492D01*
G01X1329015Y267741D02*
X1321155D01*
G01X1302910Y277593D02*
X1321412Y268891D01*
G01X1321155Y267741D02*
X1301932Y276782D01*
G01X1297186Y299692D02*
X1302910Y277593D01*
G01X1301932Y276782D02*
X1296006Y299658D01*
G01X1341021Y262424D02*
X1353298D01*
G01X1353775Y261274D02*
X1340544D01*
G01X1338961Y264484D02*
X1341021Y262424D01*
G01X1340544Y261274D02*
X1338484Y263334D01*
G01X1330270Y264484D02*
X1338961D01*
G01X1338484Y263334D02*
X1329793D01*
G01X1328363Y266391D02*
X1330270Y264484D01*
G01X1329793Y263334D02*
X1327886Y265241D01*
G01X1320841Y266391D02*
X1328363D01*
G01X1327886Y265241D02*
X1320584D01*
G01X1299257Y276540D02*
X1320841Y266391D01*
G01X1320584Y265241D02*
X1298279Y275729D01*
G01X1298278Y280320D02*
X1299257Y276540D01*
G01X1298279Y275729D02*
X1291927Y300248D01*
G01X1288511Y302535D02*
X1295848Y274039D01*
G01X1289690Y302569D02*
X1296827Y274850D01*
G01X1295848Y274039D02*
X1319886Y262741D01*
G01X1296827Y274850D02*
X1320143Y263891D01*
G01X1319886Y262741D02*
X1326575D01*
G01X1320143Y263891D02*
X1327052D01*
G01X1326575Y262741D02*
X1328482Y260834D01*
G01X1327052Y263891D02*
X1328959Y261984D01*
G01X1328482Y260834D02*
X1337447D01*
G01X1328959Y261984D02*
X1337924D01*
G01X1337447Y260834D02*
X1339507Y258774D01*
G01X1337924Y261984D02*
X1339984Y259924D01*
G01X1339507Y258774D02*
X1363977D01*
G01X1339984Y259924D02*
X1363500D01*
G01X1365343Y257424D02*
X1338711D01*
G01X1378120Y256274D02*
X1338234D01*
G01X1338711Y257424D02*
X1336651Y259484D01*
G01X1338234Y256274D02*
X1336174Y258334D01*
G01X1336651Y259484D02*
X1327459D01*
G01X1336174Y258334D02*
X1326982D01*
G01X1327459Y259484D02*
X1325644Y261299D01*
G01X1326982Y258334D02*
X1325167Y260149D01*
G01X1325644Y261299D02*
X1319750D01*
G01X1325167Y260149D02*
X1319493D01*
G01X1319750Y261299D02*
X1309545Y266095D01*
G01X1319493Y260149D02*
X1309134Y265017D01*
G01X1309545Y266095D02*
X1306210Y267085D01*
G01X1309134Y265017D02*
X1306244Y265875D01*
G01X1306210Y267085D02*
X1299855Y264804D01*
G01X1306244Y265875D02*
X1299858Y263582D01*
G01X1299855Y264804D02*
X1298446Y265303D01*
G01X1299858Y263582D02*
X1297767Y264323D01*
G01X1298446Y265303D02*
X1293764Y270864D01*
G01X1297767Y264323D02*
X1292715Y270323D01*
G01X1293764Y270864D02*
X1293427Y272171D01*
G01X1292766Y274737D02*
X1292429Y276045D01*
G01X1291767Y278611D02*
X1291430Y279918D01*
G01X1292715Y270323D02*
X1285289Y299134D01*
G01X1325618Y278038D02*
Y277199D01*
G01X1324468Y278929D02*
Y277619D01*
G01X1325618Y277199D02*
X1324595Y275982D01*
G01X1324468Y277619D02*
X1323985Y277044D01*
G01X1324595Y275982D02*
X1322661Y275646D01*
G01D02*
X1311939Y280684D01*
G01X1323985Y277044D02*
X1322822Y276842D01*
G01X1322661Y275646D02*
X1311939Y280684D01*
G01X1322822Y276842D02*
X1320961Y277716D01*
G01X1322661Y275646D02*
X1311939Y280684D01*
G01X1318563Y278843D02*
X1312901Y281504D01*
G01X1332723Y274423D02*
X1331125Y272825D01*
G01X1331100Y274427D02*
X1330648Y273975D01*
G01X1331125Y272825D02*
X1322273D01*
G01X1330648Y273975D02*
X1322530D01*
G01X1322273Y272825D02*
X1306495Y280247D01*
G01X1322530Y273975D02*
X1307456Y281066D01*
G01X1338808Y270315D02*
Y269458D01*
G01X1337658Y270545D02*
Y269935D01*
G01X1338808Y269458D02*
X1337685Y268335D01*
G01X1337658Y269935D02*
X1337208Y269485D01*
G01X1337685Y268335D02*
X1331974D01*
G01X1337208Y269485D02*
X1332451D01*
G01X1331974Y268335D02*
X1330059Y270250D01*
G01X1332451Y269485D02*
X1330536Y271400D01*
G01X1330059Y270250D02*
X1321782D01*
G01X1330536Y271400D02*
X1322040D01*
G01X1321782Y270250D02*
X1304255Y278496D01*
G01X1322040Y271400D02*
X1305217Y279315D01*
G01X1304255Y278496D02*
X1302509Y284567D01*
G01X1305217Y279315D02*
X1303690Y284623D01*
G01X1301932Y276782D02*
X1296006Y299658D01*
G01X1297186Y299692D02*
X1302910Y277593D01*
G01X1321155Y267741D02*
X1301932Y276782D01*
G01X1302910Y277593D02*
X1321412Y268891D01*
G01X1329015Y267741D02*
X1321155D01*
G01X1321412Y268891D02*
X1329492D01*
G01X1330921Y265835D02*
X1329015Y267741D01*
G01X1329492Y268891D02*
X1331398Y266985D01*
G01X1339520Y265835D02*
X1330921D01*
G01X1331398Y266985D02*
X1339997D01*
G01X1341437Y263918D02*
X1339520Y265835D01*
G01X1339997Y266985D02*
X1341914Y265068D01*
G01X1344596Y263918D02*
X1341437D01*
G01X1341914Y265068D02*
X1344119D01*
G01X1298279Y275729D02*
X1291927Y300248D01*
G01X1298279Y275729D02*
X1291927Y300248D01*
G01X1298279Y275729D02*
X1291927Y300248D01*
G01X1298279Y275729D02*
X1291927Y300248D01*
G01X1298278Y280320D02*
X1299257Y276540D01*
G01X1320584Y265241D02*
X1298279Y275729D01*
G01X1299257Y276540D02*
X1320841Y266391D01*
G01X1327886Y265241D02*
X1320584D01*
G01X1320841Y266391D02*
X1328363D01*
G01X1329793Y263334D02*
X1327886Y265241D01*
G01X1328363Y266391D02*
X1330270Y264484D01*
G01X1338484Y263334D02*
X1329793D01*
G01X1330270Y264484D02*
X1338961D01*
G01X1340544Y261274D02*
X1338484Y263334D01*
G01X1338961Y264484D02*
X1341021Y262424D01*
G01X1353775Y261274D02*
X1340544D01*
G01X1341021Y262424D02*
X1353298D01*
G01X1289690Y302569D02*
X1296827Y274850D01*
G01X1288511Y302535D02*
X1295848Y274039D01*
G01X1296827Y274850D02*
X1320143Y263891D01*
G01X1295848Y274039D02*
X1319886Y262741D01*
G01X1320143Y263891D02*
X1327052D01*
G01X1319886Y262741D02*
X1326575D01*
G01X1327052Y263891D02*
X1328959Y261984D01*
G01X1326575Y262741D02*
X1328482Y260834D01*
G01X1328959Y261984D02*
X1337924D01*
G01X1328482Y260834D02*
X1337447D01*
G01X1337924Y261984D02*
X1339984Y259924D01*
G01X1337447Y260834D02*
X1339507Y258774D01*
G01X1339984Y259924D02*
X1363500D01*
G01X1339507Y258774D02*
X1363977D01*
G01X1378120Y256274D02*
X1338234D01*
G01X1378120D02*
X1338234D01*
G01X1378120D02*
X1338234D01*
G01X1378120D02*
X1338234D01*
G01X1365343Y257424D02*
X1338711D01*
G01X1338234Y256274D02*
X1336174Y258334D01*
G01X1338711Y257424D02*
X1336651Y259484D01*
G01X1336174Y258334D02*
X1326982D01*
G01X1336651Y259484D02*
X1327459D01*
G01X1326982Y258334D02*
X1325167Y260149D01*
G01X1327459Y259484D02*
X1325644Y261299D01*
G01X1325167Y260149D02*
X1319493D01*
G01X1325644Y261299D02*
X1319750D01*
G01X1319493Y260149D02*
X1309134Y265017D01*
G01X1319750Y261299D02*
X1309545Y266095D01*
G01X1309134Y265017D02*
X1306244Y265875D01*
G01X1309545Y266095D02*
X1306210Y267085D01*
G01X1306244Y265875D02*
X1299858Y263582D01*
G01X1306210Y267085D02*
X1299855Y264804D01*
G01X1299858Y263582D02*
X1297767Y264323D01*
G01X1299855Y264804D02*
X1298446Y265303D01*
G01X1297767Y264323D02*
X1292715Y270323D01*
G01X1298446Y265303D02*
X1293764Y270864D01*
G01X1292715Y270323D02*
X1285289Y299134D01*
G01X1293764Y270864D02*
X1293427Y272171D01*
G01X1292715Y270323D02*
X1285289Y299134D01*
G01X1292766Y274737D02*
X1292429Y276045D01*
G01X1292715Y270323D02*
X1285289Y299134D01*
G01X1291767Y278611D02*
X1291430Y279918D01*
G01X1292715Y270323D02*
X1285289Y299134D01*
G01X1317075Y231668D02*
Y230473D01*
G01X1318225Y231668D02*
Y230775D01*
G01X1317075Y230473D02*
X1318070Y228706D01*
G01X1318225Y230775D02*
X1318937Y229511D01*
G01X1318070Y228706D02*
X1322944Y225457D01*
G01X1318937Y229511D02*
X1318938D01*
G01X1318070Y228706D02*
X1322944Y225457D01*
G01X1324248Y223807D02*
X1325149Y223987D01*
G01D02*
X1329602Y221019D01*
G01X1318938Y229511D02*
X1330055Y222101D01*
G01X1329606Y221017D02*
X1335700Y219800D01*
G01X1330055Y222101D02*
X1336149Y220884D01*
G01X1335700Y219800D02*
X1337367Y218689D01*
G01X1336149Y220884D02*
X1337813Y219774D01*
G01X1337367Y218689D02*
X1337592Y218645D01*
G01D02*
X1337593D01*
G01X1337813Y219774D02*
X1363110Y214835D01*
G01X1328075Y231668D02*
Y230226D01*
G01X1329225Y231668D02*
Y230561D01*
G01X1328075Y230226D02*
X1329143Y228546D01*
G01X1329225Y230561D02*
X1329995Y229350D01*
G01X1329143Y228546D02*
X1332354Y226232D01*
G01X1333597Y224535D02*
X1334505Y224683D01*
G01D02*
X1339742Y220909D01*
G01X1329995Y229350D02*
X1340210Y221990D01*
G01X1339742Y220909D02*
X1366640Y215656D01*
G01X1340210Y221990D02*
X1367331Y216693D01*
G01X1338993Y231667D02*
Y228860D01*
G01X1340143Y231668D02*
Y229131D01*
G01X1338993Y228860D02*
X1340887Y225061D01*
G01X1340143Y229131D02*
X1341788Y225834D01*
G01X1340887Y225061D02*
X1343940Y222903D01*
G01X1341788Y225834D02*
X1344402Y223985D01*
G01X1329225Y231668D02*
Y230561D01*
G01X1328075Y231668D02*
Y230226D01*
G01X1329225Y230561D02*
X1329995Y229350D01*
G01X1328075Y230226D02*
X1329143Y228546D01*
G01X1329995Y229350D02*
X1340210Y221990D01*
G01X1329143Y228546D02*
X1332354Y226232D01*
G01X1329995Y229350D02*
X1340210Y221990D01*
G01X1333597Y224535D02*
X1334505Y224683D01*
G01X1329995Y229350D02*
X1340210Y221990D01*
G01X1334505Y224683D02*
X1339742Y220909D01*
G01X1340210Y221990D02*
X1367331Y216693D01*
G01X1339742Y220909D02*
X1366640Y215656D01*
G01X1340143Y231668D02*
Y229131D01*
G01X1338993Y231667D02*
Y228860D01*
G01X1340143Y229131D02*
X1341788Y225834D01*
G01X1338993Y228860D02*
X1340887Y225061D01*
G01X1341788Y225834D02*
X1344402Y223985D01*
G01X1340887Y225061D02*
X1343940Y222903D01*
G01X1281937Y282769D02*
X1281588Y284124D01*
G01X1286366Y281352D02*
X1286715Y279996D01*
G01X1281937Y282769D02*
X1281588Y284124D01*
G01X1286366Y281352D02*
X1286715Y279996D01*
G01X1312901Y281504D02*
X1311921Y284905D01*
G01X1311939Y280687D02*
X1310740Y284849D01*
G01X1311921Y284905D02*
X1312746Y289291D01*
G01X1310740Y284849D02*
X1311665Y289766D01*
G01X1312746Y289291D02*
X1314878Y292142D01*
G01X1311665Y289766D02*
X1313802Y292625D01*
G01X1314878Y292142D02*
X1315771Y296531D01*
G01X1313802Y292625D02*
X1314597Y296531D01*
G01X1315771D02*
X1315093Y299865D01*
G01X1314597Y296531D02*
X1313436Y302233D01*
G01X1314564Y302462D02*
X1314315Y303685D01*
G01X1313437Y302233D02*
X1313138Y303697D01*
G01X1314315Y303685D02*
X1315292Y308032D01*
G01X1313138Y303697D02*
X1314215Y308486D01*
G01X1315292Y308032D02*
X1315969Y309074D01*
G01X1314215Y308486D02*
X1315116Y309872D01*
G01X1315969Y309074D02*
X1317089Y309914D01*
G01D02*
X1317999Y309784D01*
G01X1315116Y309872D02*
X1316780Y311120D01*
G01X1319250Y311533D02*
X1320370Y312373D01*
G01D02*
X1321280Y312243D01*
G01X1322530Y313993D02*
X1323650Y314832D01*
G01D02*
X1324560Y314702D01*
G01X1325811Y316452D02*
X1326931Y317292D01*
G01D02*
X1327841Y317162D01*
G01X1329091Y318911D02*
X1332147Y321202D01*
G01D02*
X1333056Y321071D01*
G01X1334267Y322791D02*
X1335347Y323601D01*
G01X1316779Y311120D02*
X1334775Y324610D01*
G01X1335347Y323601D02*
X1351378Y330164D01*
G01X1334775Y324610D02*
X1351316Y331382D01*
G01X1307456Y281066D02*
X1306393Y284759D01*
G01X1306495Y280247D02*
X1305212Y284703D01*
G01X1306393Y284759D02*
X1306705Y286415D01*
G01X1305212Y284703D02*
X1305624Y286890D01*
G01X1306705Y286415D02*
X1312407Y294042D01*
G01X1305624Y286890D02*
X1311331Y294524D01*
G01X1312407Y294042D02*
X1312913Y296529D01*
G01X1311331Y294524D02*
X1311739Y296529D01*
G01X1312913D02*
X1311607Y302950D01*
G01X1311739Y296529D02*
X1310433Y302950D01*
G01X1311607D02*
X1314270Y316034D01*
G01X1310433Y302950D02*
X1313187Y316483D01*
G01X1314270Y316034D02*
X1314606Y316542D01*
G01X1313187Y316483D02*
X1313909Y317575D01*
G01X1316096Y318793D02*
X1316869Y319961D01*
G01X1318358Y322213D02*
X1320017Y324720D01*
G01X1313910Y317575D02*
X1319297Y325717D01*
G01X1320017Y324720D02*
X1321368Y325086D01*
G01X1323974Y325792D02*
X1325326Y326159D01*
G01X1327932Y326865D02*
X1329283Y327231D01*
G01X1331889Y327937D02*
X1333240Y328303D01*
G01X1335846Y329009D02*
X1337197Y329375D01*
G01X1339803Y330081D02*
X1341106Y330434D01*
G01X1319297Y325717D02*
X1358958Y336464D01*
G01X1303690Y284623D02*
X1304204Y287356D01*
G01X1302509Y284567D02*
X1303123Y287831D01*
G01X1304204Y287356D02*
X1309679Y294678D01*
G01X1303123Y287831D02*
X1308603Y295160D01*
G01X1309679Y294678D02*
X1310056Y296531D01*
G01X1308603Y295160D02*
X1308882Y296531D01*
G01X1310056D02*
X1308568Y303839D01*
G01X1308882Y296531D02*
X1307394Y303839D01*
G01X1308568D02*
X1309103Y306468D01*
G01X1309632Y309065D02*
X1311111Y316333D01*
G01X1311640Y318930D02*
X1312070Y321042D01*
G01X1307394Y303839D02*
X1310987Y321491D01*
G01X1312070Y321042D02*
X1312815Y322168D01*
G01X1314277Y324378D02*
X1317069Y328599D01*
G01X1310987Y321491D02*
X1316237Y329426D01*
G01X1317069Y328599D02*
X1318807Y329766D01*
G01D02*
X1319709Y329588D01*
G01X1321008Y331242D02*
X1330015Y337288D01*
G01X1316237Y329426D02*
X1329553Y338364D01*
G01X1330015Y337288D02*
X1336756Y338794D01*
G01X1339342Y339372D02*
X1341394Y339831D01*
G01X1329553Y338364D02*
X1351895Y343357D01*
G01X1300193Y314913D02*
X1297186Y299692D01*
G01X1296006Y299658D02*
X1299105Y315343D01*
G01X1300934Y316101D02*
X1300193Y314913D01*
G01X1299105Y315343D02*
X1299958Y316710D01*
G01X1320749Y347869D02*
X1310989Y332222D01*
G01X1309586Y329973D02*
X1308872Y328828D01*
G01X1307443Y326537D02*
X1306702Y325349D01*
G01X1305274Y323058D02*
X1304533Y321871D01*
G01X1303104Y319580D02*
X1302363Y318392D01*
G01X1299958Y316711D02*
X1319920Y348713D01*
G01X1293107Y300282D02*
X1295607Y290630D01*
G01X1296272Y288064D02*
X1296610Y286757D01*
G01X1297275Y284192D02*
X1297613Y282885D01*
G01X1296486Y317377D02*
X1295827Y314045D01*
G01X1295314Y311445D02*
X1295052Y310121D01*
G01X1294538Y307521D02*
X1293107Y300282D01*
G01X1291927Y300248D02*
X1295398Y317807D01*
G01X1311689Y341753D02*
X1310948Y340565D01*
G01X1309519Y338274D02*
X1308778Y337086D01*
G01X1307349Y334795D02*
X1296486Y317377D01*
G01X1295398Y317807D02*
X1315199Y349555D01*
G01X1305883Y342346D02*
X1291969Y320037D01*
G01X1307098Y342120D02*
X1303127Y335752D01*
G01X1305883Y342346D02*
X1291969Y320037D01*
G01X1301725Y333503D02*
X1301517Y333170D01*
G01X1305883Y342346D02*
X1291969Y320037D01*
G01X1301517Y333170D02*
X1301010Y332358D01*
G01X1305883Y342346D02*
X1291969Y320037D01*
G01X1299608Y330109D02*
X1298894Y328964D01*
G01X1305883Y342346D02*
X1291969Y320037D01*
G01X1297491Y326715D02*
X1296777Y325570D01*
G01X1305883Y342346D02*
X1291969Y320037D01*
G01X1295374Y323321D02*
X1293057Y319607D01*
G01X1291969Y320037D02*
X1288511Y302535D01*
G01X1293057Y319607D02*
X1292795Y318283D01*
G01X1291969Y320037D02*
X1288511Y302535D01*
G01X1292282Y315683D02*
X1292020Y314359D01*
G01X1291969Y320037D02*
X1288511Y302535D01*
G01X1291506Y311759D02*
X1289690Y302569D01*
G01X1290769Y282484D02*
X1286468Y299168D01*
G01D02*
X1291102Y322635D01*
G01X1285289Y299134D02*
X1290014Y323065D01*
G01X1291102Y322635D02*
X1291843Y323823D01*
G01X1293272Y326114D02*
X1294013Y327302D01*
G01X1295442Y329592D02*
X1296183Y330780D01*
G01X1297612Y333071D02*
X1298353Y334259D01*
G01X1299782Y336549D02*
X1300523Y337737D01*
G01X1301952Y340028D02*
X1303770Y342943D01*
G01X1290014Y323065D02*
X1302554Y343168D01*
G01X1311939Y280687D02*
X1310740Y284849D01*
G01X1312901Y281504D02*
X1311921Y284905D01*
G01X1310740Y284849D02*
X1311665Y289766D01*
G01X1311921Y284905D02*
X1312746Y289291D01*
G01X1311665Y289766D02*
X1313802Y292625D01*
G01X1312746Y289291D02*
X1314878Y292142D01*
G01X1313802Y292625D02*
X1314597Y296531D01*
G01X1314878Y292142D02*
X1315771Y296531D01*
G01X1314597D02*
X1313436Y302233D01*
G01X1315771Y296531D02*
X1315093Y299865D01*
G01X1313437Y302233D02*
X1313138Y303697D01*
G01X1314564Y302462D02*
X1314315Y303685D01*
G01X1313138Y303697D02*
X1314215Y308486D01*
G01X1314315Y303685D02*
X1315292Y308032D01*
G01X1314215Y308486D02*
X1315116Y309872D01*
G01X1315292Y308032D02*
X1315969Y309074D01*
G01X1315116Y309872D02*
X1316780Y311120D01*
G01X1315969Y309074D02*
X1317089Y309914D01*
G01X1315116Y309872D02*
X1316780Y311120D01*
G01X1317089Y309914D02*
X1317999Y309784D01*
G01X1316779Y311120D02*
X1334775Y324610D01*
G01X1319250Y311533D02*
X1320370Y312373D01*
G01X1316779Y311120D02*
X1334775Y324610D01*
G01X1320370Y312373D02*
X1321280Y312243D01*
G01X1316779Y311120D02*
X1334775Y324610D01*
G01X1322530Y313993D02*
X1323650Y314832D01*
G01X1316779Y311120D02*
X1334775Y324610D01*
G01X1323650Y314832D02*
X1324560Y314702D01*
G01X1316779Y311120D02*
X1334775Y324610D01*
G01X1325811Y316452D02*
X1326931Y317292D01*
G01X1316779Y311120D02*
X1334775Y324610D01*
G01X1326931Y317292D02*
X1327841Y317162D01*
G01X1316779Y311120D02*
X1334775Y324610D01*
G01X1329091Y318911D02*
X1332147Y321202D01*
G01X1316779Y311120D02*
X1334775Y324610D01*
G01X1332147Y321202D02*
X1333056Y321071D01*
G01X1316779Y311120D02*
X1334775Y324610D01*
G01X1334267Y322791D02*
X1335347Y323601D01*
G01X1334775Y324610D02*
X1351316Y331382D01*
G01X1335347Y323601D02*
X1351378Y330164D01*
G01X1306495Y280247D02*
X1305212Y284703D01*
G01X1307456Y281066D02*
X1306393Y284759D01*
G01X1305212Y284703D02*
X1305624Y286890D01*
G01X1306393Y284759D02*
X1306705Y286415D01*
G01X1305624Y286890D02*
X1311331Y294524D01*
G01X1306705Y286415D02*
X1312407Y294042D01*
G01X1311331Y294524D02*
X1311739Y296529D01*
G01X1312407Y294042D02*
X1312913Y296529D01*
G01X1311739D02*
X1310433Y302950D01*
G01X1312913Y296529D02*
X1311607Y302950D01*
G01X1310433D02*
X1313187Y316483D01*
G01X1311607Y302950D02*
X1314270Y316034D01*
G01X1313187Y316483D02*
X1313909Y317575D01*
G01X1314270Y316034D02*
X1314606Y316542D01*
G01X1313910Y317575D02*
X1319297Y325717D01*
G01X1316096Y318793D02*
X1316869Y319961D01*
G01X1313910Y317575D02*
X1319297Y325717D01*
G01X1318358Y322213D02*
X1320017Y324720D01*
G01X1319297Y325717D02*
X1358958Y336464D01*
G01X1320017Y324720D02*
X1321368Y325086D01*
G01X1319297Y325717D02*
X1358958Y336464D01*
G01X1323974Y325792D02*
X1325326Y326159D01*
G01X1319297Y325717D02*
X1358958Y336464D01*
G01X1327932Y326865D02*
X1329283Y327231D01*
G01X1319297Y325717D02*
X1358958Y336464D01*
G01X1331889Y327937D02*
X1333240Y328303D01*
G01X1319297Y325717D02*
X1358958Y336464D01*
G01X1335846Y329009D02*
X1337197Y329375D01*
G01X1319297Y325717D02*
X1358958Y336464D01*
G01X1339803Y330081D02*
X1341106Y330434D01*
G01X1319297Y325717D02*
X1358958Y336464D01*
G01X1319297Y325717D02*
X1358958Y336464D01*
G01X1319297Y325717D02*
X1358958Y336464D01*
G01X1319297Y325717D02*
X1358958Y336464D01*
G01X1302509Y284567D02*
X1303123Y287831D01*
G01X1303690Y284623D02*
X1304204Y287356D01*
G01X1303123Y287831D02*
X1308603Y295160D01*
G01X1304204Y287356D02*
X1309679Y294678D01*
G01X1308603Y295160D02*
X1308882Y296531D01*
G01X1309679Y294678D02*
X1310056Y296531D01*
G01X1308882D02*
X1307394Y303839D01*
G01X1310056Y296531D02*
X1308568Y303839D01*
G01X1307394D02*
X1310987Y321491D01*
G01X1308568Y303839D02*
X1309103Y306468D01*
G01X1307394Y303839D02*
X1310987Y321491D01*
G01X1309632Y309065D02*
X1311111Y316333D01*
G01X1307394Y303839D02*
X1310987Y321491D01*
G01X1311640Y318930D02*
X1312070Y321042D01*
G01X1310987Y321491D02*
X1316237Y329426D01*
G01X1312070Y321042D02*
X1312815Y322168D01*
G01X1310987Y321491D02*
X1316237Y329426D01*
G01X1314277Y324378D02*
X1317069Y328599D01*
G01X1316237Y329426D02*
X1329553Y338364D01*
G01X1317069Y328599D02*
X1318807Y329766D01*
G01X1316237Y329426D02*
X1329553Y338364D01*
G01X1318807Y329766D02*
X1319709Y329588D01*
G01X1316237Y329426D02*
X1329553Y338364D01*
G01X1321008Y331242D02*
X1330015Y337288D01*
G01X1329553Y338364D02*
X1351895Y343357D01*
G01X1330015Y337288D02*
X1336756Y338794D01*
G01X1329553Y338364D02*
X1351895Y343357D01*
G01X1339342Y339372D02*
X1341394Y339831D01*
G01X1329553Y338364D02*
X1351895Y343357D01*
G01X1329553Y338364D02*
X1351895Y343357D01*
G01X1329553Y338364D02*
X1351895Y343357D01*
G01X1299958Y316711D02*
X1319920Y348713D01*
G01X1320749Y347869D02*
X1310989Y332222D01*
G01X1299958Y316711D02*
X1319920Y348713D01*
G01X1309586Y329973D02*
X1308872Y328828D01*
G01X1299958Y316711D02*
X1319920Y348713D01*
G01X1307443Y326537D02*
X1306702Y325349D01*
G01X1299958Y316711D02*
X1319920Y348713D01*
G01X1305274Y323058D02*
X1304533Y321871D01*
G01X1299958Y316711D02*
X1319920Y348713D01*
G01X1303104Y319580D02*
X1302363Y318392D01*
G01X1299105Y315343D02*
X1299958Y316710D01*
G01X1300934Y316101D02*
X1300193Y314913D01*
G01X1296006Y299658D02*
X1299105Y315343D01*
G01X1300193Y314913D02*
X1297186Y299692D01*
G01X1295398Y317807D02*
X1315199Y349555D01*
G01X1295398Y317807D02*
X1315199Y349555D01*
G01X1295398Y317807D02*
X1315199Y349555D01*
G01X1311689Y341753D02*
X1310948Y340565D01*
G01X1295398Y317807D02*
X1315199Y349555D01*
G01X1309519Y338274D02*
X1308778Y337086D01*
G01X1295398Y317807D02*
X1315199Y349555D01*
G01X1307349Y334795D02*
X1296486Y317377D01*
G01X1291927Y300248D02*
X1295398Y317807D01*
G01X1296486Y317377D02*
X1295827Y314045D01*
G01X1291927Y300248D02*
X1295398Y317807D01*
G01X1295314Y311445D02*
X1295052Y310121D01*
G01X1291927Y300248D02*
X1295398Y317807D01*
G01X1294538Y307521D02*
X1293107Y300282D01*
G01D02*
X1295607Y290630D01*
G01X1296272Y288064D02*
X1296610Y286757D01*
G01X1297275Y284192D02*
X1297613Y282885D01*
G01X1307098Y342120D02*
X1303127Y335752D01*
G01X1301725Y333503D02*
X1301517Y333170D01*
G01D02*
X1301010Y332358D01*
G01X1299608Y330109D02*
X1298894Y328964D01*
G01X1297491Y326715D02*
X1296777Y325570D01*
G01X1295374Y323321D02*
X1293057Y319607D01*
G01X1305883Y342346D02*
X1291969Y320037D01*
G01X1293057Y319607D02*
X1292795Y318283D01*
G01X1292282Y315683D02*
X1292020Y314359D01*
G01X1291506Y311759D02*
X1289690Y302569D01*
G01X1291969Y320037D02*
X1288511Y302535D01*
G01X1290769Y282484D02*
X1286468Y299168D01*
G01X1285289Y299134D02*
X1290014Y323065D01*
G01X1286468Y299168D02*
X1291102Y322635D01*
G01X1290014Y323065D02*
X1302554Y343168D01*
G01X1291102Y322635D02*
X1291843Y323823D01*
G01X1290014Y323065D02*
X1302554Y343168D01*
G01X1293272Y326114D02*
X1294013Y327302D01*
G01X1290014Y323065D02*
X1302554Y343168D01*
G01X1295442Y329592D02*
X1296183Y330780D01*
G01X1290014Y323065D02*
X1302554Y343168D01*
G01X1297612Y333071D02*
X1298353Y334259D01*
G01X1290014Y323065D02*
X1302554Y343168D01*
G01X1299782Y336549D02*
X1300523Y337737D01*
G01X1290014Y323065D02*
X1302554Y343168D01*
G01X1301952Y340028D02*
X1303770Y342943D01*
G01X1319750Y283729D02*
Y286750D01*
G01X1320900Y284090D02*
Y286273D01*
G01X1319750Y286750D02*
X1320880Y287880D01*
G01X1320900Y286273D02*
X1321357Y286730D01*
G01X1320880Y287880D02*
X1323438D01*
G01X1321357Y286730D02*
X1323690D01*
G01X1323438Y287880D02*
X1325389Y288775D01*
G01X1323690Y286730D02*
X1326328Y287940D01*
G01X1325389Y288775D02*
X1336253Y322372D01*
G01X1326328Y287940D02*
X1329205Y296837D01*
G01X1325389Y288775D02*
X1336253Y322372D01*
G01X1330021Y299358D02*
X1330436Y300643D01*
G01X1325389Y288775D02*
X1336253Y322372D01*
G01X1331251Y303164D02*
X1337183Y321510D01*
G01X1336253Y322372D02*
X1351634Y328671D01*
G01X1337183Y321510D02*
X1351696Y327453D01*
G01X1320900Y284090D02*
Y286273D01*
G01X1319750Y283729D02*
Y286750D01*
G01X1320900Y286273D02*
X1321357Y286730D01*
G01X1319750Y286750D02*
X1320880Y287880D01*
G01X1321357Y286730D02*
X1323690D01*
G01X1320880Y287880D02*
X1323438D01*
G01X1323690Y286730D02*
X1326328Y287940D01*
G01X1323438Y287880D02*
X1325389Y288775D01*
G01X1326328Y287940D02*
X1329205Y296837D01*
G01X1330021Y299358D02*
X1330436Y300643D01*
G01X1331251Y303164D02*
X1337183Y321510D01*
G01X1325389Y288775D02*
X1336253Y322372D01*
G01X1337183Y321510D02*
X1351696Y327453D01*
G01X1336253Y322372D02*
X1351634Y328671D01*
G01X1339763Y295621D02*
X1360582Y286980D01*
G01X1361569Y287816D02*
X1340623Y296510D01*
G01X1338610Y298158D02*
X1339763Y295621D01*
G01X1340623Y296510D02*
X1339760Y298408D01*
G01X1338610Y300739D02*
Y298158D01*
G01X1339760Y298408D02*
Y300739D01*
G01Y298408D02*
Y300739D01*
G01X1338610D02*
Y298158D01*
G01X1340623Y296510D02*
X1339760Y298408D01*
G01X1338610Y298158D02*
X1339763Y295621D01*
G01X1361569Y287816D02*
X1340623Y296510D01*
G01X1339763Y295621D02*
X1360582Y286980D01*
G01X1328157Y352312D02*
X1320749Y347869D01*
G01X1319920Y348713D02*
X1327736Y353401D01*
G01X1337364Y354153D02*
X1328157Y352312D01*
G01X1327736Y353401D02*
X1337392Y355332D01*
G01X1349571Y351093D02*
X1337364Y354153D01*
G01X1337392Y355332D02*
X1349599Y352272D01*
G01X1316028Y348711D02*
X1315287Y347523D01*
G01X1313858Y345232D02*
X1313118Y344044D01*
G01X1326527Y355007D02*
X1316028Y348711D01*
G01X1315199Y349555D02*
X1326106Y356096D01*
G01X1337298Y357162D02*
X1326527Y355007D01*
G01X1326106Y356096D02*
X1337326Y358341D01*
G01X1349701Y354053D02*
X1337298Y357162D01*
G01X1337326Y358341D02*
X1349729Y355232D01*
G01X1303663Y409645D02*
X1305275Y401346D01*
G01X1304835Y409645D02*
X1306447Y401346D01*
G01X1305275D02*
X1302153Y385284D01*
G01X1306447Y401346D02*
X1303325Y385284D01*
G01X1302153D02*
X1304778Y371784D01*
G01X1303325Y385284D02*
X1305950Y371784D01*
G01X1304778D02*
X1302469Y359911D01*
G01X1305950Y371784D02*
X1303641Y359911D01*
G01X1302469D02*
X1305881Y342346D01*
G01X1303641Y359911D02*
X1307098Y342120D01*
G01X1303770Y342943D02*
X1300424Y360160D01*
G01X1302554Y343168D02*
X1299252Y360160D01*
G01X1300424D02*
X1302652Y371627D01*
G01X1299252Y360160D02*
X1301480Y371627D01*
G01X1302652D02*
X1300072Y384900D01*
G01X1301480Y371627D02*
X1298900Y384900D01*
G01X1300072D02*
X1302713Y398487D01*
G01X1298900Y384900D02*
X1301541Y398487D01*
G01X1302713D02*
X1300453Y410113D01*
G01X1301541Y398487D02*
X1299279Y410123D01*
G01X1337392Y355332D02*
X1349599Y352272D01*
G01X1349571Y351093D02*
X1337364Y354153D01*
G01X1327736Y353401D02*
X1337392Y355332D01*
G01X1337364Y354153D02*
X1328157Y352312D01*
G01X1319920Y348713D02*
X1327736Y353401D01*
G01X1328157Y352312D02*
X1320749Y347869D01*
G01X1337326Y358341D02*
X1349729Y355232D01*
G01X1349701Y354053D02*
X1337298Y357162D01*
G01X1326106Y356096D02*
X1337326Y358341D01*
G01X1337298Y357162D02*
X1326527Y355007D01*
G01X1315199Y349555D02*
X1326106Y356096D01*
G01X1326527Y355007D02*
X1316028Y348711D01*
G01D02*
X1315287Y347523D01*
G01X1313858Y345232D02*
X1313118Y344044D01*
G01X1304835Y409645D02*
X1306447Y401346D01*
G01X1303663Y409645D02*
X1305275Y401346D01*
G01X1306447D02*
X1303325Y385284D01*
G01X1305275Y401346D02*
X1302153Y385284D01*
G01X1303325D02*
X1305950Y371784D01*
G01X1302153Y385284D02*
X1304778Y371784D01*
G01X1305950D02*
X1303641Y359911D01*
G01X1304778Y371784D02*
X1302469Y359911D01*
G01X1303641D02*
X1307098Y342120D01*
G01X1302469Y359911D02*
X1305881Y342346D01*
G01X1302554Y343168D02*
X1299252Y360160D01*
G01X1303770Y342943D02*
X1300424Y360160D01*
G01X1299252D02*
X1301480Y371627D01*
G01X1300424Y360160D02*
X1302652Y371627D01*
G01X1301480D02*
X1298900Y384900D01*
G01X1302652Y371627D02*
X1300072Y384900D01*
G01X1298900D02*
X1301541Y398487D01*
G01X1300072Y384900D02*
X1302713Y398487D01*
G01X1301541D02*
X1299279Y410123D01*
G01X1302713Y398487D02*
X1300453Y410113D01*
G01X1293705Y474915D02*
X1284280Y461509D01*
G01X1294547Y474112D02*
X1285341Y461017D01*
G01X1295126Y468240D02*
X1293418Y461043D01*
G01X1294100Y468900D02*
X1292228Y461012D01*
G01X1293418Y461043D02*
X1295405Y454275D01*
G01X1295406D02*
X1295500Y453955D01*
G01X1292228Y461012D02*
X1294301Y453951D01*
G01X1295500Y453955D02*
X1290670Y437110D01*
G01X1294302Y453951D02*
X1289626Y437644D01*
G01X1290670Y437110D02*
X1288540Y434405D01*
G01X1289626Y437644D02*
X1287808Y435335D01*
G01X1282120Y463260D02*
X1292742Y476664D01*
G01X1291926Y477488D02*
X1281048Y463762D01*
G01X1281851Y461937D02*
X1282120Y463260D01*
G01X1343336Y450767D02*
X1341146Y449450D01*
G01X1342410Y451553D02*
X1340826Y450600D01*
G01X1341146Y449450D02*
X1333877D01*
G01X1340826Y450600D02*
X1333726D01*
G01X1333877Y449450D02*
X1327108Y447645D01*
G01X1333726Y450600D02*
X1327085Y448830D01*
G01X1327108Y447645D02*
X1321761Y448850D01*
G01X1327085Y448830D02*
X1321756Y450030D01*
G01X1321761Y448850D02*
X1304718Y444859D01*
G01X1321756Y450030D02*
X1304136Y445905D01*
G01X1304718Y444859D02*
X1303245Y443386D01*
G01X1304136Y445905D02*
X1302095Y443863D01*
G01X1303245Y443386D02*
Y439185D01*
G01X1302095Y443863D02*
Y439662D01*
G01X1303245Y439185D02*
X1292882Y428822D01*
G01X1302095Y439662D02*
X1292217Y429785D01*
G01X1297866Y466610D02*
X1296628Y461389D01*
G01X1296822Y467193D02*
X1295444Y461381D01*
G01X1296628Y461389D02*
X1298538Y453810D01*
G01X1295444Y461381D02*
X1297349Y453820D01*
G01X1298538Y453810D02*
X1293482Y435050D01*
G01X1297349Y453820D02*
X1292426Y435556D01*
G01X1293482Y435050D02*
X1291250Y431999D01*
G01X1292427Y435556D02*
X1290497Y432919D01*
G01X1294547Y474112D02*
X1285341Y461017D01*
G01X1293705Y474915D02*
X1284280Y461509D01*
G01X1294100Y468900D02*
X1292228Y461012D01*
G01X1295126Y468240D02*
X1293418Y461043D01*
G01X1292228Y461012D02*
X1294301Y453951D01*
G01X1293418Y461043D02*
X1295405Y454275D01*
G01X1292228Y461012D02*
X1294301Y453951D01*
G01X1295406Y454275D02*
X1295500Y453955D01*
G01X1294302Y453951D02*
X1289626Y437644D01*
G01X1295500Y453955D02*
X1290670Y437110D01*
G01X1289626Y437644D02*
X1287808Y435335D01*
G01X1290670Y437110D02*
X1288540Y434405D01*
G01X1281851Y461937D02*
X1282120Y463260D01*
G01X1291926Y477488D02*
X1281048Y463762D01*
G01X1282120Y463260D02*
X1292742Y476664D01*
G01X1342410Y451553D02*
X1340826Y450600D01*
G01X1343336Y450767D02*
X1341146Y449450D01*
G01X1340826Y450600D02*
X1333726D01*
G01X1341146Y449450D02*
X1333877D01*
G01X1333726Y450600D02*
X1327085Y448830D01*
G01X1333877Y449450D02*
X1327108Y447645D01*
G01X1327085Y448830D02*
X1321756Y450030D01*
G01X1327108Y447645D02*
X1321761Y448850D01*
G01X1321756Y450030D02*
X1304136Y445905D01*
G01X1321761Y448850D02*
X1304718Y444859D01*
G01X1304136Y445905D02*
X1302095Y443863D01*
G01X1304718Y444859D02*
X1303245Y443386D01*
G01X1302095Y443863D02*
Y439662D01*
G01X1303245Y443386D02*
Y439185D01*
G01X1302095Y439662D02*
X1292217Y429785D01*
G01X1303245Y439185D02*
X1292882Y428822D01*
G01X1296822Y467193D02*
X1295444Y461381D01*
G01X1297866Y466610D02*
X1296628Y461389D01*
G01X1295444Y461381D02*
X1297349Y453820D01*
G01X1296628Y461389D02*
X1298538Y453810D01*
G01X1297349Y453820D02*
X1292426Y435556D01*
G01X1298538Y453810D02*
X1293482Y435050D01*
G01X1292427Y435556D02*
X1290497Y432919D01*
G01X1293482Y435050D02*
X1291250Y431999D01*
G01X1343226Y440655D02*
X1338682Y439772D01*
G01X1343337Y439505D02*
X1338682Y438600D01*
G01Y439772D02*
X1334129Y440657D01*
G01X1338682Y438600D02*
X1334129Y439485D01*
G01Y440657D02*
X1330152Y439884D01*
G01X1334129Y439485D02*
X1330601Y438799D01*
G01X1330152Y439884D02*
X1326500Y437422D01*
G01X1330601Y438799D02*
X1326949Y436337D01*
G01X1326500Y437422D02*
X1316484Y435475D01*
G01X1326949Y436337D02*
X1316595Y434325D01*
G01X1316484Y435475D02*
X1313349D01*
G01X1316595Y434325D02*
X1313826D01*
G01X1313349Y435475D02*
X1311925Y434051D01*
G01X1313826Y434325D02*
X1313075Y433574D01*
G01X1311925Y434051D02*
Y426201D01*
G01X1313075Y433574D02*
Y425849D01*
G01X1311925Y426201D02*
X1309821Y423082D01*
G01X1313075Y425849D02*
X1310650Y422253D01*
G01X1309821Y423082D02*
X1305735Y420326D01*
G01X1310650Y422253D02*
X1306774Y419639D01*
G01X1305735Y420326D02*
X1303663Y409645D01*
G01X1306774Y419639D02*
X1304835Y409645D01*
G01X1300453Y410113D02*
X1303000Y422000D01*
G01X1299279Y410123D02*
X1301963Y422651D01*
G01X1303000Y422000D02*
X1308200Y426039D01*
G01X1301963Y422651D02*
X1307050Y426602D01*
G01X1308200Y426039D02*
Y435073D01*
G01X1307050Y426602D02*
Y435550D01*
G01X1308200Y435073D02*
X1310433Y437306D01*
G01X1307050Y435550D02*
X1309956Y438456D01*
G01X1310433Y437306D02*
X1316024D01*
G01X1309956Y438456D02*
X1315913D01*
G01X1316024Y437306D02*
X1325543Y439154D01*
G01X1315913Y438456D02*
X1325094Y440239D01*
G01X1325543Y439154D02*
X1327514Y440483D01*
G01X1325094Y440239D02*
X1326779Y441375D01*
G01X1327514Y440483D02*
X1328200Y441169D01*
G01X1326779Y441375D02*
X1327050Y441646D01*
G01X1328200Y441169D02*
Y443600D01*
G01X1327050Y441646D02*
Y444077D01*
G01X1328200Y443600D02*
X1328976Y444376D01*
G01X1327050Y444077D02*
X1328499Y445526D01*
G01X1328976Y444376D02*
X1341600D01*
G01X1328499Y445526D02*
X1341489D01*
G01X1341600Y444376D02*
X1343347Y444716D01*
G01X1341489Y445526D02*
X1342897Y445801D01*
G01X1341600Y444376D02*
X1343347Y444716D01*
G01X1343337Y439505D02*
X1338682Y438600D01*
G01X1343226Y440655D02*
X1338682Y439772D01*
G01Y438600D02*
X1334129Y439485D01*
G01X1338682Y439772D02*
X1334129Y440657D01*
G01Y439485D02*
X1330601Y438799D01*
G01X1334129Y440657D02*
X1330152Y439884D01*
G01X1330601Y438799D02*
X1326949Y436337D01*
G01X1330152Y439884D02*
X1326500Y437422D01*
G01X1326949Y436337D02*
X1316595Y434325D01*
G01X1326500Y437422D02*
X1316484Y435475D01*
G01X1316595Y434325D02*
X1313826D01*
G01X1316484Y435475D02*
X1313349D01*
G01X1313826Y434325D02*
X1313075Y433574D01*
G01X1313349Y435475D02*
X1311925Y434051D01*
G01X1313075Y433574D02*
Y425849D01*
G01X1311925Y434051D02*
Y426201D01*
G01X1313075Y425849D02*
X1310650Y422253D01*
G01X1311925Y426201D02*
X1309821Y423082D01*
G01X1310650Y422253D02*
X1306774Y419639D01*
G01X1309821Y423082D02*
X1305735Y420326D01*
G01X1306774Y419639D02*
X1304835Y409645D01*
G01X1305735Y420326D02*
X1303663Y409645D01*
G01X1299279Y410123D02*
X1301963Y422651D01*
G01X1300453Y410113D02*
X1303000Y422000D01*
G01X1301963Y422651D02*
X1307050Y426602D01*
G01X1303000Y422000D02*
X1308200Y426039D01*
G01X1307050Y426602D02*
Y435550D01*
G01X1308200Y426039D02*
Y435073D01*
G01X1307050Y435550D02*
X1309956Y438456D01*
G01X1308200Y435073D02*
X1310433Y437306D01*
G01X1309956Y438456D02*
X1315913D01*
G01X1310433Y437306D02*
X1316024D01*
G01X1315913Y438456D02*
X1325094Y440239D01*
G01X1316024Y437306D02*
X1325543Y439154D01*
G01X1325094Y440239D02*
X1326779Y441375D01*
G01X1325543Y439154D02*
X1327514Y440483D01*
G01X1326779Y441375D02*
X1327050Y441646D01*
G01X1327514Y440483D02*
X1328200Y441169D01*
G01X1327050Y441646D02*
Y444077D01*
G01X1328200Y441169D02*
Y443600D01*
G01X1327050Y444077D02*
X1328499Y445526D01*
G01X1328200Y443600D02*
X1328976Y444376D01*
G01X1328499Y445526D02*
X1341489D01*
G01X1328976Y444376D02*
X1341600D01*
G01X1341489Y445526D02*
X1342897Y445801D01*
G01X1341600Y444376D02*
X1343347Y444716D01*
G01X1348067Y481612D02*
X1341023Y480115D01*
G01Y480114D02*
X1338894Y479662D01*
G01X1341262Y478989D02*
X1338894Y478486D01*
G01Y479662D02*
X1317955Y484111D01*
G01X1338894Y478486D02*
X1317994Y482926D01*
G01X1317955Y484111D02*
X1298439Y478593D01*
G01X1317994Y482926D02*
X1298968Y477547D01*
G01X1298439Y478593D02*
X1293705Y474915D01*
G01X1298968Y477547D02*
X1294547Y474112D01*
G01X1344590Y470186D02*
X1334844Y476713D01*
G01X1345040Y471269D02*
X1335300Y477792D01*
G01X1334844Y476713D02*
X1320126Y479833D01*
G01X1335300Y477792D02*
X1320043Y481027D01*
G01X1320126Y479833D02*
X1301227Y472981D01*
G01X1320043Y481027D02*
X1300664Y474001D01*
G01X1301227Y472981D02*
X1295126Y468240D01*
G01X1300664Y474001D02*
X1294100Y468900D01*
G01X1338932Y481060D02*
X1348326Y483053D01*
G01X1348319Y484228D02*
X1338932Y482236D01*
G01X1315700Y485995D02*
X1338932Y481060D01*
G01Y482236D02*
X1315653Y487181D01*
G01X1297996Y480747D02*
X1300839Y481590D01*
G01X1303380Y482343D02*
X1304674Y482727D01*
G01X1307215Y483480D02*
X1315700Y485995D01*
G01X1315653Y487181D02*
X1297461Y481788D01*
G01X1292742Y476664D02*
X1297996Y480747D01*
G01X1297461Y481788D02*
X1291926Y477488D01*
G01X1348138Y487732D02*
X1336373Y485375D01*
G01X1348121Y486555D02*
X1336366Y484200D01*
G01X1336373Y485375D02*
X1308944Y491202D01*
G01X1336366Y484200D02*
X1308975Y490019D01*
G01X1308944Y491202D02*
X1288635Y485765D01*
G01X1308975Y490019D02*
X1289325Y484759D01*
G01X1288635Y485765D02*
X1286639Y483030D01*
G01X1289325Y484759D02*
X1287668Y482489D01*
G01X1286639Y483030D02*
X1282238Y470485D01*
G01X1287668Y482489D02*
X1283268Y469945D01*
G01X1281644Y487630D02*
X1286477Y494253D01*
G01X1282673Y487089D02*
X1287167Y493247D01*
G01X1286477Y494253D02*
X1300781Y498080D01*
G01X1287167Y493247D02*
X1300812Y496897D01*
G01X1300781Y498080D02*
X1333060Y491223D01*
G01X1300812Y496897D02*
X1333051Y490049D01*
G01X1333060Y491223D02*
X1348464Y494236D01*
G01X1333051Y490049D02*
X1348456Y493062D01*
G01X1348920Y490861D02*
X1335262Y488174D01*
G01X1348913Y489687D02*
X1335253Y487000D01*
G01X1335262Y488174D02*
X1308036Y493958D01*
G01X1335253Y487000D02*
X1308067Y492775D01*
G01X1308036Y493958D02*
X1286451Y488181D01*
G01X1308067Y492775D02*
X1287141Y487175D01*
G01X1286451Y488181D02*
X1283984Y484800D01*
G01X1287141Y487175D02*
X1285013Y484259D01*
G01X1342500Y467418D02*
X1338579Y470043D01*
G01D02*
X1338577D01*
G01X1342950Y468501D02*
X1339029Y471126D01*
G01X1338579Y470043D02*
X1338577D01*
G01D02*
X1336528Y470452D01*
G01X1333929Y470971D02*
X1331814Y471392D01*
G01Y471393D02*
X1329236Y471908D01*
G01X1339029Y471126D02*
X1329223Y473084D01*
G01X1329236Y471908D02*
X1325546Y471087D01*
G01X1329223Y473084D02*
X1325021Y472149D01*
G01X1325546Y471087D02*
X1323259Y469178D01*
G01X1325021Y472149D02*
X1322769Y470267D01*
G01X1323259Y469178D02*
X1311203Y467348D01*
G01X1322769Y470267D02*
X1311230Y468516D01*
G01X1311203Y467348D02*
X1302952Y468999D01*
G01X1311230Y468516D02*
X1302935Y470176D01*
G01X1302952Y468999D02*
X1299447Y468190D01*
G01X1302935Y470176D02*
X1298867Y469237D01*
G01X1299447Y468190D02*
X1297866Y466610D01*
G01X1298867Y469237D02*
X1296822Y467193D01*
G01X1348067Y481612D02*
X1341023Y480115D01*
G01X1341262Y478989D02*
X1338894Y478486D01*
G01X1341023Y480114D02*
X1338894Y479662D01*
G01Y478486D02*
X1317994Y482926D01*
G01X1338894Y479662D02*
X1317955Y484111D01*
G01X1317994Y482926D02*
X1298968Y477547D01*
G01X1317955Y484111D02*
X1298439Y478593D01*
G01X1298968Y477547D02*
X1294547Y474112D01*
G01X1298439Y478593D02*
X1293705Y474915D01*
G01X1345040Y471269D02*
X1335300Y477792D01*
G01X1344590Y470186D02*
X1334844Y476713D01*
G01X1335300Y477792D02*
X1320043Y481027D01*
G01X1334844Y476713D02*
X1320126Y479833D01*
G01X1320043Y481027D02*
X1300664Y474001D01*
G01X1320126Y479833D02*
X1301227Y472981D01*
G01X1300664Y474001D02*
X1294100Y468900D01*
G01X1301227Y472981D02*
X1295126Y468240D01*
G01X1297461Y481788D02*
X1291926Y477488D01*
G01X1292742Y476664D02*
X1297996Y480747D01*
G01X1315653Y487181D02*
X1297461Y481788D01*
G01X1297996Y480747D02*
X1300839Y481590D01*
G01X1315653Y487181D02*
X1297461Y481788D01*
G01X1303380Y482343D02*
X1304674Y482727D01*
G01X1315653Y487181D02*
X1297461Y481788D01*
G01X1307215Y483480D02*
X1315700Y485995D01*
G01X1338932Y482236D02*
X1315653Y487181D01*
G01X1315700Y485995D02*
X1338932Y481060D01*
G01X1348319Y484228D02*
X1338932Y482236D01*
G01Y481060D02*
X1348326Y483053D01*
G01X1348121Y486555D02*
X1336366Y484200D01*
G01X1348138Y487732D02*
X1336373Y485375D01*
G01X1336366Y484200D02*
X1308975Y490019D01*
G01X1336373Y485375D02*
X1308944Y491202D01*
G01X1308975Y490019D02*
X1289325Y484759D01*
G01X1308944Y491202D02*
X1288635Y485765D01*
G01X1289325Y484759D02*
X1287668Y482489D01*
G01X1288635Y485765D02*
X1286639Y483030D01*
G01X1287668Y482489D02*
X1283268Y469945D01*
G01X1286639Y483030D02*
X1282238Y470485D01*
G01X1282673Y487089D02*
X1287167Y493247D01*
G01X1281644Y487630D02*
X1286477Y494253D01*
G01X1287167Y493247D02*
X1300812Y496897D01*
G01X1286477Y494253D02*
X1300781Y498080D01*
G01X1300812Y496897D02*
X1333051Y490049D01*
G01X1300781Y498080D02*
X1333060Y491223D01*
G01X1333051Y490049D02*
X1348456Y493062D01*
G01X1333060Y491223D02*
X1348464Y494236D01*
G01X1348913Y489687D02*
X1335253Y487000D01*
G01X1348920Y490861D02*
X1335262Y488174D01*
G01X1335253Y487000D02*
X1308067Y492775D01*
G01X1335262Y488174D02*
X1308036Y493958D01*
G01X1308067Y492775D02*
X1287141Y487175D01*
G01X1308036Y493958D02*
X1286451Y488181D01*
G01X1287141Y487175D02*
X1285013Y484259D01*
G01X1286451Y488181D02*
X1283984Y484800D01*
G01X1342950Y468501D02*
X1339029Y471126D01*
G01X1342500Y467418D02*
X1338579Y470043D01*
G01X1342950Y468501D02*
X1339029Y471126D01*
G01D02*
X1329223Y473084D01*
G01X1338579Y470043D02*
X1338577D01*
G01X1339029Y471126D02*
X1329223Y473084D01*
G01X1338577Y470043D02*
X1336528Y470452D01*
G01X1339029Y471126D02*
X1329223Y473084D01*
G01X1333929Y470971D02*
X1331814Y471392D01*
G01X1339029Y471126D02*
X1329223Y473084D01*
G01X1331814Y471393D02*
X1329236Y471908D01*
G01X1329223Y473084D02*
X1325021Y472149D01*
G01X1329236Y471908D02*
X1325546Y471087D01*
G01X1325021Y472149D02*
X1322769Y470267D01*
G01X1325546Y471087D02*
X1323259Y469178D01*
G01X1322769Y470267D02*
X1311230Y468516D01*
G01X1323259Y469178D02*
X1311203Y467348D01*
G01X1311230Y468516D02*
X1302935Y470176D01*
G01X1311203Y467348D02*
X1302952Y468999D01*
G01X1302935Y470176D02*
X1298867Y469237D01*
G01X1302952Y468999D02*
X1299447Y468190D01*
G01X1298867Y469237D02*
X1296822Y467193D01*
G01X1299447Y468190D02*
X1297866Y466610D01*
G01X1383200Y180047D02*
Y144479D01*
G01X1382050Y179698D02*
Y144164D01*
G01X1383200Y144479D02*
X1384312Y142596D01*
G01X1382050Y144164D02*
X1383524Y141668D01*
G01X1384312Y142596D02*
X1395138Y138390D01*
G01X1383524Y141668D02*
X1394629Y137354D01*
G01X1395138Y138390D02*
X1401099Y134798D01*
G01X1394629Y137354D02*
X1400284Y133945D01*
G01X1401099Y134798D02*
X1406217Y127118D01*
G01X1400284Y133945D02*
X1405137Y126663D01*
G01X1382050Y179698D02*
Y144164D01*
G01X1383200Y180047D02*
Y144479D01*
G01X1382050Y144164D02*
X1383524Y141668D01*
G01X1383200Y144479D02*
X1384312Y142596D01*
G01X1383524Y141668D02*
X1394629Y137354D01*
G01X1384312Y142596D02*
X1395138Y138390D01*
G01X1394629Y137354D02*
X1400284Y133945D01*
G01X1395138Y138390D02*
X1401099Y134798D01*
G01X1400284Y133945D02*
X1405137Y126663D01*
G01X1401099Y134798D02*
X1406217Y127118D01*
G01X1386950Y178324D02*
Y153463D01*
G01X1388100Y178673D02*
Y153812D01*
G01X1386950Y153463D02*
X1394990Y141400D01*
G01X1388100Y153812D02*
X1395805Y142253D01*
G01X1394990Y141400D02*
X1401719Y137344D01*
G01X1395805Y142253D02*
X1402534Y138197D01*
G01X1401719Y137344D02*
X1407170Y129162D01*
G01X1402534Y138197D02*
X1408250Y129617D01*
G01X1392750Y174600D02*
Y149901D01*
G01X1393900Y174949D02*
Y150250D01*
G01X1392750Y149901D02*
X1396988Y143541D01*
G01X1393900Y150250D02*
X1397803Y144394D01*
G01X1396988Y143541D02*
X1403216Y139789D01*
G01X1397803Y144394D02*
X1404031Y140642D01*
G01X1403216Y139789D02*
X1409475Y130402D01*
G01X1388100Y178673D02*
Y153812D01*
G01X1386950Y178324D02*
Y153463D01*
G01X1388100Y153812D02*
X1395805Y142253D01*
G01X1386950Y153463D02*
X1394990Y141400D01*
G01X1395805Y142253D02*
X1402534Y138197D01*
G01X1394990Y141400D02*
X1401719Y137344D01*
G01X1402534Y138197D02*
X1408250Y129617D01*
G01X1401719Y137344D02*
X1407170Y129162D01*
G01X1393900Y174949D02*
Y150250D01*
G01X1392750Y174600D02*
Y149901D01*
G01X1393900Y150250D02*
X1397803Y144394D01*
G01X1392750Y149901D02*
X1396988Y143541D01*
G01X1397803Y144394D02*
X1404031Y140642D01*
G01X1396988Y143541D02*
X1403216Y139789D01*
G01D02*
X1409475Y130402D01*
G01X1395250Y175600D02*
Y150752D01*
G01X1396400Y175949D02*
Y151101D01*
G01X1395250Y150752D02*
X1398579Y145756D01*
G01X1396400Y151101D02*
X1399537Y146395D01*
G01X1398943Y145410D02*
X1404957Y141785D01*
G01X1399537Y146395D02*
X1405773Y142637D01*
G01X1396400Y175949D02*
Y151101D01*
G01X1395250Y175600D02*
Y150752D01*
G01X1396400Y151101D02*
X1399537Y146395D01*
G01X1395250Y150752D02*
X1398579Y145756D01*
G01X1399537Y146395D02*
X1405773Y142637D01*
G01X1398943Y145410D02*
X1404957Y141785D01*
G01X1363110Y214835D02*
X1364393Y212912D01*
G01X1362419Y213798D02*
X1363309Y212462D01*
G01X1364393Y212912D02*
X1365721Y206275D01*
G01X1363309Y212462D02*
X1364638Y205826D01*
G01X1365721Y206275D02*
X1383200Y180047D01*
G01X1364638Y205826D02*
X1364763Y205637D01*
G01X1365721Y206275D02*
X1383200Y180047D01*
G01X1364764Y205637D02*
X1382050Y179698D01*
G01X1362419Y213798D02*
X1363309Y212462D01*
G01X1363110Y214835D02*
X1364393Y212912D01*
G01X1363309Y212462D02*
X1364638Y205826D01*
G01X1364393Y212912D02*
X1365721Y206275D01*
G01X1364638Y205826D02*
X1364763Y205637D01*
G01X1364764D02*
X1382050Y179698D01*
G01X1365721Y206275D02*
X1383200Y180047D01*
G01X1366640Y215656D02*
X1370408Y210010D01*
G01X1367331Y216693D02*
X1371492Y210459D01*
G01X1370408Y210010D02*
X1372364Y200204D01*
G01X1371492Y210459D02*
X1373448Y200653D01*
G01X1372364Y200204D02*
X1386950Y178324D01*
G01X1373448Y200653D02*
X1388100Y178673D01*
G01X1368357Y218142D02*
X1373176Y210910D01*
G01X1369048Y219179D02*
X1374260Y211359D01*
G01X1373176Y210910D02*
X1375162Y200983D01*
G01X1374260Y211359D02*
X1376245Y201432D01*
G01X1375162Y200983D02*
X1375287Y200794D01*
G01X1375288D02*
X1392750Y174600D01*
G01X1376245Y201432D02*
X1393900Y174949D01*
G01X1367331Y216693D02*
X1371492Y210459D01*
G01X1366640Y215656D02*
X1370408Y210010D01*
G01X1371492Y210459D02*
X1373448Y200653D01*
G01X1370408Y210010D02*
X1372364Y200204D01*
G01X1373448Y200653D02*
X1388100Y178673D01*
G01X1372364Y200204D02*
X1386950Y178324D01*
G01X1369048Y219179D02*
X1374260Y211359D01*
G01X1368357Y218142D02*
X1373176Y210910D01*
G01X1374260Y211359D02*
X1376245Y201432D01*
G01X1373176Y210910D02*
X1375162Y200983D01*
G01X1376245Y201432D02*
X1393900Y174949D01*
G01X1375162Y200983D02*
X1375287Y200794D01*
G01X1376245Y201432D02*
X1393900Y174949D01*
G01X1375288Y200794D02*
X1392750Y174600D01*
G01X1398290Y200484D02*
X1414510Y176281D01*
G01X1415593Y176731D02*
X1399373Y200934D01*
G01X1396967Y207100D02*
X1398290Y200484D01*
G01X1399373Y200934D02*
X1398140Y207100D01*
G01X1398063Y212587D02*
X1396967Y207100D01*
G01X1398140D02*
X1399098Y211893D01*
G01X1407169Y218649D02*
X1398063Y212587D01*
G01X1399098Y211893D02*
X1408204Y217956D01*
G01X1399098Y211893D02*
X1408204Y217956D01*
G01X1407169Y218649D02*
X1398063Y212587D01*
G01X1398140Y207100D02*
X1399098Y211893D01*
G01X1398063Y212587D02*
X1396967Y207100D01*
G01X1399373Y200934D02*
X1398140Y207100D01*
G01X1396967D02*
X1398290Y200484D01*
G01X1415593Y176731D02*
X1399373Y200934D01*
G01X1398290Y200484D02*
X1414510Y176281D01*
G01X1370832Y220708D02*
X1375601Y213557D01*
G01X1371526Y221742D02*
X1376684Y214006D01*
G01X1375601Y213557D02*
X1378024Y201445D01*
G01X1376684Y214006D02*
X1379107Y201894D01*
G01X1378024Y201445D02*
X1395250Y175600D01*
G01X1379107Y201894D02*
X1396400Y175949D01*
G01X1371526Y221742D02*
X1376684Y214006D01*
G01X1370832Y220708D02*
X1375601Y213557D01*
G01X1376684Y214006D02*
X1379107Y201894D01*
G01X1375601Y213557D02*
X1378024Y201445D01*
G01X1379107Y201894D02*
X1396400Y175949D01*
G01X1378024Y201445D02*
X1395250Y175600D01*
G01X1400789Y201485D02*
X1416857Y177373D01*
G01X1417941Y177822D02*
X1401873Y201934D01*
G01X1399646Y207209D02*
X1400789Y201485D01*
G01X1401873Y201934D02*
X1400819Y207209D01*
G01X1400329Y210630D02*
X1399646Y207209D01*
G01X1400819D02*
X1401364Y209936D01*
G01X1409379Y216654D02*
X1400329Y210630D01*
G01X1401364Y209936D02*
X1410414Y215960D01*
G01X1401364Y209936D02*
X1410414Y215960D01*
G01X1409379Y216654D02*
X1400329Y210630D01*
G01X1400819Y207209D02*
X1401364Y209936D01*
G01X1400329Y210630D02*
X1399646Y207209D01*
G01X1401873Y201934D02*
X1400819Y207209D01*
G01X1399646D02*
X1400789Y201485D01*
G01X1417941Y177822D02*
X1401873Y201934D01*
G01X1400789Y201485D02*
X1416857Y177373D01*
G01X1372286Y223349D02*
X1377992Y214790D01*
G01X1372979Y224384D02*
X1379075Y215239D01*
G01X1377992Y214790D02*
X1380413Y202687D01*
G01X1379075Y215239D02*
X1381496Y203136D01*
G01X1380413Y202687D02*
X1405713Y164753D01*
G01X1381496Y203136D02*
X1406796Y165202D01*
G01X1372075Y229254D02*
X1380076Y217818D01*
G01D02*
X1382872Y203833D01*
G01X1381157Y218280D02*
X1383956Y204282D01*
G01X1382872Y203833D02*
X1408072Y165994D01*
G01X1383956Y204282D02*
X1409156Y166443D01*
G01X1384343Y228860D02*
X1390722Y196977D01*
G01X1385424Y229323D02*
X1391805Y197428D01*
G01X1390722Y196977D02*
X1410237Y167971D01*
G01X1391805Y197428D02*
X1411320Y168422D01*
G01X1412590Y169282D02*
X1397961Y191235D01*
G01X1413674Y169731D02*
X1399006Y191741D01*
G01X1397961Y191235D02*
X1389353Y217776D01*
G01X1399006Y191741D02*
X1390541Y217842D01*
G01X1389353Y217776D02*
X1391242Y226994D01*
G01X1390541Y217842D02*
X1392321Y226529D01*
G01X1372979Y224384D02*
X1379075Y215239D01*
G01X1372286Y223349D02*
X1377992Y214790D01*
G01X1379075Y215239D02*
X1381496Y203136D01*
G01X1377992Y214790D02*
X1380413Y202687D01*
G01X1381496Y203136D02*
X1406796Y165202D01*
G01X1380413Y202687D02*
X1405713Y164753D01*
G01X1372075Y229254D02*
X1380076Y217818D01*
G01X1381157Y218280D02*
X1383956Y204282D01*
G01X1380076Y217818D02*
X1382872Y203833D01*
G01X1383956Y204282D02*
X1409156Y166443D01*
G01X1382872Y203833D02*
X1408072Y165994D01*
G01X1385424Y229323D02*
X1391805Y197428D01*
G01X1384343Y228860D02*
X1390722Y196977D01*
G01X1391805Y197428D02*
X1411320Y168422D01*
G01X1390722Y196977D02*
X1410237Y167971D01*
G01X1413674Y169731D02*
X1399006Y191741D01*
G01X1412590Y169282D02*
X1397961Y191235D01*
G01X1399006Y191741D02*
X1390541Y217842D01*
G01X1397961Y191235D02*
X1389353Y217776D01*
G01X1390541Y217842D02*
X1392321Y226529D01*
G01X1389353Y217776D02*
X1391242Y226994D01*
G01X1350075Y238350D02*
Y241388D01*
G01X1351225Y238350D02*
Y241865D01*
G01X1350075Y241388D02*
X1348311Y243152D01*
G01X1351225Y241865D02*
X1348788Y244302D01*
G01X1361075Y238350D02*
Y241567D01*
G01X1362225Y238350D02*
Y242044D01*
G01X1361075Y241567D02*
X1356990Y245652D01*
G01X1362225Y242044D02*
X1357467Y246802D01*
G01X1372075Y243897D02*
X1367820Y248152D01*
G01X1368297Y249302D02*
X1373225Y244374D01*
G01X1372075Y238350D02*
Y243897D01*
G01X1373225Y244374D02*
Y238350D01*
G01X1383075Y239827D02*
X1379347Y243555D01*
G01X1377473Y245429D02*
X1372250Y250652D01*
G01X1372727Y251802D02*
X1384225Y240304D01*
G01X1383075Y238350D02*
Y239827D01*
G01X1384225Y240304D02*
Y238350D01*
G01X1379847Y253152D02*
X1394011Y238988D01*
G01X1380324Y254302D02*
X1395161Y239465D01*
G01X1394011Y238988D02*
Y238350D01*
G01X1395161Y239465D02*
Y238414D01*
G01X1351225Y238350D02*
Y241865D01*
G01X1350075Y238350D02*
Y241388D01*
G01X1351225Y241865D02*
X1348788Y244302D01*
G01X1350075Y241388D02*
X1348311Y243152D01*
G01X1362225Y238350D02*
Y242044D01*
G01X1361075Y238350D02*
Y241567D01*
G01X1362225Y242044D02*
X1357467Y246802D01*
G01X1361075Y241567D02*
X1356990Y245652D01*
G01X1373225Y244374D02*
Y238350D01*
G01X1372075D02*
Y243897D01*
G01X1368297Y249302D02*
X1373225Y244374D01*
G01X1372075Y243897D02*
X1367820Y248152D01*
G01X1384225Y240304D02*
Y238350D01*
G01X1383075D02*
Y239827D01*
G01X1372727Y251802D02*
X1384225Y240304D01*
G01X1383075Y239827D02*
X1379347Y243555D01*
G01X1372727Y251802D02*
X1384225Y240304D01*
G01X1377473Y245429D02*
X1372250Y250652D01*
G01X1380324Y254302D02*
X1395161Y239465D01*
G01X1379847Y253152D02*
X1394011Y238988D01*
G01X1395161Y239465D02*
Y238414D01*
G01X1394011Y238988D02*
Y238350D01*
G01X1344911Y265860D02*
Y266852D01*
G01X1346061Y266688D02*
Y265383D01*
G01X1344119Y265068D02*
X1344911Y265860D01*
G01X1346061Y265383D02*
X1344596Y263918D01*
G01X1354148Y263274D02*
Y264851D01*
G01X1355298Y264725D02*
Y262797D01*
G01X1353298Y262424D02*
X1354148Y263274D01*
G01X1355298Y262797D02*
X1353775Y261274D01*
G01X1363977Y258774D02*
X1365100Y259897D01*
G01X1363500Y259924D02*
X1363950Y260374D01*
G01X1365100Y259897D02*
Y264313D01*
G01X1363950Y260374D02*
Y264378D01*
G01X1378561Y264561D02*
Y258342D01*
G01X1379711Y264280D02*
Y257865D01*
G01X1378561Y258342D02*
X1377643Y257424D01*
G01X1379711Y257865D02*
X1378120Y256274D01*
G01X1377643Y257424D02*
X1376243D01*
G01X1373543D02*
X1372143D01*
G01X1369443D02*
X1368043D01*
G01X1346061Y265383D02*
X1344596Y263918D01*
G01X1344119Y265068D02*
X1344911Y265860D01*
G01X1346061Y266688D02*
Y265383D01*
G01X1344911Y265860D02*
Y266852D01*
G01X1355298Y262797D02*
X1353775Y261274D01*
G01X1353298Y262424D02*
X1354148Y263274D01*
G01X1355298Y264725D02*
Y262797D01*
G01X1354148Y263274D02*
Y264851D01*
G01X1363500Y259924D02*
X1363950Y260374D01*
G01X1363977Y258774D02*
X1365100Y259897D01*
G01X1363950Y260374D02*
Y264378D01*
G01X1365100Y259897D02*
Y264313D01*
G01X1379711Y264280D02*
Y257865D01*
G01X1378561Y264561D02*
Y258342D01*
G01X1379711Y257865D02*
X1378120Y256274D01*
G01X1378561Y258342D02*
X1377643Y257424D01*
G01D02*
X1376243D01*
G01X1373543D02*
X1372143D01*
G01X1369443D02*
X1368043D01*
G01X1343940Y222903D02*
X1368357Y218142D01*
G01X1344402Y223985D02*
X1369048Y219179D01*
G01X1344402Y223985D02*
X1369048Y219179D01*
G01X1343940Y222903D02*
X1368357Y218142D01*
G01X1400955Y239255D02*
X1404922Y233099D01*
G01X1405960Y233613D02*
X1401806Y240058D01*
G01X1394039Y244303D02*
X1400955Y239255D01*
G01X1401806Y240058D02*
X1394989Y245035D01*
G01X1385010Y267402D02*
X1394039Y244303D01*
G01X1394989Y245035D02*
X1386061Y267875D01*
G01X1383236Y270872D02*
X1385010Y267402D01*
G01X1386061Y267875D02*
X1384052Y271805D01*
G01X1377167Y273013D02*
X1383236Y270872D01*
G01X1384052Y271805D02*
X1377700Y274045D01*
G01X1361209Y284280D02*
X1377167Y273013D01*
G01X1377700Y274045D02*
X1362231Y284967D01*
G01X1377700Y274045D02*
X1362231Y284967D01*
G01X1361209Y284280D02*
X1377167Y273013D01*
G01X1384052Y271805D02*
X1377700Y274045D01*
G01X1377167Y273013D02*
X1383236Y270872D01*
G01X1386061Y267875D02*
X1384052Y271805D01*
G01X1383236Y270872D02*
X1385010Y267402D01*
G01X1394989Y245035D02*
X1386061Y267875D01*
G01X1385010Y267402D02*
X1394039Y244303D01*
G01X1401806Y240058D02*
X1394989Y245035D01*
G01X1394039Y244303D02*
X1400955Y239255D01*
G01X1405960Y233613D02*
X1401806Y240058D01*
G01X1400955Y239255D02*
X1404922Y233099D01*
G01X1350075Y231668D02*
Y230593D01*
G01X1351225Y231668D02*
Y230850D01*
G01X1350075Y230593D02*
X1350863Y228911D01*
G01X1351225Y230850D02*
X1351770Y229689D01*
G01X1350863Y228911D02*
X1359841Y222926D01*
G01X1351770Y229689D02*
X1360291Y224009D01*
G01X1359841Y222926D02*
X1370832Y220708D01*
G01X1360291Y224009D02*
X1371526Y221742D01*
G01X1351225Y231668D02*
Y230850D01*
G01X1350075Y231668D02*
Y230593D01*
G01X1351225Y230850D02*
X1351770Y229689D01*
G01X1350075Y230593D02*
X1350863Y228911D01*
G01X1351770Y229689D02*
X1360291Y224009D01*
G01X1350863Y228911D02*
X1359841Y222926D01*
G01X1360291Y224009D02*
X1371526Y221742D01*
G01X1359841Y222926D02*
X1370832Y220708D01*
G01X1403011Y241233D02*
X1406844Y235158D01*
G01X1396134Y246252D02*
X1403011Y241233D01*
G01X1403867Y242033D02*
X1397084Y246984D01*
G01X1387832Y267484D02*
X1396134Y246252D01*
G01X1397084Y246984D02*
X1388883Y267957D01*
G01X1384554Y273898D02*
X1387832Y267484D01*
G01X1388883Y267957D02*
X1385406Y274760D01*
G01X1374760Y278765D02*
X1384554Y273898D01*
G01X1385406Y274760D02*
X1375587Y279639D01*
G01X1371078Y285246D02*
X1374760Y278765D01*
G01X1375587Y279639D02*
X1371913Y286107D01*
G01X1375587Y279639D02*
X1371913Y286107D01*
G01X1371078Y285246D02*
X1374760Y278765D01*
G01X1385406Y274760D02*
X1375587Y279639D01*
G01X1374760Y278765D02*
X1384554Y273898D01*
G01X1388883Y267957D02*
X1385406Y274760D01*
G01X1384554Y273898D02*
X1387832Y267484D01*
G01X1397084Y246984D02*
X1388883Y267957D01*
G01X1387832Y267484D02*
X1396134Y246252D01*
G01X1403867Y242033D02*
X1397084Y246984D01*
G01X1396134Y246252D02*
X1403011Y241233D01*
G01D02*
X1406844Y235158D01*
G01X1360951Y231668D02*
Y230715D01*
G01X1362101Y231757D02*
Y231075D01*
G01X1360951Y230715D02*
X1361541Y229862D01*
G01X1362101Y231075D02*
X1362428Y230602D01*
G01X1361541Y229862D02*
X1366997Y224406D01*
G01X1362428Y230602D02*
X1367564Y225466D01*
G01X1366997Y224406D02*
X1372286Y223349D01*
G01X1367564Y225466D02*
X1372979Y224384D01*
G01X1372075Y231668D02*
Y229254D01*
G01X1373225Y231668D02*
Y229617D01*
G01D02*
X1381157Y218280D01*
G01X1383075Y231668D02*
Y230667D01*
G01X1384225Y231668D02*
Y231031D01*
G01X1383075Y230667D02*
X1384343Y228860D01*
G01X1384225Y231031D02*
X1385424Y229323D01*
G01X1391242Y226994D02*
X1394075Y231031D01*
G01X1392321Y226529D02*
X1395225Y230667D01*
G01X1394075Y231031D02*
Y231668D01*
G01X1395225Y230667D02*
Y231668D01*
G01X1362101Y231757D02*
Y231075D01*
G01X1360951Y231668D02*
Y230715D01*
G01X1362101Y231075D02*
X1362428Y230602D01*
G01X1360951Y230715D02*
X1361541Y229862D01*
G01X1362428Y230602D02*
X1367564Y225466D01*
G01X1361541Y229862D02*
X1366997Y224406D01*
G01X1367564Y225466D02*
X1372979Y224384D01*
G01X1366997Y224406D02*
X1372286Y223349D01*
G01X1373225Y231668D02*
Y229617D01*
G01X1372075Y231668D02*
Y229254D01*
G01X1373225Y229617D02*
X1381157Y218280D01*
G01X1384225Y231668D02*
Y231031D01*
G01X1383075Y231668D02*
Y230667D01*
G01X1384225Y231031D02*
X1385424Y229323D01*
G01X1383075Y230667D02*
X1384343Y228860D01*
G01X1392321Y226529D02*
X1395225Y230667D01*
G01X1391242Y226994D02*
X1394075Y231031D01*
G01X1395225Y230667D02*
Y231668D01*
G01X1394075Y231031D02*
Y231668D01*
G01X1398280Y248192D02*
X1405276Y243095D01*
G01X1406121Y243903D02*
X1399229Y248924D01*
G01X1390882Y267118D02*
X1398280Y248192D01*
G01X1399229Y248924D02*
X1391933Y267591D01*
G01X1385945Y276778D02*
X1390882Y267118D01*
G01X1391933Y267591D02*
X1386819Y277598D01*
G01X1378714Y281075D02*
X1385945Y276778D01*
G01X1386819Y277598D02*
X1379301Y282064D01*
G01X1403306Y251679D02*
X1410414Y246500D01*
G01X1398514Y265091D02*
X1403306Y251679D01*
G01X1404270Y252400D02*
X1399556Y265595D01*
G01X1388154Y281561D02*
X1398514Y265091D01*
G01X1399555Y265597D02*
X1389160Y282123D01*
G01X1390977Y281863D02*
X1400778Y266341D01*
G01X1391950Y282478D02*
X1401819Y266848D01*
G01X1400778Y266341D02*
X1405443Y253277D01*
G01X1401819Y266848D02*
X1406407Y253998D01*
G01X1403084Y267466D02*
X1407579Y254875D01*
G01X1393124Y283242D02*
X1403084Y267466D01*
G01X1404125Y267973D02*
X1394335Y283479D01*
G01X1386819Y277598D02*
X1379301Y282064D01*
G01X1386819Y277598D02*
X1379301Y282064D01*
G01X1378714Y281075D02*
X1385945Y276778D01*
G01X1391933Y267591D02*
X1386819Y277598D01*
G01X1385945Y276778D02*
X1390882Y267118D01*
G01X1399229Y248924D02*
X1391933Y267591D01*
G01X1390882Y267118D02*
X1398280Y248192D01*
G01X1406121Y243903D02*
X1399229Y248924D01*
G01X1398280Y248192D02*
X1405276Y243095D01*
G01X1399555Y265597D02*
X1389160Y282123D01*
G01X1388154Y281561D02*
X1398514Y265091D01*
G01X1404270Y252400D02*
X1399556Y265595D01*
G01X1398514Y265091D02*
X1403306Y251679D01*
G01D02*
X1410414Y246500D01*
G01X1391950Y282478D02*
X1401819Y266848D01*
G01X1390977Y281863D02*
X1400778Y266341D01*
G01X1401819Y266848D02*
X1406407Y253998D01*
G01X1400778Y266341D02*
X1405443Y253277D01*
G01X1404125Y267973D02*
X1394335Y283479D01*
G01X1393124Y283242D02*
X1403084Y267466D01*
G01D02*
X1407579Y254875D01*
G01X1351378Y330164D02*
X1361961Y327049D01*
G01X1351316Y331382D02*
X1361970Y328246D01*
G01X1361961Y327049D02*
X1365643Y328075D01*
G01X1361970Y328246D02*
X1365618Y329262D01*
G01X1365643Y328075D02*
X1368529Y327401D01*
G01X1365618Y329262D02*
X1368457Y328599D01*
G01X1368529Y327401D02*
X1371300Y328410D01*
G01X1368457Y328599D02*
X1371206Y329600D01*
G01X1371300Y328410D02*
X1379281Y326859D01*
G01X1371206Y329600D02*
X1379281Y328031D01*
G01Y326859D02*
X1381419Y327274D01*
G01X1379281Y328031D02*
X1381419Y328446D01*
G01Y327274D02*
X1384390Y326696D01*
G01X1386991Y326190D02*
X1388316Y325932D01*
G01X1390918Y325427D02*
X1393441Y324936D01*
G01X1381419Y328446D02*
X1393441Y326108D01*
G01Y324936D02*
X1402542Y326705D01*
G01X1393441Y326108D02*
X1401854Y327744D01*
G01X1402542Y326705D02*
X1406163Y332077D01*
G01X1401854Y327744D02*
X1405078Y332526D01*
G01X1343664Y331127D02*
X1344967Y331480D01*
G01X1347525Y332173D02*
X1351216Y333173D01*
G01X1353774Y333866D02*
X1355077Y334219D01*
G01X1357635Y334912D02*
X1358938Y335265D01*
G01D02*
X1362562Y334132D01*
G01X1358958Y336464D02*
X1362546Y335342D01*
G01X1362562Y334132D02*
X1366357Y335427D01*
G01X1362546Y335342D02*
X1366311Y336627D01*
G01X1366357Y335427D02*
X1369680Y334573D01*
G01X1366311Y336627D02*
X1369525Y335801D01*
G01X1369680Y334573D02*
X1372975Y336382D01*
G01X1369525Y335801D02*
X1372553Y337463D01*
G01X1372975Y336382D02*
X1375706Y337057D01*
G01X1372553Y337463D02*
X1375674Y338235D01*
G01X1375706Y337057D02*
X1377981Y336615D01*
G01X1375674Y338235D02*
X1378430Y337700D01*
G01X1377981Y336615D02*
X1382559Y333527D01*
G01X1378430Y337700D02*
X1383008Y334612D01*
G01X1382559Y333527D02*
X1385457Y332964D01*
G01X1383008Y334612D02*
X1385457Y334136D01*
G01Y332964D02*
X1388565Y333568D01*
G01X1385457Y334136D02*
X1388565Y334740D01*
G01Y333568D02*
X1399334Y331474D01*
G01X1388565Y334740D02*
X1399334Y332646D01*
G01X1388565Y333568D02*
X1399334Y331474D01*
G01D02*
X1400812Y331761D01*
G01D02*
X1402460Y332871D01*
G01X1399334Y332646D02*
X1400363Y332846D01*
G01X1400812Y331761D02*
X1402460Y332871D01*
G01X1400363Y332846D02*
X1401631Y333700D01*
G01X1402460Y332871D02*
X1403207Y333980D01*
G01X1401631Y333700D02*
X1402122Y334429D01*
G01X1403207Y333980D02*
X1403537Y335679D01*
G01X1402122Y334429D02*
X1402365Y335680D01*
G01X1403537Y335679D02*
X1403133Y337759D01*
G01X1402365Y335680D02*
X1401961Y337759D01*
G01X1403133D02*
X1406532Y355249D01*
G01X1401961Y337759D02*
X1405447Y355695D01*
G01X1343980Y340409D02*
X1348966Y341523D01*
G01X1355944Y341421D02*
X1360770Y340510D01*
G01D02*
X1364794Y341322D01*
G01D02*
X1369846Y340227D01*
G01D02*
X1372623Y341342D01*
G01D02*
X1379020Y340059D01*
G01X1372513Y342538D02*
X1379472Y341142D01*
G01X1379020Y340059D02*
X1383565Y336993D01*
G01X1379472Y341142D02*
X1384015Y338078D01*
G01X1383565Y336993D02*
X1385755Y336567D01*
G01X1384015Y338078D02*
X1385755Y337739D01*
G01Y336567D02*
X1388307Y337063D01*
G01X1385755Y337739D02*
X1388307Y338235D01*
G01Y337063D02*
X1394894Y335783D01*
G01X1388307Y338235D02*
X1394894Y336955D01*
G01Y335783D02*
X1398096Y336406D01*
G01X1394894Y336955D02*
X1397646Y337491D01*
G01X1398096Y336406D02*
X1399925Y337640D01*
G01X1397646Y337491D02*
X1399096Y338469D01*
G01X1399925Y337640D02*
X1400441Y338405D01*
G01X1399096Y338469D02*
X1399356Y338854D01*
G01X1400441Y338405D02*
X1403929Y356350D01*
G01X1399356Y338854D02*
X1402844Y356799D01*
G01X1351316Y331382D02*
X1361970Y328246D01*
G01X1351378Y330164D02*
X1361961Y327049D01*
G01X1361970Y328246D02*
X1365618Y329262D01*
G01X1361961Y327049D02*
X1365643Y328075D01*
G01X1365618Y329262D02*
X1368457Y328599D01*
G01X1365643Y328075D02*
X1368529Y327401D01*
G01X1368457Y328599D02*
X1371206Y329600D01*
G01X1368529Y327401D02*
X1371300Y328410D01*
G01X1371206Y329600D02*
X1379281Y328031D01*
G01X1371300Y328410D02*
X1379281Y326859D01*
G01Y328031D02*
X1381419Y328446D01*
G01X1379281Y326859D02*
X1381419Y327274D01*
G01Y328446D02*
X1393441Y326108D01*
G01X1381419Y327274D02*
X1384390Y326696D01*
G01X1381419Y328446D02*
X1393441Y326108D01*
G01X1386991Y326190D02*
X1388316Y325932D01*
G01X1381419Y328446D02*
X1393441Y326108D01*
G01X1390918Y325427D02*
X1393441Y324936D01*
G01Y326108D02*
X1401854Y327744D01*
G01X1393441Y324936D02*
X1402542Y326705D01*
G01X1401854Y327744D02*
X1405078Y332526D01*
G01X1402542Y326705D02*
X1406163Y332077D01*
G01X1343664Y331127D02*
X1344967Y331480D01*
G01X1347525Y332173D02*
X1351216Y333173D01*
G01X1353774Y333866D02*
X1355077Y334219D01*
G01X1357635Y334912D02*
X1358938Y335265D01*
G01X1358958Y336464D02*
X1362546Y335342D01*
G01X1358938Y335265D02*
X1362562Y334132D01*
G01X1362546Y335342D02*
X1366311Y336627D01*
G01X1362562Y334132D02*
X1366357Y335427D01*
G01X1366311Y336627D02*
X1369525Y335801D01*
G01X1366357Y335427D02*
X1369680Y334573D01*
G01X1369525Y335801D02*
X1372553Y337463D01*
G01X1369680Y334573D02*
X1372975Y336382D01*
G01X1372553Y337463D02*
X1375674Y338235D01*
G01X1372975Y336382D02*
X1375706Y337057D01*
G01X1375674Y338235D02*
X1378430Y337700D01*
G01X1375706Y337057D02*
X1377981Y336615D01*
G01X1378430Y337700D02*
X1383008Y334612D01*
G01X1377981Y336615D02*
X1382559Y333527D01*
G01X1383008Y334612D02*
X1385457Y334136D01*
G01X1382559Y333527D02*
X1385457Y332964D01*
G01Y334136D02*
X1388565Y334740D01*
G01X1385457Y332964D02*
X1388565Y333568D01*
G01Y334740D02*
X1399334Y332646D01*
G01D02*
X1400363Y332846D01*
G01X1388565Y333568D02*
X1399334Y331474D01*
G01Y332646D02*
X1400363Y332846D01*
G01X1399334Y331474D02*
X1400812Y331761D01*
G01X1399334Y332646D02*
X1400363Y332846D01*
G01D02*
X1401631Y333700D01*
G01X1400812Y331761D02*
X1402460Y332871D01*
G01X1401631Y333700D02*
X1402122Y334429D01*
G01X1402460Y332871D02*
X1403207Y333980D01*
G01X1402122Y334429D02*
X1402365Y335680D01*
G01X1403207Y333980D02*
X1403537Y335679D01*
G01X1402365Y335680D02*
X1401961Y337759D01*
G01X1403537Y335679D02*
X1403133Y337759D01*
G01X1401961D02*
X1405447Y355695D01*
G01X1403133Y337759D02*
X1406532Y355249D01*
G01X1343980Y340409D02*
X1348966Y341523D01*
G01X1355944Y341421D02*
X1360770Y340510D01*
G01D02*
X1364794Y341322D01*
G01D02*
X1369846Y340227D01*
G01D02*
X1372623Y341342D01*
G01X1372513Y342538D02*
X1379472Y341142D01*
G01X1372623Y341342D02*
X1379020Y340059D01*
G01X1379472Y341142D02*
X1384015Y338078D01*
G01X1379020Y340059D02*
X1383565Y336993D01*
G01X1384015Y338078D02*
X1385755Y337739D01*
G01X1383565Y336993D02*
X1385755Y336567D01*
G01Y337739D02*
X1388307Y338235D01*
G01X1385755Y336567D02*
X1388307Y337063D01*
G01Y338235D02*
X1394894Y336955D01*
G01X1388307Y337063D02*
X1394894Y335783D01*
G01Y336955D02*
X1397646Y337491D01*
G01X1394894Y335783D02*
X1398096Y336406D01*
G01X1397646Y337491D02*
X1399096Y338469D01*
G01X1398096Y336406D02*
X1399925Y337640D01*
G01X1399096Y338469D02*
X1399356Y338854D01*
G01X1399925Y337640D02*
X1400441Y338405D01*
G01X1399356Y338854D02*
X1402844Y356799D01*
G01X1400441Y338405D02*
X1403929Y356350D01*
G01X1351634Y328671D02*
X1361951Y325634D01*
G01X1351696Y327453D02*
X1361942Y324437D01*
G01X1361951Y325634D02*
X1365673Y326671D01*
G01X1361942Y324437D02*
X1365698Y325484D01*
G01X1365673Y326671D02*
X1368614Y325985D01*
G01X1365698Y325484D02*
X1368686Y324787D01*
G01X1368614Y325985D02*
X1368655Y326000D01*
G01D02*
X1370894Y326815D01*
G01X1368686Y324787D02*
X1370963Y325616D01*
G01X1370894Y326815D02*
X1372535Y326425D01*
G01X1370963Y325616D02*
X1372065Y325354D01*
G01X1372535Y326425D02*
X1376953Y323445D01*
G01X1372065Y325354D02*
X1376504Y322360D01*
G01X1376953Y323445D02*
X1380683Y322722D01*
G01D02*
X1380996D01*
G01X1376504Y322360D02*
X1380572Y321572D01*
G01X1380683Y322722D02*
X1380996D01*
G01X1380572Y321572D02*
X1381107D01*
G01X1380683Y322722D02*
X1380996D01*
G01D02*
X1387303Y323949D01*
G01X1381107Y321572D02*
X1387303Y322777D01*
G01Y323949D02*
X1391751Y323084D01*
G01X1387303Y322777D02*
X1391751Y321912D01*
G01Y323084D02*
X1409127Y326462D01*
G01X1391751Y321912D02*
X1409576Y325377D01*
G01X1351696Y327453D02*
X1361942Y324437D01*
G01X1351634Y328671D02*
X1361951Y325634D01*
G01X1361942Y324437D02*
X1365698Y325484D01*
G01X1361951Y325634D02*
X1365673Y326671D01*
G01X1365698Y325484D02*
X1368686Y324787D01*
G01X1365673Y326671D02*
X1368614Y325985D01*
G01X1368686Y324787D02*
X1370963Y325616D01*
G01X1368614Y325985D02*
X1368655Y326000D01*
G01X1368686Y324787D02*
X1370963Y325616D01*
G01X1368655Y326000D02*
X1370894Y326815D01*
G01X1370963Y325616D02*
X1372065Y325354D01*
G01X1370894Y326815D02*
X1372535Y326425D01*
G01X1372065Y325354D02*
X1376504Y322360D01*
G01X1372535Y326425D02*
X1376953Y323445D01*
G01X1376504Y322360D02*
X1380572Y321572D01*
G01X1376953Y323445D02*
X1380683Y322722D01*
G01X1376504Y322360D02*
X1380572Y321572D01*
G01D02*
X1381107D01*
G01D02*
X1387303Y322777D01*
G01X1380683Y322722D02*
X1380996D01*
G01X1381107Y321572D02*
X1387303Y322777D01*
G01X1380996Y322722D02*
X1387303Y323949D01*
G01Y322777D02*
X1391751Y321912D01*
G01X1387303Y323949D02*
X1391751Y323084D01*
G01Y321912D02*
X1409576Y325377D01*
G01X1391751Y323084D02*
X1409127Y326462D01*
G01X1360582Y286980D02*
X1361209Y284280D01*
G01X1362231Y284967D02*
X1361569Y287816D01*
G01X1362231Y284967D02*
X1361569Y287816D01*
G01X1360582Y286980D02*
X1361209Y284280D01*
G01X1352542Y295027D02*
X1352856Y294861D01*
G01D02*
X1371078Y285246D01*
G01X1371913Y286107D02*
X1353266Y295946D01*
G01X1350377Y297489D02*
X1352542Y295027D01*
G01X1353266Y295946D02*
X1351527Y297923D01*
G01X1350377Y298690D02*
Y297489D01*
G01X1351527Y297923D02*
Y298690D01*
G01Y297923D02*
Y298690D01*
G01X1350377D02*
Y297489D01*
G01X1353266Y295946D02*
X1351527Y297923D01*
G01X1350377Y297489D02*
X1352542Y295027D01*
G01X1371913Y286107D02*
X1353266Y295946D01*
G01X1352542Y295027D02*
X1352856Y294861D01*
G01X1371913Y286107D02*
X1353266Y295946D01*
G01X1352856Y294861D02*
X1371078Y285246D01*
G01X1378500Y281200D02*
X1378712Y281074D01*
G01X1370684Y292316D02*
X1378500Y281200D01*
G01X1379301Y282064D02*
X1371492Y293168D01*
G01X1360719Y298534D02*
X1370685Y292316D01*
G01D02*
X1370684D01*
G01X1371492Y293168D02*
X1365325Y297017D01*
G01X1360719Y298534D02*
X1370685Y292316D01*
G01X1363076Y298420D02*
X1361869Y299173D01*
G01X1360719Y299900D02*
Y298534D01*
G01X1361869Y299173D02*
Y299900D01*
G01X1383167Y291711D02*
X1388154Y281561D01*
G01X1389160Y282122D02*
X1384052Y292520D01*
G01X1371515Y298821D02*
X1383167Y291712D01*
G01X1384052Y292520D02*
X1372665Y299467D01*
G01X1371515Y300769D02*
Y298821D01*
G01X1372665Y299467D02*
Y300769D01*
G01X1382713Y301015D02*
Y298647D01*
G01X1383863Y301046D02*
Y298915D01*
G01X1382713Y298647D02*
X1384092Y295840D01*
G01X1383863Y298915D02*
X1384914Y296775D01*
G01X1384092Y295840D02*
X1385594Y295328D01*
G01X1384914Y296775D02*
X1385514Y296571D01*
G01X1385594Y295328D02*
X1387019Y296028D01*
G01X1385514Y296571D02*
X1386939Y297271D01*
G01X1387019Y296028D02*
X1387620Y295823D01*
G01X1386939Y297271D02*
X1388442Y296758D01*
G01X1387620Y295823D02*
X1388018Y295013D01*
G01X1388442Y296758D02*
X1389261Y295093D01*
G01X1388018Y295013D02*
X1387813Y294412D01*
G01X1389261Y295093D02*
X1388748Y293590D01*
G01X1387813Y294412D02*
X1386388Y293712D01*
G01X1388748Y293590D02*
X1387323Y292890D01*
G01X1386388Y293712D02*
X1385876Y292210D01*
G01X1387323Y292890D02*
X1387119Y292290D01*
G01X1385876Y292210D02*
X1386696Y290541D01*
G01X1387119Y292290D02*
X1387518Y291476D01*
G01X1386696Y290541D02*
X1388198Y290029D01*
G01X1387518Y291476D02*
X1388118Y291272D01*
G01X1388198Y290029D02*
X1389623Y290729D01*
G01X1388118Y291272D02*
X1389543Y291972D01*
G01X1389623Y290729D02*
X1390224Y290524D01*
G01X1389543Y291972D02*
X1391046Y291459D01*
G01X1390224Y290524D02*
X1390622Y289714D01*
G01X1391046Y291459D02*
X1391865Y289794D01*
G01X1390622Y289714D02*
X1390417Y289113D01*
G01X1391865Y289794D02*
X1391352Y288291D01*
G01X1390417Y289113D02*
X1388993Y288413D01*
G01X1391352Y288291D02*
X1389928Y287591D01*
G01X1388993Y288413D02*
X1388480Y286910D01*
G01X1389928Y287591D02*
X1389723Y286991D01*
G01X1388480Y286910D02*
X1390976Y281864D01*
G01X1389723Y286991D02*
X1391954Y282482D01*
G01X1394310Y289862D02*
X1393124Y283242D01*
G01X1394335Y283479D02*
X1395460Y289759D01*
G01X1394310Y301601D02*
Y289862D01*
G01X1395460Y289759D02*
Y301601D01*
G01X1361869Y299173D02*
Y299900D01*
G01X1360719D02*
Y298534D01*
G01X1371492Y293168D02*
X1365325Y297017D01*
G01X1363076Y298420D02*
X1361869Y299173D01*
G01X1360719Y298534D02*
X1370685Y292316D01*
G01X1371492Y293168D02*
X1365325Y297017D01*
G01X1370685Y292316D02*
X1370684D01*
G01X1379301Y282064D02*
X1371492Y293168D01*
G01X1370684Y292316D02*
X1378500Y281200D01*
G01D02*
X1378712Y281074D01*
G01X1372665Y299467D02*
Y300769D01*
G01X1371515D02*
Y298821D01*
G01X1384052Y292520D02*
X1372665Y299467D01*
G01X1371515Y298821D02*
X1383167Y291712D01*
G01X1389160Y282122D02*
X1384052Y292520D01*
G01X1383167Y291711D02*
X1388154Y281561D01*
G01X1383863Y301046D02*
Y298915D01*
G01X1382713Y301015D02*
Y298647D01*
G01X1383863Y298915D02*
X1384914Y296775D01*
G01X1382713Y298647D02*
X1384092Y295840D01*
G01X1384914Y296775D02*
X1385514Y296571D01*
G01X1384092Y295840D02*
X1385594Y295328D01*
G01X1385514Y296571D02*
X1386939Y297271D01*
G01X1385594Y295328D02*
X1387019Y296028D01*
G01X1386939Y297271D02*
X1388442Y296758D01*
G01X1387019Y296028D02*
X1387620Y295823D01*
G01X1388442Y296758D02*
X1389261Y295093D01*
G01X1387620Y295823D02*
X1388018Y295013D01*
G01X1389261Y295093D02*
X1388748Y293590D01*
G01X1388018Y295013D02*
X1387813Y294412D01*
G01X1388748Y293590D02*
X1387323Y292890D01*
G01X1387813Y294412D02*
X1386388Y293712D01*
G01X1387323Y292890D02*
X1387119Y292290D01*
G01X1386388Y293712D02*
X1385876Y292210D01*
G01X1387119Y292290D02*
X1387518Y291476D01*
G01X1385876Y292210D02*
X1386696Y290541D01*
G01X1387518Y291476D02*
X1388118Y291272D01*
G01X1386696Y290541D02*
X1388198Y290029D01*
G01X1388118Y291272D02*
X1389543Y291972D01*
G01X1388198Y290029D02*
X1389623Y290729D01*
G01X1389543Y291972D02*
X1391046Y291459D01*
G01X1389623Y290729D02*
X1390224Y290524D01*
G01X1391046Y291459D02*
X1391865Y289794D01*
G01X1390224Y290524D02*
X1390622Y289714D01*
G01X1391865Y289794D02*
X1391352Y288291D01*
G01X1390622Y289714D02*
X1390417Y289113D01*
G01X1391352Y288291D02*
X1389928Y287591D01*
G01X1390417Y289113D02*
X1388993Y288413D01*
G01X1389928Y287591D02*
X1389723Y286991D01*
G01X1388993Y288413D02*
X1388480Y286910D01*
G01X1389723Y286991D02*
X1391954Y282482D01*
G01X1388480Y286910D02*
X1390976Y281864D01*
G01X1395460Y289759D02*
Y301601D01*
G01X1394310D02*
Y289862D01*
G01X1394335Y283479D02*
X1395460Y289759D01*
G01X1394310Y289862D02*
X1393124Y283242D01*
G01X1348966Y341523D02*
X1348967D01*
G01D02*
X1351915Y342182D01*
G01D02*
X1353291Y341922D01*
G01X1351895Y343357D02*
X1360763Y341682D01*
G01D02*
X1364802Y342497D01*
G01D02*
X1369745Y341426D01*
G01D02*
X1372513Y342538D01*
G01X1402844Y356799D02*
X1408886Y365858D01*
G01X1371542Y355486D02*
X1349571Y351093D01*
G01X1349599Y352272D02*
X1371542Y356661D01*
G01X1386323Y352532D02*
X1371542Y355488D01*
G01Y356661D02*
X1386326Y353705D01*
G01X1400158Y355235D02*
X1386323Y352532D01*
G01X1386326Y353705D02*
X1399467Y356272D01*
G01X1407918Y366871D02*
X1400158Y355235D01*
G01X1399467Y356272D02*
X1407065Y367666D01*
G01X1371465Y358407D02*
X1349701Y354053D01*
G01X1349729Y355232D02*
X1371467Y359581D01*
G01X1386574Y355333D02*
X1371465Y358407D01*
G01X1371467Y359581D02*
X1386574Y356507D01*
G01X1398868Y357835D02*
X1386574Y355333D01*
G01Y356507D02*
X1398174Y358868D01*
G01X1406143Y368746D02*
X1398868Y357835D01*
G01X1398174Y358868D02*
X1405290Y369541D01*
G01X1348966Y341523D02*
X1348967D01*
G01D02*
X1351915Y342182D01*
G01X1351895Y343357D02*
X1360763Y341682D01*
G01X1351915Y342182D02*
X1353291Y341922D01*
G01X1351895Y343357D02*
X1360763Y341682D01*
G01D02*
X1364802Y342497D01*
G01D02*
X1369745Y341426D01*
G01D02*
X1372513Y342538D01*
G01X1402844Y356799D02*
X1408886Y365858D01*
G01X1399467Y356272D02*
X1407065Y367666D01*
G01X1407918Y366871D02*
X1400158Y355235D01*
G01X1386326Y353705D02*
X1399467Y356272D01*
G01X1400158Y355235D02*
X1386323Y352532D01*
G01X1371542Y356661D02*
X1386326Y353705D01*
G01X1386323Y352532D02*
X1371542Y355488D01*
G01X1349599Y352272D02*
X1371542Y356661D01*
G01Y355486D02*
X1349571Y351093D01*
G01X1398174Y358868D02*
X1405290Y369541D01*
G01X1406143Y368746D02*
X1398868Y357835D01*
G01X1386574Y356507D02*
X1398174Y358868D01*
G01X1398868Y357835D02*
X1386574Y355333D01*
G01X1371467Y359581D02*
X1386574Y356507D01*
G01Y355333D02*
X1371465Y358407D01*
G01X1349729Y355232D02*
X1371467Y359581D01*
G01X1371465Y358407D02*
X1349701Y354053D01*
G01X1393637Y471783D02*
X1354883Y463796D01*
G01D02*
X1347178Y458664D01*
G01X1354431Y464878D02*
X1346349Y459494D01*
G01X1347178Y458664D02*
X1345432Y456044D01*
G01X1346349Y459494D02*
X1344407Y456582D01*
G01X1345432Y456044D02*
X1344479Y453645D01*
G01X1344407Y456582D02*
X1343410Y454069D01*
G01X1344478Y453642D02*
X1343336Y450767D01*
G01X1343409Y454068D02*
X1342410Y451553D01*
G01X1393637Y471783D02*
X1354883Y463796D01*
G01X1354431Y464878D02*
X1346349Y459494D01*
G01X1354883Y463796D02*
X1347178Y458664D01*
G01X1346349Y459494D02*
X1344407Y456582D01*
G01X1347178Y458664D02*
X1345432Y456044D01*
G01X1344407Y456582D02*
X1343410Y454069D01*
G01X1345432Y456044D02*
X1344479Y453645D01*
G01X1343409Y454068D02*
X1342410Y451553D01*
G01X1344478Y453642D02*
X1343336Y450767D01*
G01X1411000Y461472D02*
X1396155Y464358D01*
G01X1411000Y461472D02*
X1396155Y464358D01*
G01X1401406Y462165D02*
X1400080Y462423D01*
G01X1411000Y461472D02*
X1396155Y464358D01*
G01X1397479Y462928D02*
X1396154Y463186D01*
G01X1396155Y464358D02*
X1391383Y463430D01*
G01X1396154Y463186D02*
X1391832Y462345D01*
G01X1391383Y463430D02*
X1380918Y456373D01*
G01X1391832Y462345D02*
X1388000Y459761D01*
G01X1391383Y463430D02*
X1380918Y456373D01*
G01X1386705Y458104D02*
X1385803Y458279D01*
G01X1391383Y463430D02*
X1380918Y456373D01*
G01X1385803Y458279D02*
X1384683Y457524D01*
G01X1391383Y463430D02*
X1380918Y456373D01*
G01X1383389Y455867D02*
X1382486Y456043D01*
G01X1391383Y463430D02*
X1380918Y456373D01*
G01X1382486Y456043D02*
X1381367Y455288D01*
G01X1380918Y456373D02*
X1376834Y455579D01*
G01X1381367Y455288D02*
X1376834Y454407D01*
G01Y455579D02*
X1373257Y456274D01*
G01X1376834Y454407D02*
X1373257Y455102D01*
G01Y456274D02*
X1368889Y455425D01*
G01X1373257Y455102D02*
X1369338Y454340D01*
G01X1368889Y455425D02*
X1367944Y454789D01*
G01X1369338Y454340D02*
X1368773Y453960D01*
G01X1367944Y454789D02*
X1367197Y453679D01*
G01X1368773Y453960D02*
X1368282Y453230D01*
G01X1367197Y453679D02*
X1366774Y451510D01*
G01X1368282Y453230D02*
X1367860Y451064D01*
G01X1366774Y451510D02*
X1366584Y451224D01*
G01X1367860Y451064D02*
X1367417Y450397D01*
G01X1366584Y451224D02*
X1365867Y450741D01*
G01X1367417Y450397D02*
X1366316Y449656D01*
G01X1365867Y450741D02*
X1363133Y450209D01*
G01X1366316Y449656D02*
X1363133Y449037D01*
G01Y450209D02*
X1360592Y450703D01*
G01X1363133Y449037D02*
X1360592Y449531D01*
G01Y450703D02*
X1357434Y450090D01*
G01X1360592Y449531D02*
X1357883Y449005D01*
G01X1357434Y450090D02*
X1350852Y445650D01*
G01X1357883Y449005D02*
X1351204Y444500D01*
G01X1350852Y445650D02*
X1349023D01*
G01X1351204Y444500D02*
X1349500D01*
G01X1349023Y445650D02*
X1347000Y443627D01*
G01X1349500Y444500D02*
X1348150Y443150D01*
G01X1347000Y443627D02*
Y441627D01*
G01X1348150Y443150D02*
Y441150D01*
G01X1347000Y441627D02*
X1346028Y440655D01*
G01X1348150Y441150D02*
X1346505Y439505D01*
G01X1346028Y440655D02*
X1343226D01*
G01X1346505Y439505D02*
X1343337D01*
G01X1343347Y444716D02*
X1345641Y446263D01*
G01X1342897Y445801D02*
X1342899D01*
G01X1343347Y444716D02*
X1345641Y446263D01*
G01X1342899Y445801D02*
X1344812Y447092D01*
G01X1345641Y446263D02*
X1346570Y447641D01*
G01X1344812Y447092D02*
X1345741Y448471D01*
G01X1346570Y447641D02*
X1348737Y449098D01*
G01X1345741Y448471D02*
X1348288Y450183D01*
G01X1348737Y449098D02*
X1351604Y449656D01*
G01X1348288Y450183D02*
X1351154Y450741D01*
G01X1351604Y449656D02*
X1358160Y454078D01*
G01X1351154Y450741D02*
X1357710Y455163D01*
G01X1358160Y454078D02*
X1362472Y454917D01*
G01X1357710Y455163D02*
X1362022Y456002D01*
G01X1362472Y454917D02*
X1365298Y456823D01*
G01X1362022Y456002D02*
X1364469Y457652D01*
G01X1365298Y456823D02*
X1367282Y459765D01*
G01X1364469Y457652D02*
X1366453Y460594D01*
G01X1367282Y459765D02*
X1369675Y461379D01*
G01X1366453Y460594D02*
X1369225Y462464D01*
G01X1369675Y461379D02*
X1396136Y466523D01*
G01X1369225Y462464D02*
X1396136Y467695D01*
G01X1401406Y462165D02*
X1400080Y462423D01*
G01X1397479Y462928D02*
X1396154Y463186D01*
G01X1411000Y461472D02*
X1396155Y464358D01*
G01X1396154Y463186D02*
X1391832Y462345D01*
G01X1396155Y464358D02*
X1391383Y463430D01*
G01X1391832Y462345D02*
X1388000Y459761D01*
G01X1386705Y458104D02*
X1385803Y458279D01*
G01D02*
X1384683Y457524D01*
G01X1383389Y455867D02*
X1382486Y456043D01*
G01D02*
X1381367Y455288D01*
G01X1391383Y463430D02*
X1380918Y456373D01*
G01X1381367Y455288D02*
X1376834Y454407D01*
G01X1380918Y456373D02*
X1376834Y455579D01*
G01Y454407D02*
X1373257Y455102D01*
G01X1376834Y455579D02*
X1373257Y456274D01*
G01Y455102D02*
X1369338Y454340D01*
G01X1373257Y456274D02*
X1368889Y455425D01*
G01X1369338Y454340D02*
X1368773Y453960D01*
G01X1368889Y455425D02*
X1367944Y454789D01*
G01X1368773Y453960D02*
X1368282Y453230D01*
G01X1367944Y454789D02*
X1367197Y453679D01*
G01X1368282Y453230D02*
X1367860Y451064D01*
G01X1367197Y453679D02*
X1366774Y451510D01*
G01X1367860Y451064D02*
X1367417Y450397D01*
G01X1366774Y451510D02*
X1366584Y451224D01*
G01X1367417Y450397D02*
X1366316Y449656D01*
G01X1366584Y451224D02*
X1365867Y450741D01*
G01X1366316Y449656D02*
X1363133Y449037D01*
G01X1365867Y450741D02*
X1363133Y450209D01*
G01Y449037D02*
X1360592Y449531D01*
G01X1363133Y450209D02*
X1360592Y450703D01*
G01Y449531D02*
X1357883Y449005D01*
G01X1360592Y450703D02*
X1357434Y450090D01*
G01X1357883Y449005D02*
X1351204Y444500D01*
G01X1357434Y450090D02*
X1350852Y445650D01*
G01X1351204Y444500D02*
X1349500D01*
G01X1350852Y445650D02*
X1349023D01*
G01X1349500Y444500D02*
X1348150Y443150D01*
G01X1349023Y445650D02*
X1347000Y443627D01*
G01X1348150Y443150D02*
Y441150D01*
G01X1347000Y443627D02*
Y441627D01*
G01X1348150Y441150D02*
X1346505Y439505D01*
G01X1347000Y441627D02*
X1346028Y440655D01*
G01X1346505Y439505D02*
X1343337D01*
G01X1346028Y440655D02*
X1343226D01*
G01X1342897Y445801D02*
X1342899D01*
G01X1342897D02*
X1342899D01*
G01D02*
X1344812Y447092D01*
G01X1343347Y444716D02*
X1345641Y446263D01*
G01X1344812Y447092D02*
X1345741Y448471D01*
G01X1345641Y446263D02*
X1346570Y447641D01*
G01X1345741Y448471D02*
X1348288Y450183D01*
G01X1346570Y447641D02*
X1348737Y449098D01*
G01X1348288Y450183D02*
X1351154Y450741D01*
G01X1348737Y449098D02*
X1351604Y449656D01*
G01X1351154Y450741D02*
X1357710Y455163D01*
G01X1351604Y449656D02*
X1358160Y454078D01*
G01X1357710Y455163D02*
X1362022Y456002D01*
G01X1358160Y454078D02*
X1362472Y454917D01*
G01X1362022Y456002D02*
X1364469Y457652D01*
G01X1362472Y454917D02*
X1365298Y456823D01*
G01X1364469Y457652D02*
X1366453Y460594D01*
G01X1365298Y456823D02*
X1367282Y459765D01*
G01X1366453Y460594D02*
X1369225Y462464D01*
G01X1367282Y459765D02*
X1369675Y461379D01*
G01X1369225Y462464D02*
X1396136Y467695D01*
G01X1369675Y461379D02*
X1396136Y466523D01*
G01X1409745Y492400D02*
X1400287Y489219D01*
G01X1409934Y491250D02*
X1400826Y488186D01*
G01X1400287Y489219D02*
X1396306Y486273D01*
G01D02*
X1395397Y486409D01*
G01X1394176Y484697D02*
X1388385Y480413D01*
G01X1400826Y488186D02*
X1388869Y479340D01*
G01X1388385Y480414D02*
X1365346Y475522D01*
G01X1388869Y479340D02*
X1365353Y474347D01*
G01X1365346Y475522D02*
X1358718Y476848D01*
G01X1365353Y474347D02*
X1358269Y475765D01*
G01X1358718Y476848D02*
X1353076Y480609D01*
G01X1358269Y475765D02*
X1352627Y479526D01*
G01X1353076Y480609D02*
X1348067Y481612D01*
G01X1352627Y479526D02*
X1348074Y480437D01*
G01D02*
X1343903Y479550D01*
G01X1403881Y479402D02*
X1352256Y468654D01*
G01X1403762Y480552D02*
X1352251Y469828D01*
G01X1352256Y468654D02*
X1344590Y470186D01*
G01X1352251Y469828D02*
X1345040Y471269D01*
G01X1376144Y483594D02*
X1380022D01*
G01X1379714Y484744D02*
X1375802D01*
G01X1368672Y478724D02*
X1376144Y483594D01*
G01X1375802Y484744D02*
X1368140Y479751D01*
G01X1364583Y477098D02*
X1368672Y478724D01*
G01X1368140Y479751D02*
X1364475Y478293D01*
G01X1359153Y478184D02*
X1364583Y477098D01*
G01X1364475Y478293D02*
X1362038Y478781D01*
G01X1359153Y478184D02*
X1364583Y477098D01*
G01X1362038Y478780D02*
X1359602Y479267D01*
G01X1353358Y482047D02*
X1359153Y478184D01*
G01X1359602Y479267D02*
X1353807Y483130D01*
G01X1348326Y483053D02*
X1353358Y482047D01*
G01X1353807Y483130D02*
X1348319Y484228D01*
G01X1360291Y484673D02*
X1359509D01*
G01X1360291Y483523D02*
X1359249D01*
G01X1360291Y484673D02*
X1359509D01*
G01D02*
X1357700Y485533D01*
G01X1359249Y483523D02*
X1357320Y484440D01*
G01X1357700Y485533D02*
X1348138Y487732D01*
G01X1357320Y484440D02*
X1348121Y486555D01*
G01X1348464Y494236D02*
X1354599Y492952D01*
G01X1348456Y493062D02*
X1354642Y491768D01*
G01X1354599Y492952D02*
X1360015Y494497D01*
G01X1354642Y491768D02*
X1360617Y493472D01*
G01X1360015Y494497D02*
X1362880Y497362D01*
G01X1360617Y493472D02*
X1361724Y494579D01*
G01X1382794Y496704D02*
X1380548D01*
G01X1382812Y495554D02*
X1380875D01*
G01X1380548Y496704D02*
X1369351Y489796D01*
G01X1380875Y495554D02*
X1369578Y488584D01*
G01X1369351Y489796D02*
X1365444Y490516D01*
G01X1369578Y488584D02*
X1365484Y489339D01*
G01X1365444Y490516D02*
X1362806Y489845D01*
G01X1365484Y489339D02*
X1364408Y489065D01*
G01X1365444Y490516D02*
X1362806Y489845D01*
G01X1364408Y489065D02*
X1362823Y488662D01*
G01X1362806Y489845D02*
X1360300Y490404D01*
G01X1362823Y488662D02*
X1360256Y489235D01*
G01X1360300Y490404D02*
X1354877Y489615D01*
G01X1360256Y489235D02*
X1354841Y488447D01*
G01X1354877Y489615D02*
X1348920Y490861D01*
G01X1354841Y488447D02*
X1348913Y489687D01*
G01X1408776Y468567D02*
X1393637Y471783D01*
G01X1408776Y469743D02*
X1393641Y472958D01*
G01D02*
X1354431Y464878D01*
G01X1410795Y471879D02*
X1396047Y474830D01*
G01X1410788Y473054D02*
X1396047Y476003D01*
G01Y474830D02*
X1350744Y465769D01*
G01X1396047Y476003D02*
X1350744Y466942D01*
G01Y465769D02*
X1342500Y467418D01*
G01X1350744Y466942D02*
X1342950Y468501D01*
G01X1409934Y491250D02*
X1400826Y488186D01*
G01X1409745Y492400D02*
X1400287Y489219D01*
G01X1400826Y488186D02*
X1388869Y479340D01*
G01X1400287Y489219D02*
X1396306Y486273D01*
G01X1400826Y488186D02*
X1388869Y479340D01*
G01X1396306Y486273D02*
X1395397Y486409D01*
G01X1400826Y488186D02*
X1388869Y479340D01*
G01X1394176Y484697D02*
X1388385Y480413D01*
G01X1388869Y479340D02*
X1365353Y474347D01*
G01X1388385Y480414D02*
X1365346Y475522D01*
G01X1365353Y474347D02*
X1358269Y475765D01*
G01X1365346Y475522D02*
X1358718Y476848D01*
G01X1358269Y475765D02*
X1352627Y479526D01*
G01X1358718Y476848D02*
X1353076Y480609D01*
G01X1352627Y479526D02*
X1348074Y480437D01*
G01X1353076Y480609D02*
X1348067Y481612D01*
G01X1348074Y480437D02*
X1343903Y479550D01*
G01X1403762Y480552D02*
X1352251Y469828D01*
G01X1403881Y479402D02*
X1352256Y468654D01*
G01X1352251Y469828D02*
X1345040Y471269D01*
G01X1352256Y468654D02*
X1344590Y470186D01*
G01X1353807Y483130D02*
X1348319Y484228D01*
G01X1348326Y483053D02*
X1353358Y482047D01*
G01X1359602Y479267D02*
X1353807Y483130D01*
G01X1353358Y482047D02*
X1359153Y478184D01*
G01X1364475Y478293D02*
X1362038Y478781D01*
G01Y478780D02*
X1359602Y479267D01*
G01X1359153Y478184D02*
X1364583Y477098D01*
G01X1368140Y479751D02*
X1364475Y478293D01*
G01X1364583Y477098D02*
X1368672Y478724D01*
G01X1375802Y484744D02*
X1368140Y479751D01*
G01X1368672Y478724D02*
X1376144Y483594D01*
G01X1379714Y484744D02*
X1375802D01*
G01X1376144Y483594D02*
X1380022D01*
G01X1360291Y483523D02*
X1359249D01*
G01D02*
X1357320Y484440D01*
G01X1360291Y484673D02*
X1359509D01*
G01X1359249Y483523D02*
X1357320Y484440D01*
G01X1359509Y484673D02*
X1357700Y485533D01*
G01X1357320Y484440D02*
X1348121Y486555D01*
G01X1357700Y485533D02*
X1348138Y487732D01*
G01X1348456Y493062D02*
X1354642Y491768D01*
G01X1348464Y494236D02*
X1354599Y492952D01*
G01X1354642Y491768D02*
X1360617Y493472D01*
G01X1354599Y492952D02*
X1360015Y494497D01*
G01X1360617Y493472D02*
X1361724Y494579D01*
G01X1360015Y494497D02*
X1362880Y497362D01*
G01X1382812Y495554D02*
X1380875D01*
G01X1382794Y496704D02*
X1380548D01*
G01X1380875Y495554D02*
X1369578Y488584D01*
G01X1380548Y496704D02*
X1369351Y489796D01*
G01X1369578Y488584D02*
X1365484Y489339D01*
G01X1369351Y489796D02*
X1365444Y490516D01*
G01X1365484Y489339D02*
X1364408Y489065D01*
G01D02*
X1362823Y488662D01*
G01X1365444Y490516D02*
X1362806Y489845D01*
G01X1362823Y488662D02*
X1360256Y489235D01*
G01X1362806Y489845D02*
X1360300Y490404D01*
G01X1360256Y489235D02*
X1354841Y488447D01*
G01X1360300Y490404D02*
X1354877Y489615D01*
G01X1354841Y488447D02*
X1348913Y489687D01*
G01X1354877Y489615D02*
X1348920Y490861D01*
G01X1408776Y469743D02*
X1393641Y472958D01*
G01X1408776Y468567D02*
X1393637Y471783D01*
G01X1393641Y472958D02*
X1354431Y464878D01*
G01X1410788Y473054D02*
X1396047Y476003D01*
G01X1410795Y471879D02*
X1396047Y474830D01*
G01Y476003D02*
X1350744Y466942D01*
G01X1396047Y474830D02*
X1350744Y465769D01*
G01Y466942D02*
X1342950Y468501D01*
G01X1350744Y465769D02*
X1342500Y467418D01*
G01X1396136Y466523D02*
X1411057Y463622D01*
G01X1396136Y467695D02*
X1411057Y464794D01*
G01X1396136Y467695D02*
X1411057Y464794D01*
G01X1396136Y466523D02*
X1411057Y463622D01*
G01X1447004Y35395D02*
X1457808Y28195D01*
G01X1446174Y34565D02*
X1457319Y27138D01*
G01X1457808Y28195D02*
X1490505Y18852D01*
G01X1457319Y27138D02*
X1489782Y17862D01*
G01X1446174Y34565D02*
X1457319Y27138D01*
G01X1447004Y35395D02*
X1457808Y28195D01*
G01X1457319Y27138D02*
X1489782Y17862D01*
G01X1457808Y28195D02*
X1490505Y18852D01*
G01X1454146Y36809D02*
X1460082Y29054D01*
G01X1454845Y37790D02*
X1460763Y30057D01*
G01X1460082Y29054D02*
X1493672Y19454D01*
G01X1460763Y30057D02*
X1494394Y20444D01*
G01X1461578Y37356D02*
X1466525Y29942D01*
G01X1454845Y37790D02*
X1460763Y30057D01*
G01X1454146Y36809D02*
X1460082Y29054D01*
G01X1460763Y30057D02*
X1494394Y20444D01*
G01X1460082Y29054D02*
X1493672Y19454D01*
G01X1461578Y37356D02*
X1466525Y29942D01*
G01X1406217Y127118D02*
X1421459Y55369D01*
G01X1405137Y126663D02*
X1420426Y54693D01*
G01X1421459Y55369D02*
X1444857Y38618D01*
G01X1420426Y54693D02*
X1444016Y37805D01*
G01X1444857Y38618D02*
X1447004Y35395D01*
G01X1444016Y37805D02*
X1446174Y34565D01*
G01X1405137Y126663D02*
X1420426Y54693D01*
G01X1406217Y127118D02*
X1421459Y55369D01*
G01X1420426Y54693D02*
X1444016Y37805D01*
G01X1421459Y55369D02*
X1444857Y38618D01*
G01X1444016Y37805D02*
X1446174Y34565D01*
G01X1444857Y38618D02*
X1447004Y35395D01*
G01X1407170Y129162D02*
X1422683Y56164D01*
G01X1408250Y129617D02*
X1423716Y56840D01*
G01X1422683Y56164D02*
X1445900Y39545D01*
G01X1423716Y56840D02*
X1446428Y40582D01*
G01X1445900Y39545D02*
X1454146Y36809D01*
G01X1446428Y40582D02*
X1454845Y37790D01*
G01X1409475Y130402D02*
X1424934Y57640D01*
G01X1410554Y130857D02*
X1425967Y58316D01*
G01X1424934Y57640D02*
X1446088Y42497D01*
G01X1425967Y58316D02*
X1446616Y43534D01*
G01X1446088Y42497D02*
X1461578Y37356D01*
G01X1446616Y43534D02*
X1462316Y38324D01*
G01D02*
X1467247Y30932D01*
G01X1408250Y129617D02*
X1423716Y56840D01*
G01X1407170Y129162D02*
X1422683Y56164D01*
G01X1423716Y56840D02*
X1446428Y40582D01*
G01X1422683Y56164D02*
X1445900Y39545D01*
G01X1446428Y40582D02*
X1454845Y37790D01*
G01X1445900Y39545D02*
X1454146Y36809D01*
G01X1410554Y130857D02*
X1425967Y58316D01*
G01X1409475Y130402D02*
X1424934Y57640D01*
G01X1425967Y58316D02*
X1446616Y43534D01*
G01X1424934Y57640D02*
X1446088Y42497D01*
G01X1446616Y43534D02*
X1462316Y38324D01*
G01X1446088Y42497D02*
X1461578Y37356D01*
G01X1462316Y38324D02*
X1467247Y30932D01*
G01X1457909Y56358D02*
X1483907Y47188D01*
G01X1483985Y48381D02*
X1458446Y57389D01*
G01X1438416Y70313D02*
X1457909Y56358D01*
G01X1458446Y57389D02*
X1439449Y70989D01*
G01X1424000Y138129D02*
X1438416Y70313D01*
G01X1439449Y70989D02*
X1425079Y138584D01*
G01X1439449Y70989D02*
X1425079Y138584D01*
G01X1424000Y138129D02*
X1438416Y70313D01*
G01X1458446Y57389D02*
X1439449Y70989D01*
G01X1438416Y70313D02*
X1457909Y56358D01*
G01X1483985Y48381D02*
X1458446Y57389D01*
G01X1457909Y56358D02*
X1483907Y47188D01*
G01X1411806Y131508D02*
X1427182Y59116D01*
G01X1412885Y131965D02*
X1428215Y59792D01*
G01X1427182Y59116D02*
X1444721Y46563D01*
G01X1428215Y59792D02*
X1445258Y47594D01*
G01X1444721Y46563D02*
X1463015Y40109D01*
G01X1445258Y47594D02*
X1463742Y41072D01*
G01X1463015Y40109D02*
X1468718Y32067D01*
G01X1463742Y41072D02*
X1469423Y33063D01*
G01X1412885Y131965D02*
X1428215Y59792D01*
G01X1411806Y131508D02*
X1427182Y59116D01*
G01X1428215Y59792D02*
X1445258Y47594D01*
G01X1427182Y59116D02*
X1444721Y46563D01*
G01X1445258Y47594D02*
X1463742Y41072D01*
G01X1444721Y46563D02*
X1463015Y40109D01*
G01X1463742Y41072D02*
X1469423Y33063D01*
G01X1463015Y40109D02*
X1468718Y32067D01*
G01X1459081Y58607D02*
X1483991Y49822D01*
G01X1484069Y51015D02*
X1459618Y59638D01*
G01X1440669Y71787D02*
X1459081Y58607D01*
G01X1459618Y59638D02*
X1441702Y72463D01*
G01X1426348Y139163D02*
X1440669Y71787D01*
G01X1441702Y72463D02*
X1427427Y139618D01*
G01X1441702Y72463D02*
X1427427Y139618D01*
G01X1426348Y139163D02*
X1440669Y71787D01*
G01X1459618Y59638D02*
X1441702Y72463D01*
G01X1440669Y71787D02*
X1459081Y58607D01*
G01X1484069Y51015D02*
X1459618Y59638D01*
G01X1459081Y58607D02*
X1483991Y49822D01*
G01X1414124Y133009D02*
X1428861Y63650D01*
G01X1415204Y133464D02*
X1429894Y64326D01*
G01X1428861Y63650D02*
X1452789Y46520D01*
G01X1429894Y64326D02*
X1453326Y47551D01*
G01X1452789Y46520D02*
X1483341Y35744D01*
G01X1453326Y47551D02*
X1483419Y36937D01*
G01X1416340Y134658D02*
X1431112Y65125D01*
G01X1417420Y135113D02*
X1432145Y65801D01*
G01X1431112Y65125D02*
X1453956Y48771D01*
G01X1432145Y65801D02*
X1454493Y49802D01*
G01X1453956Y48771D02*
X1483501Y38351D01*
G01X1454493Y49802D02*
X1483579Y39544D01*
G01X1418638Y135906D02*
X1433362Y66600D01*
G01X1419718Y136361D02*
X1434395Y67276D01*
G01X1433362Y66600D02*
X1455128Y51020D01*
G01X1434395Y67276D02*
X1455665Y52051D01*
G01X1455128Y51020D02*
X1483484Y41018D01*
G01X1455665Y52051D02*
X1483562Y42211D01*
G01X1483521Y43668D02*
X1456300Y53268D01*
G01X1483599Y44861D02*
X1456837Y54299D01*
G01X1456300Y53268D02*
X1435608Y68079D01*
G01X1456837Y54299D02*
X1436641Y68755D01*
G01X1435608Y68079D02*
X1420974Y137007D01*
G01X1436641Y68755D02*
X1422054Y137462D01*
G01X1415204Y133464D02*
X1429894Y64326D01*
G01X1414124Y133009D02*
X1428861Y63650D01*
G01X1429894Y64326D02*
X1453326Y47551D01*
G01X1428861Y63650D02*
X1452789Y46520D01*
G01X1453326Y47551D02*
X1483419Y36937D01*
G01X1452789Y46520D02*
X1483341Y35744D01*
G01X1417420Y135113D02*
X1432145Y65801D01*
G01X1416340Y134658D02*
X1431112Y65125D01*
G01X1432145Y65801D02*
X1454493Y49802D01*
G01X1431112Y65125D02*
X1453956Y48771D01*
G01X1454493Y49802D02*
X1483579Y39544D01*
G01X1453956Y48771D02*
X1483501Y38351D01*
G01X1419718Y136361D02*
X1434395Y67276D01*
G01X1418638Y135906D02*
X1433362Y66600D01*
G01X1434395Y67276D02*
X1455665Y52051D01*
G01X1433362Y66600D02*
X1455128Y51020D01*
G01X1455665Y52051D02*
X1483562Y42211D01*
G01X1455128Y51020D02*
X1483484Y41018D01*
G01X1483599Y44861D02*
X1456837Y54299D01*
G01X1483521Y43668D02*
X1456300Y53268D01*
G01X1456837Y54299D02*
X1436641Y68755D01*
G01X1456300Y53268D02*
X1435608Y68079D01*
G01X1436641Y68755D02*
X1422054Y137462D01*
G01X1435608Y68079D02*
X1420974Y137007D01*
G01X1460252Y60856D02*
X1484150Y52426D01*
G01X1484228Y53619D02*
X1460789Y61887D01*
G01X1443123Y73116D02*
X1460252Y60856D01*
G01X1460789Y61887D02*
X1444156Y73792D01*
G01X1428930Y139905D02*
X1443123Y73116D01*
G01X1444156Y73792D02*
X1430010Y140360D01*
G01X1461422Y63103D02*
X1484206Y55066D01*
G01X1484284Y56259D02*
X1461959Y64134D01*
G01X1445389Y74581D02*
X1461422Y63103D01*
G01X1461959Y64134D02*
X1446421Y75257D01*
G01X1431267Y140987D02*
X1445389Y74581D01*
G01X1446421Y75257D02*
X1432346Y141442D01*
G01X1433623Y142164D02*
X1444669Y90223D01*
G01X1434702Y142619D02*
X1445748Y90678D01*
G01X1444669Y90223D02*
X1450145Y82008D01*
G01D02*
X1450273Y81816D01*
G01X1445748Y90678D02*
X1451103Y82646D01*
G01X1450273Y81816D02*
X1458431Y76378D01*
G01X1451103Y82646D02*
X1459261Y77208D01*
G01X1458431Y76378D02*
X1459355Y74992D01*
G01X1459261Y77208D02*
X1460400Y75501D01*
G01X1459355Y74992D02*
X1460962Y70092D01*
G01X1460400Y75501D02*
X1461939Y70808D01*
G01X1460962Y70092D02*
X1472428Y61884D01*
G01X1461939Y70808D02*
X1472965Y62915D01*
G01X1463141Y71693D02*
X1473804Y64059D01*
G01X1474341Y65090D02*
X1464174Y72369D01*
G01X1460332Y84908D02*
X1463141Y71693D01*
G01X1464174Y72369D02*
X1461412Y85363D01*
G01X1459470Y86204D02*
X1460332Y84908D01*
G01X1461412Y85363D02*
X1460300Y87033D01*
G01X1458112Y87109D02*
X1459470Y86204D01*
G01X1460300Y87033D02*
X1458561Y88192D01*
G01X1453802Y87971D02*
X1458112Y87109D01*
G01X1458561Y88192D02*
X1454251Y89054D01*
G01X1449904Y90568D02*
X1453802Y87971D01*
G01X1454251Y89054D02*
X1450734Y91398D01*
G01X1445935Y96527D02*
X1449904Y90568D01*
G01X1450734Y91398D02*
X1447014Y96984D01*
G01X1444156Y73792D02*
X1430010Y140360D01*
G01X1428930Y139905D02*
X1443123Y73116D01*
G01X1460789Y61887D02*
X1444156Y73792D01*
G01X1443123Y73116D02*
X1460252Y60856D01*
G01X1484228Y53619D02*
X1460789Y61887D01*
G01X1460252Y60856D02*
X1484150Y52426D01*
G01X1446421Y75257D02*
X1432346Y141442D01*
G01X1431267Y140987D02*
X1445389Y74581D01*
G01X1461959Y64134D02*
X1446421Y75257D01*
G01X1445389Y74581D02*
X1461422Y63103D01*
G01X1484284Y56259D02*
X1461959Y64134D01*
G01X1461422Y63103D02*
X1484206Y55066D01*
G01X1434702Y142619D02*
X1445748Y90678D01*
G01X1433623Y142164D02*
X1444669Y90223D01*
G01X1445748Y90678D02*
X1451103Y82646D01*
G01X1444669Y90223D02*
X1450145Y82008D01*
G01X1445748Y90678D02*
X1451103Y82646D01*
G01X1450145Y82008D02*
X1450273Y81816D01*
G01X1451103Y82646D02*
X1459261Y77208D01*
G01X1450273Y81816D02*
X1458431Y76378D01*
G01X1459261Y77208D02*
X1460400Y75501D01*
G01X1458431Y76378D02*
X1459355Y74992D01*
G01X1460400Y75501D02*
X1461939Y70808D01*
G01X1459355Y74992D02*
X1460962Y70092D01*
G01X1461939Y70808D02*
X1472965Y62915D01*
G01X1460962Y70092D02*
X1472428Y61884D01*
G01X1450734Y91398D02*
X1447014Y96984D01*
G01X1445935Y96527D02*
X1449904Y90568D01*
G01X1454251Y89054D02*
X1450734Y91398D01*
G01X1449904Y90568D02*
X1453802Y87971D01*
G01X1458561Y88192D02*
X1454251Y89054D01*
G01X1453802Y87971D02*
X1458112Y87109D01*
G01X1460300Y87033D02*
X1458561Y88192D01*
G01X1458112Y87109D02*
X1459470Y86204D01*
G01X1461412Y85363D02*
X1460300Y87033D01*
G01X1459470Y86204D02*
X1460332Y84908D01*
G01X1464174Y72369D02*
X1461412Y85363D01*
G01X1460332Y84908D02*
X1463141Y71693D01*
G01X1474341Y65090D02*
X1464174Y72369D01*
G01X1463141Y71693D02*
X1473804Y64059D01*
G01X1463088Y89556D02*
X1457952Y96427D01*
G01X1457241Y95456D02*
X1462015Y89069D01*
G01X1466405Y73945D02*
X1463088Y89556D01*
G01X1462015Y89069D02*
X1465372Y73269D01*
G01D02*
X1475212Y66225D01*
G01X1465372Y73269D02*
X1475212Y66225D01*
G01X1462015Y89069D02*
X1465372Y73269D01*
G01X1466405Y73945D02*
X1463088Y89556D01*
G01X1457241Y95456D02*
X1462015Y89069D01*
G01X1463088Y89556D02*
X1457952Y96427D01*
G01X1465305Y91442D02*
X1460127Y98369D01*
G01X1459416Y97398D02*
X1464232Y90955D01*
G01X1468683Y75546D02*
X1465305Y91442D01*
G01X1464232Y90955D02*
X1467650Y74870D01*
G01X1464232Y90955D02*
X1467650Y74870D01*
G01X1468683Y75546D02*
X1465305Y91442D01*
G01X1459416Y97398D02*
X1464232Y90955D01*
G01X1465305Y91442D02*
X1460127Y98369D01*
G01X1404031Y140642D02*
X1410554Y130857D01*
G01X1404031Y140642D02*
X1410554Y130857D01*
G01X1421336Y142123D02*
X1424000Y138129D01*
G01X1425079Y138584D02*
X1422420Y142572D01*
G01X1414510Y176281D02*
X1421336Y142123D01*
G01X1422420Y142572D02*
X1415593Y176731D01*
G01X1422420Y142572D02*
X1415593Y176731D01*
G01X1414510Y176281D02*
X1421336Y142123D01*
G01X1425079Y138584D02*
X1422420Y142572D01*
G01X1421336Y142123D02*
X1424000Y138129D01*
G01X1404957Y141785D02*
X1411806Y131508D01*
G01X1405773Y142637D02*
X1412885Y131965D01*
G01X1405773Y142637D02*
X1412885Y131965D01*
G01X1404957Y141785D02*
X1411806Y131508D01*
G01X1423700Y143132D02*
X1426348Y139163D01*
G01X1427427Y139618D02*
X1424784Y143580D01*
G01X1416857Y177373D02*
X1423700Y143132D01*
G01X1424784Y143580D02*
X1417983Y177612D01*
G01X1424784Y143580D02*
X1417983Y177612D01*
G01X1416857Y177373D02*
X1423700Y143132D01*
G01X1427427Y139618D02*
X1424784Y143580D01*
G01X1423700Y143132D02*
X1426348Y139163D01*
G01X1405713Y164753D02*
X1411186Y137418D01*
G01X1406796Y165202D02*
X1412269Y137867D01*
G01X1411186Y137418D02*
X1414124Y133009D01*
G01X1412269Y137867D02*
X1415204Y133464D01*
G01X1408072Y165994D02*
X1413483Y138946D01*
G01X1409156Y166443D02*
X1414567Y139395D01*
G01X1413483Y138946D02*
X1416340Y134658D01*
G01X1414567Y139395D02*
X1417420Y135113D01*
G01X1410237Y167971D02*
X1415803Y140160D01*
G01X1411320Y168422D02*
X1416886Y140609D01*
G01X1415803Y140160D02*
X1418638Y135906D01*
G01X1416886Y140609D02*
X1417983Y138964D01*
G01X1415803Y140160D02*
X1418638Y135906D01*
G01X1417983Y138964D02*
X1419718Y136361D01*
G01X1420974Y137007D02*
X1418212Y141151D01*
G01X1422054Y137462D02*
X1419296Y141600D01*
G01X1418212Y141151D02*
X1417983Y142297D01*
G01D02*
X1412590Y169282D01*
G01X1419296Y141600D02*
X1413674Y169731D01*
G01X1406796Y165202D02*
X1412269Y137867D01*
G01X1405713Y164753D02*
X1411186Y137418D01*
G01X1412269Y137867D02*
X1415204Y133464D01*
G01X1411186Y137418D02*
X1414124Y133009D01*
G01X1409156Y166443D02*
X1414567Y139395D01*
G01X1408072Y165994D02*
X1413483Y138946D01*
G01X1414567Y139395D02*
X1417420Y135113D01*
G01X1413483Y138946D02*
X1416340Y134658D01*
G01X1411320Y168422D02*
X1416886Y140609D01*
G01X1410237Y167971D02*
X1415803Y140160D01*
G01X1416886Y140609D02*
X1417983Y138964D01*
G01D02*
X1419718Y136361D01*
G01X1415803Y140160D02*
X1418638Y135906D01*
G01X1422054Y137462D02*
X1419296Y141600D01*
G01X1420974Y137007D02*
X1418212Y141151D01*
G01X1419296Y141600D02*
X1413674Y169731D01*
G01X1418212Y141151D02*
X1417983Y142297D01*
G01X1419296Y141600D02*
X1413674Y169731D01*
G01X1417983Y142297D02*
X1412590Y169282D01*
G01X1426045Y144236D02*
X1428930Y139905D01*
G01X1430010Y140360D02*
X1427129Y144685D01*
G01X1419166Y178663D02*
X1426045Y144236D01*
G01X1427129Y144685D02*
X1420249Y179115D01*
G01X1428454Y145207D02*
X1431267Y140987D01*
G01X1432346Y141442D02*
X1429537Y145656D01*
G01X1421553Y179683D02*
X1428454Y145207D01*
G01X1429537Y145656D02*
X1422636Y180134D01*
G01X1420181Y199268D02*
X1430767Y146447D01*
G01X1421354Y199268D02*
X1431850Y146896D01*
G01X1430767Y146447D02*
X1433623Y142164D01*
G01X1431850Y146896D02*
X1434702Y142619D01*
G01X1436009Y143202D02*
X1445935Y96527D01*
G01X1447014Y96984D02*
X1437088Y143658D01*
G01X1433234Y147366D02*
X1436009Y143202D01*
G01X1437088Y143658D02*
X1434317Y147815D01*
G01X1422822Y199422D02*
X1433234Y147366D01*
G01X1434317Y147815D02*
X1424016Y199320D01*
G01X1427129Y144685D02*
X1420249Y179115D01*
G01X1419166Y178663D02*
X1426045Y144236D01*
G01X1430010Y140360D02*
X1427129Y144685D01*
G01X1426045Y144236D02*
X1428930Y139905D01*
G01X1429537Y145656D02*
X1422636Y180134D01*
G01X1421553Y179683D02*
X1428454Y145207D01*
G01X1432346Y141442D02*
X1429537Y145656D01*
G01X1428454Y145207D02*
X1431267Y140987D01*
G01X1421354Y199268D02*
X1431850Y146896D01*
G01X1420181Y199268D02*
X1430767Y146447D01*
G01X1431850Y146896D02*
X1434702Y142619D01*
G01X1430767Y146447D02*
X1433623Y142164D01*
G01X1434317Y147815D02*
X1424016Y199320D01*
G01X1422822Y199422D02*
X1433234Y147366D01*
G01X1437088Y143658D02*
X1434317Y147815D01*
G01X1433234Y147366D02*
X1436009Y143202D01*
G01X1447014Y96984D02*
X1437088Y143658D01*
G01X1436009Y143202D02*
X1445935Y96527D01*
G01X1436982Y148415D02*
X1426816Y199525D01*
G01X1425623Y199627D02*
X1435898Y147968D01*
G01X1439480Y144668D02*
X1436982Y148415D01*
G01X1435898Y147967D02*
X1438401Y144213D01*
G01X1448682Y101392D02*
X1439480Y144668D01*
G01X1438401Y144213D02*
X1447604Y100931D01*
G01X1450241Y99112D02*
X1448682Y101392D01*
G01X1447604Y100931D02*
X1449505Y98150D01*
G01X1457952Y96427D02*
X1450241Y99112D01*
G01X1449505Y98150D02*
X1457241Y95456D01*
G01X1449505Y98150D02*
X1457241Y95456D01*
G01X1457952Y96427D02*
X1450241Y99112D01*
G01X1447604Y100931D02*
X1449505Y98150D01*
G01X1450241Y99112D02*
X1448682Y101392D01*
G01X1438401Y144213D02*
X1447604Y100931D01*
G01X1448682Y101392D02*
X1439480Y144668D01*
G01X1435898Y147967D02*
X1438401Y144213D01*
G01X1439480Y144668D02*
X1436982Y148415D01*
G01X1425623Y199627D02*
X1435898Y147968D01*
G01X1436982Y148415D02*
X1426816Y199525D01*
G01X1443019Y148858D02*
X1441224Y158748D01*
G01X1440135Y158308D02*
X1441842Y148902D01*
G01X1442015Y145004D02*
X1443019Y148858D01*
G01X1441842Y148902D02*
X1440833Y145031D01*
G01X1451073Y102414D02*
X1442015Y145004D01*
G01X1440833Y145031D02*
X1449995Y101952D01*
G01X1451872Y101246D02*
X1451073Y102414D01*
G01X1449995Y101952D02*
X1451136Y100283D01*
G01X1460127Y98369D02*
X1451872Y101246D01*
G01X1451136Y100283D02*
X1459416Y97398D01*
G01X1451136Y100283D02*
X1459416Y97398D01*
G01X1460127Y98369D02*
X1451872Y101246D01*
G01X1449995Y101952D02*
X1451136Y100283D01*
G01X1451872Y101246D02*
X1451073Y102414D01*
G01X1440833Y145031D02*
X1449995Y101952D01*
G01X1451073Y102414D02*
X1442015Y145004D01*
G01X1441842Y148902D02*
X1440833Y145031D01*
G01X1442015Y145004D02*
X1443019Y148858D01*
G01X1440135Y158308D02*
X1441842Y148902D01*
G01X1443019Y148858D02*
X1441224Y158748D01*
G01X1460461Y113224D02*
X1478117Y89607D01*
G01X1477306Y88770D02*
X1459388Y112737D01*
G01X1454780Y139946D02*
X1460461Y113224D01*
G01X1459388Y112737D02*
X1453595Y139989D01*
G01X1456324Y145285D02*
X1454780Y139946D01*
G01X1453595Y139989D02*
X1455129Y145293D01*
G01X1454142Y153248D02*
X1456324Y145285D01*
G01X1455129Y145293D02*
X1453111Y152658D01*
G01X1450762Y156715D02*
X1454142Y153248D01*
G01X1453111Y152658D02*
X1449692Y156163D01*
G01D02*
X1444718Y183542D01*
G01X1449692Y156163D02*
X1444718Y183542D01*
G01X1453111Y152658D02*
X1449692Y156163D01*
G01X1450762Y156715D02*
X1454142Y153248D01*
G01X1455129Y145293D02*
X1453111Y152658D01*
G01X1454142Y153248D02*
X1456324Y145285D01*
G01X1453595Y139989D02*
X1455129Y145293D01*
G01X1456324Y145285D02*
X1454780Y139946D01*
G01X1459388Y112737D02*
X1453595Y139989D01*
G01X1454780Y139946D02*
X1460461Y113224D01*
G01X1477306Y88770D02*
X1459388Y112737D01*
G01X1460461Y113224D02*
X1478117Y89607D01*
G01X1458082Y112147D02*
X1476666Y87286D01*
G01X1475854Y86451D02*
X1457009Y111660D01*
G01X1454893Y127151D02*
X1458082Y112147D01*
G01X1457009Y111660D02*
X1453859Y126481D01*
G01X1451769Y129429D02*
X1454893Y127151D01*
G01X1453859Y126481D02*
X1450735Y128759D01*
G01X1448487Y144857D02*
X1451769Y129429D01*
G01X1450735Y128759D02*
X1447306Y144884D01*
G01X1449570Y149004D02*
X1448487Y144857D01*
G01X1447306Y144884D02*
X1448393Y149049D01*
G01X1444533Y176731D02*
X1449570Y149004D01*
G01X1448393Y149049D02*
X1443492Y176032D01*
G01X1448393Y149049D02*
X1443492Y176032D01*
G01X1444533Y176731D02*
X1449570Y149004D01*
G01X1447306Y144884D02*
X1448393Y149049D01*
G01X1449570Y149004D02*
X1448487Y144857D01*
G01X1450735Y128759D02*
X1447306Y144884D01*
G01X1448487Y144857D02*
X1451769Y129429D01*
G01X1453859Y126481D02*
X1450735Y128759D01*
G01X1451769Y129429D02*
X1454893Y127151D01*
G01X1457009Y111660D02*
X1453859Y126481D01*
G01X1454893Y127151D02*
X1458082Y112147D01*
G01X1475854Y86451D02*
X1457009Y111660D01*
G01X1458082Y112147D02*
X1476666Y87286D01*
G01X1465217Y115380D02*
X1480667Y94715D01*
G01X1479972Y93723D02*
X1464144Y114893D01*
G01X1460034Y139756D02*
X1465217Y115380D01*
G01X1464144Y114893D02*
X1458849Y139799D01*
G01X1461623Y145249D02*
X1460034Y139756D01*
G01X1458849Y139799D02*
X1460428Y145257D01*
G01X1458790Y155589D02*
X1461623Y145249D01*
G01X1460428Y145257D02*
X1457608Y155551D01*
G01X1460856Y165655D02*
X1458790Y155589D01*
G01X1457608Y155551D02*
X1459669Y165593D01*
G01X1457608Y155551D02*
X1459669Y165593D01*
G01X1460856Y165655D02*
X1458790Y155589D01*
G01X1460428Y145257D02*
X1457608Y155551D01*
G01X1458790Y155589D02*
X1461623Y145249D01*
G01X1458849Y139799D02*
X1460428Y145257D01*
G01X1461623Y145249D02*
X1460034Y139756D01*
G01X1464144Y114893D02*
X1458849Y139799D01*
G01X1460034Y139756D02*
X1465217Y115380D01*
G01X1479972Y93723D02*
X1464144Y114893D01*
G01X1465217Y115380D02*
X1480667Y94715D01*
G01X1446346Y149126D02*
X1442975Y167687D01*
G01X1441886Y167247D02*
X1445168Y149171D01*
G01X1445251Y144931D02*
X1446346Y149126D01*
G01X1445168Y149171D02*
X1444069Y144958D01*
G01X1448938Y127594D02*
X1445251Y144931D01*
G01X1444069Y144958D02*
X1447904Y126924D01*
G01X1452062Y125316D02*
X1448938Y127594D01*
G01X1447904Y126924D02*
X1451028Y124646D01*
G01X1455324Y109975D02*
X1452062Y125316D01*
G01X1451028Y124646D02*
X1454251Y109488D01*
G01X1468195Y92756D02*
X1455324Y109975D01*
G01X1454251Y109488D02*
X1467123Y92268D01*
G01X1454251Y109488D02*
X1467123Y92268D01*
G01X1468195Y92756D02*
X1455324Y109975D01*
G01X1451028Y124646D02*
X1454251Y109488D01*
G01X1455324Y109975D02*
X1452062Y125316D01*
G01X1447904Y126924D02*
X1451028Y124646D01*
G01X1452062Y125316D02*
X1448938Y127594D01*
G01X1444069Y144958D02*
X1447904Y126924D01*
G01X1448938Y127594D02*
X1445251Y144931D01*
G01X1445168Y149171D02*
X1444069Y144958D01*
G01X1445251Y144931D02*
X1446346Y149126D01*
G01X1441886Y167247D02*
X1445168Y149171D01*
G01X1446346Y149126D02*
X1442975Y167687D01*
G01X1467595Y116458D02*
X1462661Y139661D01*
G01X1466522Y115971D02*
X1461476Y139704D01*
G01X1462661Y139661D02*
X1464272Y145231D01*
G01X1461476Y139704D02*
X1463077Y145239D01*
G01X1464272Y145231D02*
X1461411Y155673D01*
G01X1463077Y145239D02*
X1460229Y155635D01*
G01X1461411Y155673D02*
X1463730Y166973D01*
G01X1460229Y155635D02*
X1462543Y166911D01*
G01X1466522Y115971D02*
X1461476Y139704D01*
G01X1467595Y116458D02*
X1462661Y139661D01*
G01X1461476Y139704D02*
X1463077Y145239D01*
G01X1462661Y139661D02*
X1464272Y145231D01*
G01X1463077Y145239D02*
X1460229Y155635D01*
G01X1464272Y145231D02*
X1461411Y155673D01*
G01X1460229Y155635D02*
X1462543Y166911D01*
G01X1461411Y155673D02*
X1463730Y166973D01*
G01X1458098Y164902D02*
X1456169Y155497D01*
G01X1456911Y164840D02*
X1454987Y155458D01*
G01X1456169Y155497D02*
X1458973Y145266D01*
G01X1454987Y155458D02*
X1457778Y145274D01*
G01X1458973Y145266D02*
X1457407Y139851D01*
G01X1457778Y145274D02*
X1456222Y139894D01*
G01X1457407Y139851D02*
X1462839Y114304D01*
G01X1456222Y139894D02*
X1461766Y113817D01*
G01X1462839Y114304D02*
X1479144Y92490D01*
G01X1461766Y113817D02*
X1478445Y91504D01*
G01X1456911Y164840D02*
X1454987Y155458D01*
G01X1458098Y164902D02*
X1456169Y155497D01*
G01X1454987Y155458D02*
X1457778Y145274D01*
G01X1456169Y155497D02*
X1458973Y145266D01*
G01X1457778Y145274D02*
X1456222Y139894D01*
G01X1458973Y145266D02*
X1457407Y139851D01*
G01X1456222Y139894D02*
X1461766Y113817D01*
G01X1457407Y139851D02*
X1462839Y114304D01*
G01X1461766Y113817D02*
X1478445Y91504D01*
G01X1462839Y114304D02*
X1479144Y92490D01*
G01X1467403Y145855D02*
X1464145Y157748D01*
G01X1467403Y145855D02*
X1464145Y157748D01*
G01X1410855Y224036D02*
X1409379Y216654D01*
G01X1410414Y215960D02*
X1412046Y224125D01*
G01X1410414Y215960D02*
X1412046Y224125D01*
G01X1410855Y224036D02*
X1409379Y216654D01*
G01X1414684Y185307D02*
X1417983Y180417D01*
G01D02*
X1419166Y178663D01*
G01X1420249Y179115D02*
X1415767Y185759D01*
G01X1410158Y207946D02*
X1414684Y185307D01*
G01X1415767Y185759D02*
X1411333Y207949D01*
G01X1413499Y224257D02*
X1410158Y207946D01*
G01X1411333Y207949D02*
X1414691Y224343D01*
G01X1417708Y185397D02*
X1417983Y184988D01*
G01D02*
X1421553Y179683D01*
G01X1422636Y180134D02*
X1418791Y185848D01*
G01X1412977Y209048D02*
X1417708Y185397D01*
G01X1418791Y185848D02*
X1417983Y189887D01*
G01X1412977Y209048D02*
X1417708Y185397D01*
G01X1417983Y189887D02*
X1414151Y209045D01*
G01X1416150Y224524D02*
X1412977Y209048D01*
G01X1414151Y209045D02*
X1417342Y224610D01*
G01X1418273Y221341D02*
X1421437Y205549D01*
G01X1419447Y221338D02*
X1422610Y205549D01*
G01X1421437D02*
X1420181Y199268D01*
G01X1422610Y205549D02*
X1421354Y199268D01*
G01X1428012Y212919D02*
X1422822Y199422D01*
G01X1424016Y199320D02*
X1429249Y212930D01*
G01X1422472Y226586D02*
X1428012Y212919D01*
G01X1429249Y212930D02*
X1423502Y227112D01*
G01X1411333Y207949D02*
X1414691Y224343D01*
G01X1413499Y224257D02*
X1410158Y207946D01*
G01X1415767Y185759D02*
X1411333Y207949D01*
G01X1410158Y207946D02*
X1414684Y185307D01*
G01X1420249Y179115D02*
X1415767Y185759D01*
G01X1414684Y185307D02*
X1417983Y180417D01*
G01X1420249Y179115D02*
X1415767Y185759D01*
G01X1417983Y180417D02*
X1419166Y178663D01*
G01X1414151Y209045D02*
X1417342Y224610D01*
G01X1416150Y224524D02*
X1412977Y209048D01*
G01X1418791Y185848D02*
X1417983Y189887D01*
G01D02*
X1414151Y209045D01*
G01X1412977Y209048D02*
X1417708Y185397D01*
G01X1422636Y180134D02*
X1418791Y185848D01*
G01X1417708Y185397D02*
X1417983Y184988D01*
G01X1422636Y180134D02*
X1418791Y185848D01*
G01X1417983Y184988D02*
X1421553Y179683D01*
G01X1419447Y221338D02*
X1422610Y205549D01*
G01X1418273Y221341D02*
X1421437Y205549D01*
G01X1422610D02*
X1421354Y199268D01*
G01X1421437Y205549D02*
X1420181Y199268D01*
G01X1429249Y212930D02*
X1423502Y227112D01*
G01X1422472Y226586D02*
X1428012Y212919D01*
G01X1424016Y199320D02*
X1429249Y212930D01*
G01X1428012Y212919D02*
X1422822Y199422D01*
G01X1432178Y213458D02*
X1426621Y227155D01*
G01X1425595Y226624D02*
X1430941Y213447D01*
G01X1426816Y199525D02*
X1432178Y213458D01*
G01X1430941Y213447D02*
X1425623Y199627D01*
G01X1430941Y213447D02*
X1425623Y199627D01*
G01X1426816Y199525D02*
X1432178Y213458D01*
G01X1425595Y226624D02*
X1430941Y213447D01*
G01X1432178Y213458D02*
X1426621Y227155D01*
G01X1435169Y213920D02*
X1430095Y226435D01*
G01X1429069Y225904D02*
X1433932Y213909D01*
G01X1431982Y205623D02*
X1435169Y213920D01*
G01X1433932Y213909D02*
X1430788Y205724D01*
G01X1435520Y187939D02*
X1431982Y205623D01*
G01X1430788Y205724D02*
X1434335Y187998D01*
G01X1433479Y181262D02*
X1435520Y187939D01*
G01X1434335Y187998D02*
X1432294Y181321D01*
G01X1436572Y165732D02*
X1433479Y181262D01*
G01X1432294Y181321D02*
X1435488Y165284D01*
G01X1441224Y158748D02*
X1436572Y165732D01*
G01X1435488Y165284D02*
X1440135Y158308D01*
G01X1435488Y165284D02*
X1440135Y158308D01*
G01X1441224Y158748D02*
X1436572Y165732D01*
G01X1432294Y181321D02*
X1435488Y165284D01*
G01X1436572Y165732D02*
X1433479Y181262D01*
G01X1434335Y187998D02*
X1432294Y181321D01*
G01X1433479Y181262D02*
X1435520Y187939D01*
G01X1430788Y205724D02*
X1434335Y187998D01*
G01X1435520Y187939D02*
X1431982Y205623D01*
G01X1433932Y213909D02*
X1430788Y205724D01*
G01X1431982Y205623D02*
X1435169Y213920D01*
G01X1429069Y225904D02*
X1433932Y213909D01*
G01X1435169Y213920D02*
X1430095Y226435D01*
G01X1445902Y183460D02*
X1450762Y156715D01*
G01X1446225Y184442D02*
X1445902Y183460D01*
G01X1444718Y183542D02*
X1445031Y184494D01*
G01X1442726Y199369D02*
X1446225Y184442D01*
G01X1445031Y184494D02*
X1441549Y199350D01*
G01X1446272Y217125D02*
X1442726Y199369D01*
G01X1441549Y199350D02*
X1445099Y217125D01*
G01X1445841Y219279D02*
X1446272Y217125D01*
G01X1445099D02*
X1444758Y218830D01*
G01X1445099Y217125D02*
X1444758Y218830D01*
G01X1445841Y219279D02*
X1446272Y217125D01*
G01X1441549Y199350D02*
X1445099Y217125D01*
G01X1446272D02*
X1442726Y199369D01*
G01X1445031Y184494D02*
X1441549Y199350D01*
G01X1442726Y199369D02*
X1446225Y184442D01*
G01X1444718Y183542D02*
X1445031Y184494D01*
G01X1446225Y184442D02*
X1445902Y183460D01*
G01D02*
X1450762Y156715D01*
G01X1440911Y179063D02*
X1444533Y176731D01*
G01X1443492Y176032D02*
X1439940Y178319D01*
G01X1440340Y180857D02*
X1440911Y179063D01*
G01X1439940Y178319D02*
X1439128Y180870D01*
G01X1442503Y187170D02*
X1440340Y180857D01*
G01X1439128Y180870D02*
X1441307Y187230D01*
G01X1439872Y198432D02*
X1442503Y187170D01*
G01X1441307Y187230D02*
X1438695Y198413D01*
G01X1443544Y216819D02*
X1439872Y198432D01*
G01X1438695Y198413D02*
X1442371Y216818D01*
G01X1443226Y218402D02*
X1443544Y216819D01*
G01X1442371Y216818D02*
X1442143Y217953D01*
G01D02*
X1429068Y237573D01*
G01X1442143Y217953D02*
X1429068Y237573D01*
G01X1442371Y216818D02*
X1442143Y217953D01*
G01X1443226Y218402D02*
X1443544Y216819D01*
G01X1438695Y198413D02*
X1442371Y216818D01*
G01X1443544Y216819D02*
X1439872Y198432D01*
G01X1441307Y187230D02*
X1438695Y198413D01*
G01X1439872Y198432D02*
X1442503Y187170D01*
G01X1439128Y180870D02*
X1441307Y187230D01*
G01X1442503Y187170D02*
X1440340Y180857D01*
G01X1439940Y178319D02*
X1439128Y180870D01*
G01X1440340Y180857D02*
X1440911Y179063D01*
G01X1443492Y176032D02*
X1439940Y178319D01*
G01X1440911Y179063D02*
X1444533Y176731D01*
G01X1452650Y191581D02*
X1460856Y165655D01*
G01X1459669Y165593D02*
X1451443Y191581D01*
G01X1456148Y202607D02*
X1452650Y191581D01*
G01X1451443D02*
X1454962Y202673D01*
G01X1452284Y222093D02*
X1456148Y202607D01*
G01X1454962Y202673D02*
X1451200Y221645D01*
G01X1454962Y202673D02*
X1451200Y221645D01*
G01X1452284Y222093D02*
X1456148Y202607D01*
G01X1451443Y191581D02*
X1454962Y202673D01*
G01X1456148Y202607D02*
X1452650Y191581D01*
G01X1459669Y165593D02*
X1451443Y191581D01*
G01X1452650D02*
X1460856Y165655D01*
G01X1437759Y210962D02*
X1439298Y218700D01*
G01X1438077Y218458D02*
X1436675Y211410D01*
G01X1436883Y209645D02*
X1437759Y210962D01*
G01X1436675Y211410D02*
X1435799Y210096D01*
G01X1435656Y203505D02*
X1436882Y209645D01*
G01X1435799Y210096D02*
X1434483Y203505D01*
G01X1438856Y187509D02*
X1436441Y199583D01*
G01X1435921Y202181D02*
X1435656Y203505D01*
G01X1434483D02*
X1437670Y187573D01*
G01X1436856Y181164D02*
X1438856Y187509D01*
G01X1437670Y187573D02*
X1435670Y181228D01*
G01X1438086Y175020D02*
X1436856Y181164D01*
G01X1435670Y181228D02*
X1437003Y174571D01*
G01X1442975Y167687D02*
X1438086Y175020D01*
G01X1437003Y174571D02*
X1441886Y167247D01*
G01X1437003Y174571D02*
X1441886Y167247D01*
G01X1442975Y167687D02*
X1438086Y175020D01*
G01X1435670Y181228D02*
X1437003Y174571D01*
G01X1438086Y175020D02*
X1436856Y181164D01*
G01X1437670Y187573D02*
X1435670Y181228D01*
G01X1436856Y181164D02*
X1438856Y187509D01*
G01X1434483Y203505D02*
X1437670Y187573D01*
G01X1438856Y187509D02*
X1436441Y199583D01*
G01X1434483Y203505D02*
X1437670Y187573D01*
G01X1435921Y202181D02*
X1435656Y203505D01*
G01X1435799Y210096D02*
X1434483Y203505D01*
G01X1435656D02*
X1436882Y209645D01*
G01X1436675Y211410D02*
X1435799Y210096D01*
G01X1436883Y209645D02*
X1437759Y210962D01*
G01X1438077Y218458D02*
X1436675Y211410D01*
G01X1437759Y210962D02*
X1439298Y218700D01*
G01X1463730Y166973D02*
X1455772Y192120D01*
G01X1462543Y166911D02*
X1454565Y192120D01*
G01X1455772D02*
X1459020Y202358D01*
G01X1454565Y192120D02*
X1457834Y202423D01*
G01X1459020Y202358D02*
X1452517Y234865D01*
G01X1457834Y202423D02*
X1451436Y234402D01*
G01X1462543Y166911D02*
X1454565Y192120D01*
G01X1463730Y166973D02*
X1455772Y192120D01*
G01X1454565D02*
X1457834Y202423D01*
G01X1455772Y192120D02*
X1459020Y202358D01*
G01X1457834Y202423D02*
X1451436Y234402D01*
G01X1459020Y202358D02*
X1452517Y234865D01*
G01X1446026Y223516D02*
X1450736Y216454D01*
G01X1433824Y239736D02*
X1449654Y215998D01*
G01X1450736Y216454D02*
X1453418Y202942D01*
G01X1449654Y215998D02*
X1452232Y203008D01*
G01X1453418Y202942D02*
X1449737Y191340D01*
G01X1452232Y203008D02*
X1448530Y191341D01*
G01X1449737Y191340D02*
X1458098Y164902D01*
G01X1448530Y191341D02*
X1456911Y164840D01*
G01X1433824Y239736D02*
X1449654Y215998D01*
G01X1433824Y239736D02*
X1449654Y215998D01*
G01X1433824Y239736D02*
X1449654Y215998D01*
G01X1433824Y239736D02*
X1449654Y215998D01*
G01X1433824Y239736D02*
X1449654Y215998D01*
G01X1446026Y223516D02*
X1450736Y216454D01*
G01X1449654Y215998D02*
X1452232Y203008D01*
G01X1450736Y216454D02*
X1453418Y202942D01*
G01X1452232Y203008D02*
X1448530Y191341D01*
G01X1453418Y202942D02*
X1449737Y191340D01*
G01X1448530Y191341D02*
X1456911Y164840D01*
G01X1449737Y191340D02*
X1458098Y164902D01*
G01X1468453Y146376D02*
X1465327Y157787D01*
G01D02*
X1467114Y166504D01*
G01X1464145Y157748D02*
X1465940Y166507D01*
G01X1467114Y166504D02*
X1463602Y184065D01*
G01X1465940Y166507D02*
X1462429Y184065D01*
G01X1463602D02*
X1464577Y188949D01*
G01X1462429Y184065D02*
X1463403Y188943D01*
G01X1464577Y188949D02*
X1454930Y236233D01*
G01X1463403Y188943D02*
X1453847Y235781D01*
G01X1467902Y170112D02*
X1465227Y183492D01*
G01D02*
X1465880Y186616D01*
G01X1468453Y146376D02*
X1465327Y157787D01*
G01X1464145Y157748D02*
X1465940Y166507D01*
G01X1465327Y157787D02*
X1467114Y166504D01*
G01X1465940Y166507D02*
X1462429Y184065D01*
G01X1467114Y166504D02*
X1463602Y184065D01*
G01X1462429D02*
X1463403Y188943D01*
G01X1463602Y184065D02*
X1464577Y188949D01*
G01X1463403Y188943D02*
X1453847Y235781D01*
G01X1464577Y188949D02*
X1454930Y236233D01*
G01X1467902Y170112D02*
X1465227Y183492D01*
G01X1467902Y170112D02*
X1465227Y183492D01*
G01X1467902Y170112D02*
X1465227Y183492D01*
G01D02*
X1465880Y186616D01*
G01X1408225Y223940D02*
X1407169Y218649D01*
G01X1408204Y217956D02*
X1409416Y224029D01*
G01X1404922Y233099D02*
X1408225Y223940D01*
G01X1409416Y224029D02*
X1405960Y233613D01*
G01X1409416Y224029D02*
X1405960Y233613D01*
G01X1404922Y233099D02*
X1408225Y223940D01*
G01X1408204Y217956D02*
X1409416Y224029D01*
G01X1408225Y223940D02*
X1407169Y218649D01*
G01X1406844Y235158D02*
X1410855Y224036D01*
G01X1412046Y224125D02*
X1407884Y235666D01*
G01D02*
X1403867Y242033D01*
G01X1407884Y235666D02*
X1403867Y242033D01*
G01X1412046Y224125D02*
X1407884Y235666D01*
G01X1406844Y235158D02*
X1410855Y224036D01*
G01X1411162Y230740D02*
X1413499Y224257D01*
G01X1414691Y224343D02*
X1412271Y231056D01*
G01X1410102Y235800D02*
X1410213Y235224D01*
G01D02*
X1411162Y230740D01*
G01X1412271Y231056D02*
X1411341Y235452D01*
G01X1410102Y235800D02*
X1410213Y235224D01*
G01X1411341Y235452D02*
X1411187Y236249D01*
G01X1405276Y243095D02*
X1410104Y235800D01*
G01X1411187Y236249D02*
X1406121Y243903D01*
G01X1413506Y231858D02*
X1416150Y224524D01*
G01X1417342Y224610D02*
X1414615Y232173D01*
G01X1410414Y246500D02*
X1413506Y231858D01*
G01X1414615Y232173D02*
X1411448Y247170D01*
G01D02*
X1404270Y252400D01*
G01X1405443Y253277D02*
X1412661Y248015D01*
G01X1406407Y253998D02*
X1413695Y248685D01*
G01X1412661Y248015D02*
X1415971Y232398D01*
G01X1413695Y248685D02*
X1417080Y232714D01*
G01X1415971Y232398D02*
X1418883Y224316D01*
G01X1417080Y232714D02*
X1420075Y224402D01*
G01X1418883Y224316D02*
X1418273Y221341D01*
G01X1420075Y224402D02*
X1419447Y221338D01*
G01X1418595Y232634D02*
X1422472Y226586D01*
G01X1423502Y227112D02*
X1419677Y233078D01*
G01X1415031Y249443D02*
X1417983Y235520D01*
G01D02*
X1418595Y232634D01*
G01X1419677Y233078D02*
X1416065Y250113D01*
G01X1407579Y254875D02*
X1415031Y249443D01*
G01X1416065Y250113D02*
X1408544Y255596D01*
G01D02*
X1404125Y267973D01*
G01X1411187Y236249D02*
X1406121Y243903D01*
G01X1405276Y243095D02*
X1410104Y235800D01*
G01X1412271Y231056D02*
X1411341Y235452D01*
G01D02*
X1411187Y236249D01*
G01X1410102Y235800D02*
X1410213Y235224D01*
G01X1412271Y231056D02*
X1411341Y235452D01*
G01X1410213Y235224D02*
X1411162Y230740D01*
G01X1414691Y224343D02*
X1412271Y231056D01*
G01X1411162Y230740D02*
X1413499Y224257D01*
G01X1411448Y247170D02*
X1404270Y252400D01*
G01X1414615Y232173D02*
X1411448Y247170D01*
G01X1410414Y246500D02*
X1413506Y231858D01*
G01X1417342Y224610D02*
X1414615Y232173D01*
G01X1413506Y231858D02*
X1416150Y224524D01*
G01X1406407Y253998D02*
X1413695Y248685D01*
G01X1405443Y253277D02*
X1412661Y248015D01*
G01X1413695Y248685D02*
X1417080Y232714D01*
G01X1412661Y248015D02*
X1415971Y232398D01*
G01X1417080Y232714D02*
X1420075Y224402D01*
G01X1415971Y232398D02*
X1418883Y224316D01*
G01X1420075Y224402D02*
X1419447Y221338D01*
G01X1418883Y224316D02*
X1418273Y221341D01*
G01X1408544Y255596D02*
X1404125Y267973D01*
G01X1416065Y250113D02*
X1408544Y255596D01*
G01X1407579Y254875D02*
X1415031Y249443D01*
G01X1419677Y233078D02*
X1416065Y250113D01*
G01X1415031Y249443D02*
X1417983Y235520D01*
G01X1419677Y233078D02*
X1416065Y250113D01*
G01X1417983Y235520D02*
X1418595Y232634D01*
G01X1423502Y227112D02*
X1419677Y233078D01*
G01X1418595Y232634D02*
X1422472Y226586D01*
G01X1405420Y271928D02*
X1409441Y285429D01*
G01X1408240Y285428D02*
X1404210Y271896D01*
G01X1410682Y257195D02*
X1405420Y271928D01*
G01X1404210Y271896D02*
X1409718Y256474D01*
G01X1417983Y251873D02*
X1410682Y257195D01*
G01X1409718Y256474D02*
X1417276Y250965D01*
G01X1421957Y234430D02*
X1418310Y251635D01*
G01X1417276Y250965D02*
X1417983Y247630D01*
G01X1421957Y234430D02*
X1418310Y251635D01*
G01X1417983Y247630D02*
X1420875Y233986D01*
G01X1426621Y227155D02*
X1421957Y234430D01*
G01X1420875Y233986D02*
X1425595Y226624D01*
G01X1420875Y233986D02*
X1425595Y226624D01*
G01X1426621Y227155D02*
X1421957Y234430D01*
G01X1417276Y250965D02*
X1417983Y247630D01*
G01D02*
X1420875Y233986D01*
G01X1421957Y234430D02*
X1418310Y251635D01*
G01X1409718Y256474D02*
X1417276Y250965D01*
G01X1417983Y251873D02*
X1410682Y257195D01*
G01X1404210Y271896D02*
X1409718Y256474D01*
G01X1410682Y257195D02*
X1405420Y271928D01*
G01X1408240Y285428D02*
X1404210Y271896D01*
G01X1405420Y271928D02*
X1409441Y285429D01*
G01X1408846Y269917D02*
X1414218Y286390D01*
G01X1413102Y286682D02*
X1407630Y269900D01*
G01X1412819Y258792D02*
X1408846Y269917D01*
G01X1407630Y269900D02*
X1411855Y258071D01*
G01X1420561Y253148D02*
X1412819Y258792D01*
G01X1411855Y258071D02*
X1419527Y252478D01*
G01X1424313Y235457D02*
X1420561Y253148D01*
G01X1419527Y252478D02*
X1423231Y235013D01*
G01X1430095Y226435D02*
X1424313Y235457D01*
G01X1423231Y235013D02*
X1429069Y225904D01*
G01X1423231Y235013D02*
X1429069Y225904D01*
G01X1430095Y226435D02*
X1424313Y235457D01*
G01X1419527Y252478D02*
X1423231Y235013D01*
G01X1424313Y235457D02*
X1420561Y253148D01*
G01X1411855Y258071D02*
X1419527Y252478D01*
G01X1420561Y253148D02*
X1412819Y258792D01*
G01X1407630Y269900D02*
X1411855Y258071D01*
G01X1412819Y258792D02*
X1408846Y269917D01*
G01X1413102Y286682D02*
X1407630Y269900D01*
G01X1408846Y269917D02*
X1414218Y286390D01*
G01X1432524Y239251D02*
X1445841Y219279D01*
G01X1444758Y218830D02*
X1431444Y238796D01*
G01X1428409Y258681D02*
X1432524Y239251D01*
G01X1431444Y238796D02*
X1427374Y258011D01*
G01X1423246Y262445D02*
X1428409Y258681D01*
G01X1427374Y258011D02*
X1422226Y261764D01*
G01X1421374Y270233D02*
X1423246Y262445D01*
G01X1422226Y261764D02*
X1420195Y270217D01*
G01X1428300Y302930D02*
X1421374Y270233D01*
G01X1420195Y270217D02*
X1427150Y303051D01*
G01X1420195Y270217D02*
X1427150Y303051D01*
G01X1428300Y302930D02*
X1421374Y270233D01*
G01X1422226Y261764D02*
X1420195Y270217D01*
G01X1421374Y270233D02*
X1423246Y262445D01*
G01X1427374Y258011D02*
X1422226Y261764D01*
G01X1423246Y262445D02*
X1428409Y258681D01*
G01X1431444Y238796D02*
X1427374Y258011D01*
G01X1428409Y258681D02*
X1432524Y239251D01*
G01X1444758Y218830D02*
X1431444Y238796D01*
G01X1432524Y239251D02*
X1445841Y219279D01*
G01X1430148Y238028D02*
X1443226Y218402D01*
G01X1426072Y257246D02*
X1430148Y238028D01*
G01X1429068Y237573D02*
X1425038Y256576D01*
G01X1420979Y260959D02*
X1426072Y257246D01*
G01X1425038Y256576D02*
X1419959Y260278D01*
G01X1418768Y270164D02*
X1420979Y260959D01*
G01X1419959Y260278D02*
X1417589Y270148D01*
G01X1425550Y302208D02*
X1418768Y270164D01*
G01X1417589Y270148D02*
X1424400Y302329D01*
G01X1417589Y270148D02*
X1424400Y302329D01*
G01X1425550Y302208D02*
X1418768Y270164D01*
G01X1419959Y260278D02*
X1417589Y270148D01*
G01X1418768Y270164D02*
X1420979Y260959D01*
G01X1425038Y256576D02*
X1419959Y260278D01*
G01X1420979Y260959D02*
X1426072Y257246D01*
G01X1429068Y237573D02*
X1425038Y256576D01*
G01X1426072Y257246D02*
X1430148Y238028D01*
G01D02*
X1443226Y218402D01*
G01X1449472Y226310D02*
X1452284Y222093D01*
G01X1451200Y221645D02*
X1448459Y225755D01*
G01X1436097Y256723D02*
X1449472Y226310D01*
G01X1448459Y225755D02*
X1435006Y256345D01*
G01X1434720Y262053D02*
X1436097Y256723D01*
G01X1435006Y256345D02*
X1433666Y261530D01*
G01X1429078Y269198D02*
X1434720Y262053D01*
G01X1433666Y261530D02*
X1427829Y268923D01*
G01X1429966Y272897D02*
X1429078Y269198D01*
G01X1427829Y268923D02*
X1428783Y272896D01*
G01X1428567Y278715D02*
X1429966Y272897D01*
G01X1428783Y272896D02*
X1427388Y278699D01*
G01X1433400Y301586D02*
X1428567Y278715D01*
G01X1427388Y278699D02*
X1432250Y301707D01*
G01X1427388Y278699D02*
X1432250Y301707D01*
G01X1433400Y301586D02*
X1428567Y278715D01*
G01X1428783Y272896D02*
X1427388Y278699D01*
G01X1428567Y278715D02*
X1429966Y272897D01*
G01X1427829Y268923D02*
X1428783Y272896D01*
G01X1429966Y272897D02*
X1429078Y269198D01*
G01X1433666Y261530D02*
X1427829Y268923D01*
G01X1429078Y269198D02*
X1434720Y262053D01*
G01X1435006Y256345D02*
X1433666Y261530D01*
G01X1434720Y262053D02*
X1436097Y256723D01*
G01X1448459Y225755D02*
X1435006Y256345D01*
G01X1436097Y256723D02*
X1449472Y226310D01*
G01X1451200Y221645D02*
X1448459Y225755D01*
G01X1449472Y226310D02*
X1452284Y222093D01*
G01X1415458Y269755D02*
X1422450Y302751D01*
G01X1421300Y302872D02*
X1414279Y269739D01*
G01X1417981Y259253D02*
X1415458Y269755D01*
G01X1414279Y269739D02*
X1416961Y258572D01*
G01X1423267Y255402D02*
X1417981Y259253D01*
G01X1416961Y258572D02*
X1422233Y254732D01*
G01X1427197Y236855D02*
X1423267Y255402D01*
G01X1422233Y254732D02*
X1426117Y236400D01*
G01X1439298Y218700D02*
X1427197Y236855D01*
G01X1426117Y236400D02*
X1438077Y218458D01*
G01X1426117Y236400D02*
X1438077Y218458D01*
G01X1439298Y218700D02*
X1427197Y236855D01*
G01X1422233Y254732D02*
X1426117Y236400D01*
G01X1427197Y236855D02*
X1423267Y255402D01*
G01X1416961Y258572D02*
X1422233Y254732D01*
G01X1423267Y255402D02*
X1417981Y259253D01*
G01X1414279Y269739D02*
X1416961Y258572D01*
G01X1417981Y259253D02*
X1415458Y269755D01*
G01X1421300Y302872D02*
X1414279Y269739D01*
G01X1415458Y269755D02*
X1422450Y302751D01*
G01X1452517Y234865D02*
X1449386Y239334D01*
G01X1451436Y234402D02*
X1448437Y238682D01*
G01X1449386Y239334D02*
X1448442Y240736D01*
G01X1448437Y238682D02*
X1447357Y240287D01*
G01X1448442Y240736D02*
X1447840Y243836D01*
G01X1447357Y240287D02*
X1446755Y243387D01*
G01X1447840Y243836D02*
X1445873Y246752D01*
G01X1446755Y243387D02*
X1445044Y245923D01*
G01X1445873Y246752D02*
X1444133Y247925D01*
G01X1445044Y245923D02*
X1443214Y247157D01*
G01X1444133Y247925D02*
X1442485Y251670D01*
G01X1443214Y247157D02*
X1441286Y251539D01*
G01X1442485Y251670D02*
X1442866Y253590D01*
G01X1441286Y251539D02*
X1441648Y253363D01*
G01X1442866Y253590D02*
X1441720Y255400D01*
G01X1441648Y253363D02*
X1440641Y254952D01*
G01X1441720Y255400D02*
X1440613Y260294D01*
G01X1440641Y254952D02*
X1439600Y259554D01*
G01X1440613Y260294D02*
X1438266Y261673D01*
G01X1439600Y259554D02*
X1437497Y260791D01*
G01X1438266Y261673D02*
X1431845Y269809D01*
G01X1437497Y260791D02*
X1430595Y269534D01*
G01X1431845Y269809D02*
X1432586Y272897D01*
G01X1430595Y269534D02*
X1431403Y272893D01*
G01X1432586Y272897D02*
X1431226Y278557D01*
G01X1431403Y272893D02*
X1430047Y278542D01*
G01X1431226Y278558D02*
X1436000Y301115D01*
G01X1430047Y278542D02*
X1434850Y301236D01*
G01X1451436Y234402D02*
X1448437Y238682D01*
G01X1452517Y234865D02*
X1449386Y239334D01*
G01X1448437Y238682D02*
X1447357Y240287D01*
G01X1449386Y239334D02*
X1448442Y240736D01*
G01X1447357Y240287D02*
X1446755Y243387D01*
G01X1448442Y240736D02*
X1447840Y243836D01*
G01X1446755Y243387D02*
X1445044Y245923D01*
G01X1447840Y243836D02*
X1445873Y246752D01*
G01X1445044Y245923D02*
X1443214Y247157D01*
G01X1445873Y246752D02*
X1444133Y247925D01*
G01X1443214Y247157D02*
X1441286Y251539D01*
G01X1444133Y247925D02*
X1442485Y251670D01*
G01X1441286Y251539D02*
X1441648Y253363D01*
G01X1442485Y251670D02*
X1442866Y253590D01*
G01X1441648Y253363D02*
X1440641Y254952D01*
G01X1442866Y253590D02*
X1441720Y255400D01*
G01X1440641Y254952D02*
X1439600Y259554D01*
G01X1441720Y255400D02*
X1440613Y260294D01*
G01X1439600Y259554D02*
X1437497Y260791D01*
G01X1440613Y260294D02*
X1438266Y261673D01*
G01X1437497Y260791D02*
X1430595Y269534D01*
G01X1438266Y261673D02*
X1431845Y269809D01*
G01X1430595Y269534D02*
X1431403Y272893D01*
G01X1431845Y269809D02*
X1432586Y272897D01*
G01X1431403Y272893D02*
X1430047Y278542D01*
G01X1432586Y272897D02*
X1431226Y278557D01*
G01X1430047Y278542D02*
X1434850Y301236D01*
G01X1431226Y278558D02*
X1436000Y301115D01*
G01X1430900Y302256D02*
X1424054Y269991D01*
G01X1429750Y302377D02*
X1422875Y269975D01*
G01X1424054Y269991D02*
X1425493Y264002D01*
G01X1422875Y269975D02*
X1424473Y263321D01*
G01X1425493Y264002D02*
X1430656Y260239D01*
G01X1424473Y263321D02*
X1429622Y259569D01*
G01X1430656Y260239D02*
X1434904Y240194D01*
G01X1429622Y259569D02*
X1433824Y239736D01*
G01X1434904Y240194D02*
X1437823Y235817D01*
G01X1439293Y233612D02*
X1440117Y232377D01*
G01X1441588Y230172D02*
X1442337Y229049D01*
G01X1443807Y226844D02*
X1444556Y225721D01*
G01X1429750Y302377D02*
X1422875Y269975D01*
G01X1430900Y302256D02*
X1424054Y269991D01*
G01X1422875Y269975D02*
X1424473Y263321D01*
G01X1424054Y269991D02*
X1425493Y264002D01*
G01X1424473Y263321D02*
X1429622Y259569D01*
G01X1425493Y264002D02*
X1430656Y260239D01*
G01X1429622Y259569D02*
X1433824Y239736D01*
G01X1430656Y260239D02*
X1434904Y240194D01*
G01D02*
X1437823Y235817D01*
G01X1439293Y233612D02*
X1440117Y232377D01*
G01X1441588Y230172D02*
X1442337Y229049D01*
G01X1443807Y226844D02*
X1444556Y225721D01*
G01X1454930Y236233D02*
X1450642Y242591D01*
G01X1453847Y235781D02*
X1449557Y242142D01*
G01X1450642Y242591D02*
X1449908Y246371D01*
G01X1449557Y242142D02*
X1448823Y245922D01*
G01X1449908Y246371D02*
X1448237Y248849D01*
G01X1448823Y245922D02*
X1447408Y248020D01*
G01X1448237Y248849D02*
X1445828Y250474D01*
G01X1447408Y248020D02*
X1444859Y249740D01*
G01X1445828Y250474D02*
X1445153Y252011D01*
G01X1444859Y249819D02*
X1443954Y251879D01*
G01X1445153Y252011D02*
X1445587Y254200D01*
G01X1443954Y251879D02*
X1444369Y253973D01*
G01X1445587Y254200D02*
X1443995Y256713D01*
G01X1444369Y253973D02*
X1442917Y256265D01*
G01X1443995Y256713D02*
X1442694Y262450D01*
G01X1442917Y256265D02*
X1441702Y261622D01*
G01X1442694Y262450D02*
X1439990Y263602D01*
G01X1441702Y261622D02*
X1439269Y262659D01*
G01X1439990Y263602D02*
X1435594Y269171D01*
G01X1439269Y262659D02*
X1434334Y268909D01*
G01X1435594Y269171D02*
X1438037Y278407D01*
G01X1434334Y268909D02*
X1436836Y278365D01*
G01X1438037Y278407D02*
X1435430Y286049D01*
G01X1436835Y278365D02*
X1434239Y285978D01*
G01X1466219Y228448D02*
X1465164Y227749D01*
G01D02*
G02X1463813Y228024I-538J813D01*
G01X1465799Y226790D02*
G02X1462854Y227389I-1173J1772D01*
G01X1463813Y228024D02*
X1456636Y238864D01*
G01X1462854Y227389D02*
X1455553Y238415D01*
G01X1456636Y238864D02*
X1455121Y246312D01*
G01X1455553Y238415D02*
X1454038Y245863D01*
G01X1455121Y246312D02*
X1449841Y254287D01*
G01X1454038Y245863D02*
X1449072Y253362D01*
G01X1449841Y254287D02*
X1447211Y256506D01*
G01X1449118Y253392D02*
X1449099Y253407D01*
G01X1449841Y254287D02*
X1447211Y256506D01*
G01X1449099Y253407D02*
X1446358Y255721D01*
G01X1447211Y256506D02*
X1446433Y257600D01*
G01X1446358Y255721D02*
X1445361Y257121D01*
G01X1446433Y257600D02*
X1446027Y259398D01*
G01X1445361Y257121D02*
X1444904Y259144D01*
G01X1446027Y259398D02*
X1445281Y264225D01*
G01X1444904Y259144D02*
X1444890Y259223D01*
G01X1446027Y259398D02*
X1445281Y264225D01*
G01X1444890Y259223D02*
X1444240Y263427D01*
G01X1445281Y264225D02*
X1441296Y265988D01*
G01X1444240Y263427D02*
X1440569Y265051D01*
G01X1441296Y265988D02*
X1438371Y269694D01*
G01X1440569Y265051D02*
X1437111Y269432D01*
G01X1438371Y269694D02*
X1440700Y278500D01*
G01X1437111Y269432D02*
X1439499Y278458D01*
G01X1440700Y278500D02*
X1438053Y286257D01*
G01X1439498Y278458D02*
X1436862Y286185D01*
G01X1453847Y235781D02*
X1449557Y242142D01*
G01X1454930Y236233D02*
X1450642Y242591D01*
G01X1449557Y242142D02*
X1448823Y245922D01*
G01X1450642Y242591D02*
X1449908Y246371D01*
G01X1448823Y245922D02*
X1447408Y248020D01*
G01X1449908Y246371D02*
X1448237Y248849D01*
G01X1447408Y248020D02*
X1444859Y249740D01*
G01X1448237Y248849D02*
X1445828Y250474D01*
G01X1444859Y249819D02*
X1443954Y251879D01*
G01X1445828Y250474D02*
X1445153Y252011D01*
G01X1443954Y251879D02*
X1444369Y253973D01*
G01X1445153Y252011D02*
X1445587Y254200D01*
G01X1444369Y253973D02*
X1442917Y256265D01*
G01X1445587Y254200D02*
X1443995Y256713D01*
G01X1442917Y256265D02*
X1441702Y261622D01*
G01X1443995Y256713D02*
X1442694Y262450D01*
G01X1441702Y261622D02*
X1439269Y262659D01*
G01X1442694Y262450D02*
X1439990Y263602D01*
G01X1439269Y262659D02*
X1434334Y268909D01*
G01X1439990Y263602D02*
X1435594Y269171D01*
G01X1434334Y268909D02*
X1436836Y278365D01*
G01X1435594Y269171D02*
X1438037Y278407D01*
G01X1436835Y278365D02*
X1434239Y285978D01*
G01X1438037Y278407D02*
X1435430Y286049D01*
G01X1466219Y228448D02*
X1465164Y227749D01*
G01X1465799Y226790D02*
G02X1462854Y227389I-1173J1772D01*
G01X1465164Y227749D02*
G02X1463813Y228024I-538J813D01*
G01X1462854Y227389D02*
X1455553Y238415D01*
G01X1463813Y228024D02*
X1456636Y238864D01*
G01X1455553Y238415D02*
X1454038Y245863D01*
G01X1456636Y238864D02*
X1455121Y246312D01*
G01X1454038Y245863D02*
X1449072Y253362D01*
G01X1455121Y246312D02*
X1449841Y254287D01*
G01X1449118Y253392D02*
X1449099Y253407D01*
G01D02*
X1446358Y255721D01*
G01X1449841Y254287D02*
X1447211Y256506D01*
G01X1446358Y255721D02*
X1445361Y257121D01*
G01X1447211Y256506D02*
X1446433Y257600D01*
G01X1445361Y257121D02*
X1444904Y259144D01*
G01X1446433Y257600D02*
X1446027Y259398D01*
G01X1444904Y259144D02*
X1444890Y259223D01*
G01D02*
X1444240Y263427D01*
G01X1446027Y259398D02*
X1445281Y264225D01*
G01X1444240Y263427D02*
X1440569Y265051D01*
G01X1445281Y264225D02*
X1441296Y265988D01*
G01X1440569Y265051D02*
X1437111Y269432D01*
G01X1441296Y265988D02*
X1438371Y269694D01*
G01X1437111Y269432D02*
X1439499Y278458D01*
G01X1438371Y269694D02*
X1440700Y278500D01*
G01X1439498Y278458D02*
X1436862Y286185D01*
G01X1440700Y278500D02*
X1438053Y286257D01*
G01X1406163Y332077D02*
X1406706Y334870D01*
G01X1405078Y332526D02*
X1405534Y334869D01*
G01X1406706Y334870D02*
X1406042Y338286D01*
G01X1405534Y334869D02*
X1404870Y338286D01*
G01X1406042D02*
X1406622Y341188D01*
G01X1404869Y338289D02*
X1407657Y352242D01*
G01X1405078Y332526D02*
X1405534Y334869D01*
G01X1406163Y332077D02*
X1406706Y334870D01*
G01X1405534Y334869D02*
X1404870Y338286D01*
G01X1406706Y334870D02*
X1406042Y338286D01*
G01X1404869Y338289D02*
X1407657Y352242D01*
G01X1406042Y338286D02*
X1406622Y341188D01*
G01X1404869Y338289D02*
X1407657Y352242D01*
G01X1409127Y326462D02*
X1410384Y327309D01*
G01X1409576Y325377D02*
X1411212Y326480D01*
G01X1410384Y327309D02*
X1411049Y328296D01*
G01X1411212Y326480D02*
X1412134Y327846D01*
G01X1411049Y328296D02*
X1412718Y336879D01*
G01X1412134Y327846D02*
X1413890Y336879D01*
G01X1412718D02*
X1411986Y340642D01*
G01Y340643D02*
X1411941Y340877D01*
G01X1413890Y336879D02*
X1413115Y340863D01*
G01X1411894Y341111D02*
X1410416Y348716D01*
G01X1411894Y341111D02*
X1410416Y348716D01*
G01X1409576Y325377D02*
X1411212Y326480D01*
G01X1409127Y326462D02*
X1410384Y327309D01*
G01X1411212Y326480D02*
X1412134Y327846D01*
G01X1410384Y327309D02*
X1411049Y328296D01*
G01X1412134Y327846D02*
X1413890Y336879D01*
G01X1411049Y328296D02*
X1412718Y336879D01*
G01X1413890D02*
X1413115Y340863D01*
G01X1412718Y336879D02*
X1411986Y340642D01*
G01X1413890Y336879D02*
X1413115Y340863D01*
G01X1411986Y340643D02*
X1411941Y340877D01*
G01X1411894Y341111D02*
X1410416Y348716D01*
G01X1406362Y295674D02*
Y301596D01*
G01X1405212D02*
Y295504D01*
G01X1409441Y285429D02*
X1406362Y295674D01*
G01X1405212Y295504D02*
X1408240Y285428D01*
G01X1405212Y295504D02*
X1408240Y285428D01*
G01X1409441Y285429D02*
X1406362Y295674D01*
G01X1405212Y301596D02*
Y295504D01*
G01X1406362Y295674D02*
Y301596D01*
G01X1414218Y286390D02*
X1417040Y301401D01*
G01D02*
X1417041Y301406D01*
G01X1415893Y301528D02*
X1413102Y286682D01*
G01X1415893Y301528D02*
X1413102Y286682D01*
G01X1414218Y286390D02*
X1417040Y301401D01*
G01X1415893Y301528D02*
X1413102Y286682D01*
G01X1417040Y301401D02*
X1417041Y301406D01*
G01X1428300Y316329D02*
Y302930D01*
G01X1427150Y303051D02*
Y316446D01*
G01X1430702Y328089D02*
X1428300Y316329D01*
G01X1427150Y316446D02*
X1429528Y328091D01*
G01X1427370Y344752D02*
X1430702Y328089D01*
G01X1429528Y328091D02*
X1426197Y344752D01*
G01X1429528Y328091D02*
X1426197Y344752D01*
G01X1427370D02*
X1430702Y328089D01*
G01X1427150Y316446D02*
X1429528Y328091D01*
G01X1430702Y328089D02*
X1428300Y316329D01*
G01X1427150Y303051D02*
Y316446D01*
G01X1428300Y316329D02*
Y302930D01*
G01X1425550Y317376D02*
Y302208D01*
G01X1424400Y302329D02*
Y317498D01*
G01X1427555Y327028D02*
X1425550Y317376D01*
G01X1424400Y317498D02*
X1426381Y327032D01*
G01X1424199Y343800D02*
X1427555Y327028D01*
G01X1426381Y327032D02*
X1423026Y343800D01*
G01X1426381Y327032D02*
X1423026Y343800D01*
G01X1424199D02*
X1427555Y327028D01*
G01X1424400Y317498D02*
X1426381Y327032D01*
G01X1427555Y327028D02*
X1425550Y317376D01*
G01X1424400Y302329D02*
Y317498D01*
G01X1425550Y317376D02*
Y302208D01*
G01X1433400Y315599D02*
Y301586D01*
G01X1432250Y301707D02*
Y315720D01*
G01X1436641Y330894D02*
X1433400Y315599D01*
G01X1432250Y315720D02*
X1435466Y330901D01*
G01X1434224Y342977D02*
X1436641Y330894D01*
G01X1435466Y330901D02*
X1433051Y342977D01*
G01X1435466Y330901D02*
X1433051Y342977D01*
G01X1434224D02*
X1436641Y330894D01*
G01X1432250Y315720D02*
X1435466Y330901D01*
G01X1436641Y330894D02*
X1433400Y315599D01*
G01X1432250Y301707D02*
Y315720D01*
G01X1433400Y315599D02*
Y301586D01*
G01X1423360Y323675D02*
X1422261Y329171D01*
G01X1421741Y331769D02*
X1421476Y333093D01*
G01X1420957Y335691D02*
X1420692Y337015D01*
G01X1420172Y339613D02*
X1419907Y340937D01*
G01X1417950Y344859D02*
X1422186Y323679D01*
G01X1421590Y315115D02*
X1423360Y323675D01*
G01X1422186Y323679D02*
X1420415Y315112D01*
G01X1422450Y311061D02*
X1421590Y315115D01*
G01X1420415Y315112D02*
X1421300Y310940D01*
G01X1422450Y302751D02*
Y311061D01*
G01X1421300Y310940D02*
Y302872D01*
G01Y310940D02*
Y302872D01*
G01X1422450Y302751D02*
Y311061D01*
G01X1420415Y315112D02*
X1421300Y310940D01*
G01X1422450Y311061D02*
X1421590Y315115D01*
G01X1422186Y323679D02*
X1420415Y315112D01*
G01X1421590Y315115D02*
X1423360Y323675D01*
G01X1417950Y344859D02*
X1422186Y323679D01*
G01X1423360Y323675D02*
X1422261Y329171D01*
G01X1417950Y344859D02*
X1422186Y323679D01*
G01X1421741Y331769D02*
X1421476Y333093D01*
G01X1417950Y344859D02*
X1422186Y323679D01*
G01X1420957Y335691D02*
X1420692Y337015D01*
G01X1417950Y344859D02*
X1422186Y323679D01*
G01X1420172Y339613D02*
X1419907Y340937D01*
G01X1417950Y344859D02*
X1422186Y323679D01*
G01X1436000Y301115D02*
Y315603D01*
G01X1434850Y301236D02*
Y315724D01*
G01X1436000Y315603D02*
X1439560Y332400D01*
G01X1434850Y315724D02*
X1438385Y332407D01*
G01X1439560Y332400D02*
X1437420Y343100D01*
G01X1438385Y332407D02*
X1436247Y343100D01*
G01X1434850Y301236D02*
Y315724D01*
G01X1436000Y301115D02*
Y315603D01*
G01X1434850Y315724D02*
X1438385Y332407D01*
G01X1436000Y315603D02*
X1439560Y332400D01*
G01X1438385Y332407D02*
X1436247Y343100D01*
G01X1439560Y332400D02*
X1437420Y343100D01*
G01X1430714Y342324D02*
X1433485Y328476D01*
G01X1429541Y342324D02*
X1432310Y328483D01*
G01X1433485Y328476D02*
X1430900Y316284D01*
G01X1432310Y328483D02*
X1429750Y316405D01*
G01X1430900Y316284D02*
Y302256D01*
G01X1429750Y316405D02*
Y302377D01*
G01X1429541Y342324D02*
X1432310Y328483D01*
G01X1430714Y342324D02*
X1433485Y328476D01*
G01X1432310Y328483D02*
X1429750Y316405D01*
G01X1433485Y328476D02*
X1430900Y316284D01*
G01X1429750Y316405D02*
Y302377D01*
G01X1430900Y316284D02*
Y302256D01*
G01X1435430Y286049D02*
X1438549Y300761D01*
G01X1434239Y285978D02*
X1437399Y300883D01*
G01X1438550Y300761D02*
Y314545D01*
G01X1437400Y300883D02*
Y314659D01*
G01X1438550Y314545D02*
X1442298Y333294D01*
G01X1437400Y314659D02*
X1441125Y333294D01*
G01X1442298D02*
X1441325Y338159D01*
G01X1441125Y333294D02*
X1440152Y338159D01*
G01X1441325D02*
X1444023Y351655D01*
G01X1440152Y338159D02*
X1442988Y352348D01*
G01X1438053Y286257D02*
X1440700Y298770D01*
G01X1436862Y286185D02*
X1439550Y298891D01*
G01X1440700Y298770D02*
Y312663D01*
G01X1439550Y298891D02*
Y313140D01*
G01X1440700Y312663D02*
X1441150Y313113D01*
G01X1439550Y313140D02*
X1440673Y314263D01*
G01X1441150Y313113D02*
X1441939D01*
G01D02*
X1443750Y314924D01*
G01X1440673Y314263D02*
X1441462D01*
G01X1441939Y313113D02*
X1443750Y314924D01*
G01X1441462Y314263D02*
X1442600Y315401D01*
G01X1443750Y314924D02*
Y318550D01*
G01X1442600Y315401D02*
Y319027D01*
G01X1443750Y318550D02*
X1446360Y321160D01*
G01X1442600Y319027D02*
X1445883Y322310D01*
G01X1446360Y321160D02*
X1451713D01*
G01X1445883Y322310D02*
X1451236D01*
G01X1451713Y321160D02*
X1464490Y333941D01*
G01X1451236Y322310D02*
X1463340Y334418D01*
G01X1464490Y333941D02*
Y343537D01*
G01X1463340Y334418D02*
Y343060D01*
G01X1434239Y285978D02*
X1437399Y300883D01*
G01X1435430Y286049D02*
X1438549Y300761D01*
G01X1437400Y300883D02*
Y314659D01*
G01X1438550Y300761D02*
Y314545D01*
G01X1437400Y314659D02*
X1441125Y333294D01*
G01X1438550Y314545D02*
X1442298Y333294D01*
G01X1441125D02*
X1440152Y338159D01*
G01X1442298Y333294D02*
X1441325Y338159D01*
G01X1440152D02*
X1442988Y352348D01*
G01X1441325Y338159D02*
X1444023Y351655D01*
G01X1436862Y286185D02*
X1439550Y298891D01*
G01X1438053Y286257D02*
X1440700Y298770D01*
G01X1439550Y298891D02*
Y313140D01*
G01X1440700Y298770D02*
Y312663D01*
G01X1439550Y313140D02*
X1440673Y314263D01*
G01X1440700Y312663D02*
X1441150Y313113D01*
G01X1440673Y314263D02*
X1441462D01*
G01X1441150Y313113D02*
X1441939D01*
G01X1440673Y314263D02*
X1441462D01*
G01D02*
X1442600Y315401D01*
G01X1441939Y313113D02*
X1443750Y314924D01*
G01X1442600Y315401D02*
Y319027D01*
G01X1443750Y314924D02*
Y318550D01*
G01X1442600Y319027D02*
X1445883Y322310D01*
G01X1443750Y318550D02*
X1446360Y321160D01*
G01X1445883Y322310D02*
X1451236D01*
G01X1446360Y321160D02*
X1451713D01*
G01X1451236Y322310D02*
X1463340Y334418D01*
G01X1451713Y321160D02*
X1464490Y333941D01*
G01X1463340Y334418D02*
Y343060D01*
G01X1464490Y333941D02*
Y343537D01*
G01X1407141Y343787D02*
X1408741Y351795D01*
G01D02*
X1411276Y355625D01*
G01X1407657Y352242D02*
X1410444Y356454D01*
G01X1411276Y355625D02*
X1427199Y366243D01*
G01X1410444Y356454D02*
X1426228Y366978D01*
G01X1427199Y366243D02*
X1429949Y374747D01*
G01X1426228Y366978D02*
X1428760Y374808D01*
G01X1429949Y374747D02*
X1428877Y379788D01*
G01X1428760Y374808D02*
X1427701Y379788D01*
G01X1428877D02*
X1429815Y384213D01*
G01X1427701Y379788D02*
X1428639Y384213D01*
G01X1429815D02*
X1428530Y390271D01*
G01X1428639Y384213D02*
X1427355Y390266D01*
G01X1428530Y390271D02*
X1430450Y399694D01*
G01X1427355Y390266D02*
X1429300Y399810D01*
G01X1430450Y399694D02*
Y423065D01*
G01X1429300Y399810D02*
Y423186D01*
G01X1406532Y355249D02*
X1411702Y363001D01*
G01X1405447Y355695D02*
X1411009Y364035D01*
G01X1411702Y363001D02*
X1420170Y364698D01*
G01X1411009Y364035D02*
X1419721Y365781D01*
G01X1420170Y364698D02*
X1424944Y367881D01*
G01X1419721Y365781D02*
X1423972Y368616D01*
G01X1424944Y367881D02*
X1427204Y374882D01*
G01X1423972Y368616D02*
X1426015Y374943D01*
G01X1427204Y374882D02*
X1426238Y379433D01*
G01X1426015Y374943D02*
X1425062Y379433D01*
G01X1426238D02*
X1427230Y384092D01*
G01X1425062Y379433D02*
X1426054Y384092D01*
G01X1427230D02*
X1425884Y390432D01*
G01X1426054Y384092D02*
X1424708Y390432D01*
G01X1425884D02*
X1427950Y400155D01*
G01X1424708Y390432D02*
X1426800Y400280D01*
G01X1427950Y400155D02*
Y423330D01*
G01X1426800Y400280D02*
Y423451D01*
G01X1403929Y356350D02*
X1409739Y365063D01*
G01D02*
X1415455Y369486D01*
G01X1408886Y365858D02*
X1414964Y370561D01*
G01X1415455Y369486D02*
X1421852Y370768D01*
G01X1414964Y370561D02*
X1421403Y371851D01*
G01X1421852Y370768D02*
X1423580Y371920D01*
G01X1421403Y371851D02*
X1422546Y372613D01*
G01X1423580Y371920D02*
X1424342Y375712D01*
G01X1422546Y372613D02*
X1423167Y375706D01*
G01X1424342Y375712D02*
X1423598Y379219D01*
G01X1423167Y375706D02*
X1422422Y379219D01*
G01X1423598D02*
X1424648Y384152D01*
G01X1422422Y379219D02*
X1423472Y384152D01*
G01X1424648D02*
X1423316Y390425D01*
G01X1423472Y384152D02*
X1422140Y390425D01*
G01X1423316D02*
X1425450Y400453D01*
G01X1422140Y390425D02*
X1424300Y400575D01*
G01X1425450Y400453D02*
Y424422D01*
G01X1424300Y400575D02*
Y424543D01*
G01X1412980Y370788D02*
X1407918Y366871D01*
G01X1407065Y367666D02*
X1411921Y371423D01*
G01X1415809Y387506D02*
X1414982Y382620D01*
G01X1414541Y380007D02*
X1414315Y378676D01*
G01X1413873Y376062D02*
X1413648Y374732D01*
G01X1413206Y372119D02*
X1412980Y370788D01*
G01X1411921Y371423D02*
X1414709Y387901D01*
G01X1417962Y391250D02*
X1415809Y387506D01*
G01X1414709Y387901D02*
X1416736Y391427D01*
G01X1416988Y395305D02*
X1417962Y391250D01*
G01X1416736Y391427D02*
X1415751Y395529D01*
G01X1418711Y397860D02*
X1416988Y395305D01*
G01X1415751Y395529D02*
X1417882Y398689D01*
G01X1420664Y399177D02*
X1418711Y397860D01*
G01X1417882Y398689D02*
X1419836Y400006D01*
G01X1422950Y402564D02*
X1420664Y399177D01*
G01X1419836Y400006D02*
X1421800Y402916D01*
G01X1422950Y424687D02*
Y402564D01*
G01X1421800Y402916D02*
Y424808D01*
G01X1410120Y371821D02*
X1406143Y368746D01*
G01X1405290Y369541D02*
X1409085Y372476D01*
G01X1411610Y378630D02*
X1410120Y371821D01*
G01X1409085Y372476D02*
X1410428Y378612D01*
G01X1409024Y388962D02*
X1411610Y378630D01*
G01X1410428Y378612D02*
X1407823Y389022D01*
G01X1413025Y400106D02*
X1409024Y388962D01*
G01X1407823Y389022D02*
X1412067Y400845D01*
G01X1418240Y403684D02*
X1413025Y400106D01*
G01X1412067Y400845D02*
X1417402Y404505D01*
G01X1407141Y343787D02*
X1408741Y351795D01*
G01X1407657Y352242D02*
X1410444Y356454D01*
G01X1408741Y351795D02*
X1411276Y355625D01*
G01X1410444Y356454D02*
X1426228Y366978D01*
G01X1411276Y355625D02*
X1427199Y366243D01*
G01X1426228Y366978D02*
X1428760Y374808D01*
G01X1427199Y366243D02*
X1429949Y374747D01*
G01X1428760Y374808D02*
X1427701Y379788D01*
G01X1429949Y374747D02*
X1428877Y379788D01*
G01X1427701D02*
X1428639Y384213D01*
G01X1428877Y379788D02*
X1429815Y384213D01*
G01X1428639D02*
X1427355Y390266D01*
G01X1429815Y384213D02*
X1428530Y390271D01*
G01X1427355Y390266D02*
X1429300Y399810D01*
G01X1428530Y390271D02*
X1430450Y399694D01*
G01X1429300Y399810D02*
Y423186D01*
G01X1430450Y399694D02*
Y423065D01*
G01X1405447Y355695D02*
X1411009Y364035D01*
G01X1406532Y355249D02*
X1411702Y363001D01*
G01X1411009Y364035D02*
X1419721Y365781D01*
G01X1411702Y363001D02*
X1420170Y364698D01*
G01X1419721Y365781D02*
X1423972Y368616D01*
G01X1420170Y364698D02*
X1424944Y367881D01*
G01X1423972Y368616D02*
X1426015Y374943D01*
G01X1424944Y367881D02*
X1427204Y374882D01*
G01X1426015Y374943D02*
X1425062Y379433D01*
G01X1427204Y374882D02*
X1426238Y379433D01*
G01X1425062D02*
X1426054Y384092D01*
G01X1426238Y379433D02*
X1427230Y384092D01*
G01X1426054D02*
X1424708Y390432D01*
G01X1427230Y384092D02*
X1425884Y390432D01*
G01X1424708D02*
X1426800Y400280D01*
G01X1425884Y390432D02*
X1427950Y400155D01*
G01X1426800Y400280D02*
Y423451D01*
G01X1427950Y400155D02*
Y423330D01*
G01X1403929Y356350D02*
X1409739Y365063D01*
G01X1408886Y365858D02*
X1414964Y370561D01*
G01X1409739Y365063D02*
X1415455Y369486D01*
G01X1414964Y370561D02*
X1421403Y371851D01*
G01X1415455Y369486D02*
X1421852Y370768D01*
G01X1421403Y371851D02*
X1422546Y372613D01*
G01X1421852Y370768D02*
X1423580Y371920D01*
G01X1422546Y372613D02*
X1423167Y375706D01*
G01X1423580Y371920D02*
X1424342Y375712D01*
G01X1423167Y375706D02*
X1422422Y379219D01*
G01X1424342Y375712D02*
X1423598Y379219D01*
G01X1422422D02*
X1423472Y384152D01*
G01X1423598Y379219D02*
X1424648Y384152D01*
G01X1423472D02*
X1422140Y390425D01*
G01X1424648Y384152D02*
X1423316Y390425D01*
G01X1422140D02*
X1424300Y400575D01*
G01X1423316Y390425D02*
X1425450Y400453D01*
G01X1424300Y400575D02*
Y424543D01*
G01X1425450Y400453D02*
Y424422D01*
G01X1421800Y402916D02*
Y424808D01*
G01X1422950Y424687D02*
Y402564D01*
G01X1419836Y400006D02*
X1421800Y402916D01*
G01X1422950Y402564D02*
X1420664Y399177D01*
G01X1417882Y398689D02*
X1419836Y400006D01*
G01X1420664Y399177D02*
X1418711Y397860D01*
G01X1415751Y395529D02*
X1417882Y398689D01*
G01X1418711Y397860D02*
X1416988Y395305D01*
G01X1416736Y391427D02*
X1415751Y395529D01*
G01X1416988Y395305D02*
X1417962Y391250D01*
G01X1414709Y387901D02*
X1416736Y391427D01*
G01X1417962Y391250D02*
X1415809Y387506D01*
G01X1411921Y371423D02*
X1414709Y387901D01*
G01X1415809Y387506D02*
X1414982Y382620D01*
G01X1411921Y371423D02*
X1414709Y387901D01*
G01X1414541Y380007D02*
X1414315Y378676D01*
G01X1411921Y371423D02*
X1414709Y387901D01*
G01X1413873Y376062D02*
X1413648Y374732D01*
G01X1411921Y371423D02*
X1414709Y387901D01*
G01X1413206Y372119D02*
X1412980Y370788D01*
G01X1407065Y367666D02*
X1411921Y371423D01*
G01X1412980Y370788D02*
X1407918Y366871D01*
G01X1412067Y400845D02*
X1417402Y404505D01*
G01X1418240Y403684D02*
X1413025Y400106D01*
G01X1407823Y389022D02*
X1412067Y400845D01*
G01X1413025Y400106D02*
X1409024Y388962D01*
G01X1410428Y378612D02*
X1407823Y389022D01*
G01X1409024Y388962D02*
X1411610Y378630D01*
G01X1409085Y372476D02*
X1410428Y378612D01*
G01X1411610Y378630D02*
X1410120Y371821D01*
G01X1405290Y369541D02*
X1409085Y372476D01*
G01X1410120Y371821D02*
X1406143Y368746D01*
G01X1412609Y343464D02*
X1412352Y344790D01*
G01X1411846Y347391D02*
X1411588Y348716D01*
G01X1410416D02*
X1411198Y352736D01*
G01X1411588Y348716D02*
X1412283Y352290D01*
G01X1411198Y352736D02*
X1412576Y354803D01*
G01X1412283Y352290D02*
X1413470Y354070D01*
G01X1412576Y354803D02*
X1412739Y354966D01*
G01X1413470Y354070D02*
X1413472Y354072D01*
G01X1412739Y354966D02*
X1428491Y365466D01*
G01X1413472Y354072D02*
X1429463Y364731D01*
G01X1428491Y365466D02*
X1431406Y374483D01*
G01X1429463Y364731D02*
X1432595Y374421D01*
G01X1431406Y374483D02*
X1430277Y379803D01*
G01X1432595Y374421D02*
X1431453Y379803D01*
G01X1430277D02*
X1431227Y384290D01*
G01X1431453Y379803D02*
X1432403Y384290D01*
G01X1431227D02*
X1429965Y390246D01*
G01X1432403Y384290D02*
X1431141Y390248D01*
G01X1429965Y390246D02*
X1431800Y399029D01*
G01X1431141Y390248D02*
X1432950Y398910D01*
G01X1431800Y399029D02*
Y422920D01*
G01X1432950Y398910D02*
Y422799D01*
G01X1412609Y343464D02*
X1412352Y344790D01*
G01X1411846Y347391D02*
X1411588Y348716D01*
G01D02*
X1412283Y352290D01*
G01X1410416Y348716D02*
X1411198Y352736D01*
G01X1412283Y352290D02*
X1413470Y354070D01*
G01X1411198Y352736D02*
X1412576Y354803D01*
G01X1413470Y354070D02*
X1413472Y354072D01*
G01X1412576Y354803D02*
X1412739Y354966D01*
G01X1413472Y354072D02*
X1429463Y364731D01*
G01X1412739Y354966D02*
X1428491Y365466D01*
G01X1429463Y364731D02*
X1432595Y374421D01*
G01X1428491Y365466D02*
X1431406Y374483D01*
G01X1432595Y374421D02*
X1431453Y379803D01*
G01X1431406Y374483D02*
X1430277Y379803D01*
G01X1431453D02*
X1432403Y384290D01*
G01X1430277Y379803D02*
X1431227Y384290D01*
G01X1432403D02*
X1431141Y390248D01*
G01X1431227Y384290D02*
X1429965Y390246D01*
G01X1431141Y390248D02*
X1432950Y398910D01*
G01X1429965Y390246D02*
X1431800Y399029D01*
G01X1432950Y398910D02*
Y422799D01*
G01X1431800Y399029D02*
Y422920D01*
G01X1429223Y354016D02*
X1427370Y344752D01*
G01X1426197D02*
X1428188Y354709D01*
G01X1438324Y360083D02*
X1429223Y354016D01*
G01X1428188Y354709D02*
X1437352Y360818D01*
G01X1442729Y373723D02*
X1438324Y360083D01*
G01X1437352Y360818D02*
X1441539Y373784D01*
G01X1441547Y379290D02*
X1442729Y373723D01*
G01X1441540Y373784D02*
X1440371Y379290D01*
G01X1442400Y383304D02*
X1441547Y379290D01*
G01X1440371D02*
X1441224Y383305D01*
G01X1440980Y390034D02*
X1442400Y383304D01*
G01X1441224Y383305D02*
X1439804Y390035D01*
G01X1442627Y397799D02*
X1440980Y390034D01*
G01X1439804Y390035D02*
X1441572Y398372D01*
G01X1447600Y402773D02*
X1442627Y397799D01*
G01X1441572Y398372D02*
X1446450Y403250D01*
G01X1447600Y406182D02*
Y402773D01*
G01Y406182D02*
Y402773D01*
G01X1441572Y398372D02*
X1446450Y403250D01*
G01X1447600Y402773D02*
X1442627Y397799D01*
G01X1439804Y390035D02*
X1441572Y398372D01*
G01X1442627Y397799D02*
X1440980Y390034D01*
G01X1441224Y383305D02*
X1439804Y390035D01*
G01X1440980Y390034D02*
X1442400Y383304D01*
G01X1440371Y379290D02*
X1441224Y383305D01*
G01X1442400Y383304D02*
X1441547Y379290D01*
G01X1441540Y373784D02*
X1440371Y379290D01*
G01X1441547D02*
X1442729Y373723D01*
G01X1437352Y360818D02*
X1441539Y373784D01*
G01X1442729Y373723D02*
X1438324Y360083D01*
G01X1428188Y354709D02*
X1437352Y360818D01*
G01X1438324Y360083D02*
X1429223Y354016D01*
G01X1426197Y344752D02*
X1428188Y354709D01*
G01X1429223Y354016D02*
X1427370Y344752D01*
G01X1426484Y355211D02*
X1424199Y343800D01*
G01X1423026D02*
X1425449Y355904D01*
G01X1435536Y361245D02*
X1426484Y355211D01*
G01X1425449Y355904D02*
X1434564Y361980D01*
G01X1439807Y374468D02*
X1435536Y361245D01*
G01X1434564Y361980D02*
X1438618Y374529D01*
G01X1438709Y379639D02*
X1439807Y374468D01*
G01X1438618Y374529D02*
X1437533Y379637D01*
G01X1439579Y383817D02*
X1438709Y379639D01*
G01X1437533Y379637D02*
X1438403Y383815D01*
G01X1438247Y390091D02*
X1439579Y383817D01*
G01X1438403Y383815D02*
X1437071Y390091D01*
G01X1440106Y398829D02*
X1438247Y390091D01*
G01X1437071D02*
X1439051Y399402D01*
G01X1443385Y402109D02*
X1440106Y398829D01*
G01X1439051Y399402D02*
X1442235Y402586D01*
G01X1443385Y405917D02*
Y402109D01*
G01X1442235Y402586D02*
Y404768D01*
G01Y402586D02*
Y404768D01*
G01X1443385Y405917D02*
Y402109D01*
G01X1439051Y399402D02*
X1442235Y402586D01*
G01X1443385Y402109D02*
X1440106Y398829D01*
G01X1437071Y390091D02*
X1439051Y399402D01*
G01X1440106Y398829D02*
X1438247Y390091D01*
G01X1438403Y383815D02*
X1437071Y390091D01*
G01X1438247D02*
X1439579Y383817D01*
G01X1437533Y379637D02*
X1438403Y383815D01*
G01X1439579Y383817D02*
X1438709Y379639D01*
G01X1438618Y374529D02*
X1437533Y379637D01*
G01X1438709Y379639D02*
X1439807Y374468D01*
G01X1434564Y361980D02*
X1438618Y374529D01*
G01X1439807Y374468D02*
X1435536Y361245D01*
G01X1425449Y355904D02*
X1434564Y361980D01*
G01X1435536Y361245D02*
X1426484Y355211D01*
G01X1423026Y343800D02*
X1425449Y355904D01*
G01X1426484Y355211D02*
X1424199Y343800D01*
G01X1436110Y352412D02*
X1434224Y342977D01*
G01X1433051D02*
X1435075Y353105D01*
G01X1442752Y356839D02*
X1436110Y352412D01*
G01X1435075Y353105D02*
X1441949Y357686D01*
G01X1452935Y370486D02*
X1442752Y356839D01*
G01X1441949Y357686D02*
X1451859Y370969D01*
G01X1454643Y378800D02*
X1452935Y370486D01*
G01X1451859Y370969D02*
X1453493Y378917D01*
G01X1454643Y387485D02*
Y378800D01*
G01X1453493Y378917D02*
Y387606D01*
G01X1455472Y391399D02*
X1454643Y387485D01*
G01X1453493Y387606D02*
X1454296Y391399D01*
G01X1454484Y396055D02*
X1455472Y391399D01*
G01X1454296D02*
X1453308Y396053D01*
G01X1459531Y420309D02*
X1454484Y396055D01*
G01X1453308Y396053D02*
X1458449Y420758D01*
G01X1453308Y396053D02*
X1458449Y420758D01*
G01X1459531Y420309D02*
X1454484Y396055D01*
G01X1454296Y391399D02*
X1453308Y396053D01*
G01X1454484Y396055D02*
X1455472Y391399D01*
G01X1453493Y387606D02*
X1454296Y391399D01*
G01X1455472D02*
X1454643Y387485D01*
G01X1453493Y378917D02*
Y387606D01*
G01X1454643Y387485D02*
Y378800D01*
G01X1451859Y370969D02*
X1453493Y378917D01*
G01X1454643Y378800D02*
X1452935Y370486D01*
G01X1441949Y357686D02*
X1451859Y370969D01*
G01X1452935Y370486D02*
X1442752Y356839D01*
G01X1435075Y353105D02*
X1441949Y357686D01*
G01X1442752Y356839D02*
X1436110Y352412D01*
G01X1433051Y342977D02*
X1435075Y353105D01*
G01X1436110Y352412D02*
X1434224Y342977D01*
G01X1436050Y397554D02*
Y408951D01*
G01X1434900Y409428D02*
Y397676D01*
G01X1434673Y391088D02*
X1436050Y397554D01*
G01X1434900Y397676D02*
X1433497Y391088D01*
G01X1435987Y384895D02*
X1434673Y391088D01*
G01X1433497D02*
X1434811Y384895D01*
G01X1434842Y379502D02*
X1435987Y384895D01*
G01X1434811D02*
X1433666Y379502D01*
G01X1435976Y374164D02*
X1434842Y379502D01*
G01X1433666D02*
X1434787Y374225D01*
G01X1432342Y362913D02*
X1435976Y374164D01*
G01X1434787Y374225D02*
X1431370Y363648D01*
G01X1424060Y357388D02*
X1432342Y362913D01*
G01X1431370Y363648D02*
X1423230Y358218D01*
G01X1420588Y352183D02*
X1424060Y357388D01*
G01X1423230Y358218D02*
X1419505Y352632D01*
G01X1419123Y344859D02*
X1419388Y346183D01*
G01X1419908Y348781D02*
X1420588Y352183D01*
G01X1419505Y352632D02*
X1417950Y344859D01*
G01X1419388Y343535D02*
X1419123Y344859D01*
G01X1419388Y343535D02*
X1419123Y344859D01*
G01X1419505Y352632D02*
X1417950Y344859D01*
G01X1419123D02*
X1419388Y346183D01*
G01X1419505Y352632D02*
X1417950Y344859D01*
G01X1419908Y348781D02*
X1420588Y352183D01*
G01X1423230Y358218D02*
X1419505Y352632D01*
G01X1420588Y352183D02*
X1424060Y357388D01*
G01X1431370Y363648D02*
X1423230Y358218D01*
G01X1424060Y357388D02*
X1432342Y362913D01*
G01X1434787Y374225D02*
X1431370Y363648D01*
G01X1432342Y362913D02*
X1435976Y374164D01*
G01X1433666Y379502D02*
X1434787Y374225D01*
G01X1435976Y374164D02*
X1434842Y379502D01*
G01X1434811Y384895D02*
X1433666Y379502D01*
G01X1434842D02*
X1435987Y384895D01*
G01X1433497Y391088D02*
X1434811Y384895D01*
G01X1435987D02*
X1434673Y391088D01*
G01X1434900Y397676D02*
X1433497Y391088D01*
G01X1434673D02*
X1436050Y397554D01*
G01X1434900Y409428D02*
Y397676D01*
G01X1436050Y397554D02*
Y408951D01*
G01X1437420Y343100D02*
X1439073Y351369D01*
G01X1436247Y343100D02*
X1438038Y352061D01*
G01X1439073Y351369D02*
X1445628Y355739D01*
G01X1438038Y352061D02*
X1444812Y356577D01*
G01X1445628Y355739D02*
X1455338Y369494D01*
G01X1444812Y356577D02*
X1454611Y370459D01*
G01X1455338Y369494D02*
X1459319Y370882D01*
G01X1454611Y370459D02*
X1458493Y371813D01*
G01X1459319Y370882D02*
X1460645Y373591D01*
G01X1458493Y371813D02*
X1459432Y373730D01*
G01X1460645Y373591D02*
X1459756Y377442D01*
G01X1459432Y373730D02*
X1458606Y377311D01*
G01X1459756Y377442D02*
Y388514D01*
G01X1458606Y377311D02*
Y388364D01*
G01X1459756Y388514D02*
X1459198Y390630D01*
G01X1458606Y388364D02*
X1458189Y389942D01*
G01X1459198Y390630D02*
X1458320Y391273D01*
G01X1458189Y389942D02*
X1457304Y390590D01*
G01X1458320Y391273D02*
X1457087Y396202D01*
G01X1457304Y390590D02*
X1455907Y396178D01*
G01X1457087Y396202D02*
X1461691Y418334D01*
G01X1455907Y396178D02*
X1460599Y418733D01*
G01X1436247Y343100D02*
X1438038Y352061D01*
G01X1437420Y343100D02*
X1439073Y351369D01*
G01X1438038Y352061D02*
X1444812Y356577D01*
G01X1439073Y351369D02*
X1445628Y355739D01*
G01X1444812Y356577D02*
X1454611Y370459D01*
G01X1445628Y355739D02*
X1455338Y369494D01*
G01X1454611Y370459D02*
X1458493Y371813D01*
G01X1455338Y369494D02*
X1459319Y370882D01*
G01X1458493Y371813D02*
X1459432Y373730D01*
G01X1459319Y370882D02*
X1460645Y373591D01*
G01X1459432Y373730D02*
X1458606Y377311D01*
G01X1460645Y373591D02*
X1459756Y377442D01*
G01X1458606Y377311D02*
Y388364D01*
G01X1459756Y377442D02*
Y388514D01*
G01X1458606Y388364D02*
X1458189Y389942D01*
G01X1459756Y388514D02*
X1459198Y390630D01*
G01X1458189Y389942D02*
X1457304Y390590D01*
G01X1459198Y390630D02*
X1458320Y391273D01*
G01X1457304Y390590D02*
X1455907Y396178D01*
G01X1458320Y391273D02*
X1457087Y396202D01*
G01X1455907Y396178D02*
X1460599Y418733D01*
G01X1457087Y396202D02*
X1461691Y418334D01*
G01X1450212Y403955D02*
X1452848Y391528D01*
G01X1449033Y403969D02*
X1451672Y391528D01*
G01X1452848D02*
X1451967Y387372D01*
G01X1451672Y391528D02*
X1450817Y387493D01*
G01X1451967Y387372D02*
Y378343D01*
G01X1450817Y387493D02*
Y378464D01*
G01X1451967Y378343D02*
X1450697Y372364D01*
G01X1450817Y378464D02*
X1449623Y372847D01*
G01X1450697Y372364D02*
X1440453Y358496D01*
G01X1449623Y372847D02*
X1439647Y359342D01*
G01X1440453Y358496D02*
X1432946Y353488D01*
G01X1439647Y359342D02*
X1431911Y354183D01*
G01X1432946Y353488D02*
X1431498Y346246D01*
G01X1430979Y343648D02*
X1430714Y342324D01*
G01X1431911Y354183D02*
X1429541Y342324D01*
G01X1449033Y403969D02*
X1451672Y391528D01*
G01X1450212Y403955D02*
X1452848Y391528D01*
G01X1451672D02*
X1450817Y387493D01*
G01X1452848Y391528D02*
X1451967Y387372D01*
G01X1450817Y387493D02*
Y378464D01*
G01X1451967Y387372D02*
Y378343D01*
G01X1450817Y378464D02*
X1449623Y372847D01*
G01X1451967Y378343D02*
X1450697Y372364D01*
G01X1449623Y372847D02*
X1439647Y359342D01*
G01X1450697Y372364D02*
X1440453Y358496D01*
G01X1439647Y359342D02*
X1431911Y354183D01*
G01X1440453Y358496D02*
X1432946Y353488D01*
G01X1431911Y354183D02*
X1429541Y342324D01*
G01X1432946Y353488D02*
X1431498Y346246D01*
G01X1431911Y354183D02*
X1429541Y342324D01*
G01X1430979Y343648D02*
X1430714Y342324D01*
G01X1444023Y351655D02*
X1448176Y354423D01*
G01X1442988Y352348D02*
X1447354Y355258D01*
G01X1448176Y354423D02*
X1451984Y359946D01*
G01X1447354Y355258D02*
X1451096Y360686D01*
G01X1451984Y359946D02*
X1461347Y369310D01*
G01X1451096Y360686D02*
X1460397Y369988D01*
G01X1461347Y369310D02*
X1463347Y373397D01*
G01X1460398Y369988D02*
X1462135Y373536D01*
G01X1463347Y373397D02*
X1462736Y376045D01*
G01X1462135Y373536D02*
X1461586Y375913D01*
G01X1462736Y376045D02*
Y387102D01*
G01X1461586Y375913D02*
Y386952D01*
G01X1462736Y387102D02*
X1461935Y390131D01*
G01X1461586Y386952D02*
X1460785Y389981D01*
G01X1461935Y390131D02*
Y395125D01*
G01X1460785Y389981D02*
Y395004D01*
G01X1461935Y395125D02*
X1461111Y399008D01*
G01X1460785Y395004D02*
X1459935Y399003D01*
G01X1461111Y399008D02*
X1464133Y413540D01*
G01X1459935Y399003D02*
X1463077Y414111D01*
G01X1464490Y343537D02*
X1457000Y351027D01*
G01X1463340Y343060D02*
X1455850Y350550D01*
G01X1457000Y351027D02*
Y357141D01*
G01X1455850Y350550D02*
Y357499D01*
G01X1457000Y357141D02*
X1461262Y363341D01*
G01X1455850Y357499D02*
X1460514Y364284D01*
G01X1461262Y363341D02*
X1464608Y364649D01*
G01X1460514Y364284D02*
X1463965Y365633D01*
G01X1464608Y364649D02*
X1466895Y366935D01*
G01X1463965Y365633D02*
X1465840Y367508D01*
G01X1442988Y352348D02*
X1447354Y355258D01*
G01X1444023Y351655D02*
X1448176Y354423D01*
G01X1447354Y355258D02*
X1451096Y360686D01*
G01X1448176Y354423D02*
X1451984Y359946D01*
G01X1451096Y360686D02*
X1460397Y369988D01*
G01X1451984Y359946D02*
X1461347Y369310D01*
G01X1460398Y369988D02*
X1462135Y373536D01*
G01X1461347Y369310D02*
X1463347Y373397D01*
G01X1462135Y373536D02*
X1461586Y375913D01*
G01X1463347Y373397D02*
X1462736Y376045D01*
G01X1461586Y375913D02*
Y386952D01*
G01X1462736Y376045D02*
Y387102D01*
G01X1461586Y386952D02*
X1460785Y389981D01*
G01X1462736Y387102D02*
X1461935Y390131D01*
G01X1460785Y389981D02*
Y395004D01*
G01X1461935Y390131D02*
Y395125D01*
G01X1460785Y395004D02*
X1459935Y399003D01*
G01X1461935Y395125D02*
X1461111Y399008D01*
G01X1459935Y399003D02*
X1463077Y414111D01*
G01X1461111Y399008D02*
X1464133Y413540D01*
G01X1463340Y343060D02*
X1455850Y350550D01*
G01X1464490Y343537D02*
X1457000Y351027D01*
G01X1455850Y350550D02*
Y357499D01*
G01X1457000Y351027D02*
Y357141D01*
G01X1455850Y357499D02*
X1460514Y364284D01*
G01X1457000Y357141D02*
X1461262Y363341D01*
G01X1460514Y364284D02*
X1463965Y365633D01*
G01X1461262Y363341D02*
X1464608Y364649D01*
G01X1463965Y365633D02*
X1465840Y367508D01*
G01X1464608Y364649D02*
X1466895Y366935D01*
G01X1430450Y423065D02*
X1432004Y430372D01*
G01X1429300Y423186D02*
X1430970Y431044D01*
G01X1432004Y430372D02*
X1437542Y434393D01*
G01X1430970Y431044D02*
X1436560Y435102D01*
G01X1437542Y434393D02*
X1438909Y438693D01*
G01X1439711Y441218D02*
X1440120Y442505D01*
G01X1436560Y435102D02*
X1438921Y442530D01*
G01X1440120Y442505D02*
X1438736Y447575D01*
G01X1438921Y442530D02*
X1437537Y447600D01*
G01X1438736Y447575D02*
X1439664Y450483D01*
G01X1437537Y447600D02*
X1438691Y451221D01*
G01X1439664Y450483D02*
X1443642Y453100D01*
G01X1438691Y451221D02*
X1443297Y454250D01*
G01X1443642Y453100D02*
X1446900D01*
G01X1443297Y454250D02*
X1446813D01*
G01X1427950Y423330D02*
X1429754Y431844D01*
G01X1426800Y423451D02*
X1428720Y432515D01*
G01X1429754Y431844D02*
X1435257Y435838D01*
G01X1428720Y432515D02*
X1434275Y436547D01*
G01X1435257Y435838D02*
X1437454Y442740D01*
G01X1434275Y436547D02*
X1436255Y442765D01*
G01X1437454Y442740D02*
X1436086Y447755D01*
G01X1436255Y442765D02*
X1434886Y447780D01*
G01X1436086Y447755D02*
X1437575Y452427D01*
G01X1434886Y447780D02*
X1436602Y453164D01*
G01X1437575Y452427D02*
X1443760Y456498D01*
G01X1436602Y453164D02*
X1443415Y457648D01*
G01X1443760Y456498D02*
X1460772D01*
G01X1443415Y457648D02*
X1460772D01*
G01X1425450Y424422D02*
X1427445Y433834D01*
G01X1424300Y424543D02*
X1426262Y433800D01*
G01X1427445Y433834D02*
X1426275Y438133D01*
G01X1426262Y433800D02*
X1425076Y438159D01*
G01X1426275Y438133D02*
X1427150Y440877D01*
G01X1425076Y438159D02*
X1425950Y440904D01*
G01X1427150Y440877D02*
X1426219Y444284D01*
G01X1425950Y440904D02*
X1425110Y443979D01*
G01X1425518Y446857D02*
X1425112Y448342D01*
G01X1425105Y443999D02*
X1423902Y448404D01*
G01X1425112Y448342D02*
X1425599Y449601D01*
G01X1426556Y452072D02*
X1427398Y454246D01*
G01X1423902Y448404D02*
X1426390Y454830D01*
G01X1427398Y454246D02*
X1428830Y456016D01*
G01X1426390Y454830D02*
X1428140Y456992D01*
G01X1428830Y456015D02*
X1438509Y459435D01*
G01X1441008Y460318D02*
X1442281Y460767D01*
G01X1444779Y461650D02*
X1446052Y462100D01*
G01X1428140Y456992D02*
X1445854Y463250D01*
G01X1446052Y462100D02*
X1458010D01*
G01X1445854Y463250D02*
X1458010D01*
G01X1424758Y433221D02*
X1422950Y424687D01*
G01X1421800Y424808D02*
X1423575Y433187D01*
G01X1423452Y438006D02*
X1424758Y433221D01*
G01X1423575Y433187D02*
X1422252Y438031D01*
G01X1424386Y440934D02*
X1423452Y438006D01*
G01X1422252Y438031D02*
X1423186Y440959D01*
G01X1422388Y448251D02*
X1424386Y440934D01*
G01X1423186Y440959D02*
X1421178Y448315D01*
G01X1425378Y455963D02*
X1422388Y448251D01*
G01X1421178Y448315D02*
X1424370Y456547D01*
G01X1427504Y458592D02*
X1425378Y455963D01*
G01X1424370Y456547D02*
X1426814Y459568D01*
G01X1440699Y463251D02*
X1427504Y458592D01*
G01X1426814Y459568D02*
X1440211Y464299D01*
G01X1442600Y464371D02*
X1440699Y463251D01*
G01X1440211Y464299D02*
X1454043Y472450D01*
G01X1420450Y407054D02*
X1418240Y403684D01*
G01X1417402Y404505D02*
X1419300Y407398D01*
G01X1420450Y425217D02*
Y407054D01*
G01X1419300Y407398D02*
Y425338D01*
G01X1422092Y432966D02*
X1420450Y425217D01*
G01X1419300Y425338D02*
X1420909Y432932D01*
G01X1420763Y437835D02*
X1422092Y432966D01*
G01X1420909Y432932D02*
X1419563Y437861D01*
G01X1421770Y440989D02*
X1420763Y437835D01*
G01X1419563Y437861D02*
X1420570Y441015D01*
G01X1419744Y448415D02*
X1421770Y440989D01*
G01X1420570Y441015D02*
X1418534Y448478D01*
G01X1423306Y457616D02*
X1419744Y448415D01*
G01X1418534Y448478D02*
X1422298Y458200D01*
G01X1426365Y461397D02*
X1423306Y457616D01*
G01X1422298Y458200D02*
X1425675Y462373D01*
G01X1439817Y466151D02*
X1426365Y461397D01*
G01X1425675Y462373D02*
X1439329Y467199D01*
G01X1439150Y470003D02*
X1419897Y463201D01*
G01X1439641Y468956D02*
X1420200Y462088D01*
G01X1419897Y463201D02*
X1411000Y461472D01*
G01X1420200Y462088D02*
X1410999Y460300D01*
G01D02*
X1404007Y461659D01*
G01X1411057Y463622D02*
X1423026Y465947D01*
G01X1429300Y423186D02*
X1430970Y431044D01*
G01X1430450Y423065D02*
X1432004Y430372D01*
G01X1430970Y431044D02*
X1436560Y435102D01*
G01X1432004Y430372D02*
X1437542Y434393D01*
G01X1436560Y435102D02*
X1438921Y442530D01*
G01X1437542Y434393D02*
X1438909Y438693D01*
G01X1436560Y435102D02*
X1438921Y442530D01*
G01X1439711Y441218D02*
X1440120Y442505D01*
G01X1438921Y442530D02*
X1437537Y447600D01*
G01X1440120Y442505D02*
X1438736Y447575D01*
G01X1437537Y447600D02*
X1438691Y451221D01*
G01X1438736Y447575D02*
X1439664Y450483D01*
G01X1438691Y451221D02*
X1443297Y454250D01*
G01X1439664Y450483D02*
X1443642Y453100D01*
G01X1443297Y454250D02*
X1446813D01*
G01X1443642Y453100D02*
X1446900D01*
G01X1426800Y423451D02*
X1428720Y432515D01*
G01X1427950Y423330D02*
X1429754Y431844D01*
G01X1428720Y432515D02*
X1434275Y436547D01*
G01X1429754Y431844D02*
X1435257Y435838D01*
G01X1434275Y436547D02*
X1436255Y442765D01*
G01X1435257Y435838D02*
X1437454Y442740D01*
G01X1436255Y442765D02*
X1434886Y447780D01*
G01X1437454Y442740D02*
X1436086Y447755D01*
G01X1434886Y447780D02*
X1436602Y453164D01*
G01X1436086Y447755D02*
X1437575Y452427D01*
G01X1436602Y453164D02*
X1443415Y457648D01*
G01X1437575Y452427D02*
X1443760Y456498D01*
G01X1443415Y457648D02*
X1460772D01*
G01X1443760Y456498D02*
X1460772D01*
G01X1424300Y424543D02*
X1426262Y433800D01*
G01X1425450Y424422D02*
X1427445Y433834D01*
G01X1426262Y433800D02*
X1425076Y438159D01*
G01X1427445Y433834D02*
X1426275Y438133D01*
G01X1425076Y438159D02*
X1425950Y440904D01*
G01X1426275Y438133D02*
X1427150Y440877D01*
G01X1425950Y440904D02*
X1425110Y443979D01*
G01X1427150Y440877D02*
X1426219Y444284D01*
G01X1425105Y443999D02*
X1423902Y448404D01*
G01X1425518Y446857D02*
X1425112Y448342D01*
G01X1423902Y448404D02*
X1426390Y454830D01*
G01X1425112Y448342D02*
X1425599Y449601D01*
G01X1423902Y448404D02*
X1426390Y454830D01*
G01X1426556Y452072D02*
X1427398Y454246D01*
G01X1426390Y454830D02*
X1428140Y456992D01*
G01X1427398Y454246D02*
X1428830Y456016D01*
G01X1428140Y456992D02*
X1445854Y463250D01*
G01X1428830Y456015D02*
X1438509Y459435D01*
G01X1428140Y456992D02*
X1445854Y463250D01*
G01X1441008Y460318D02*
X1442281Y460767D01*
G01X1428140Y456992D02*
X1445854Y463250D01*
G01X1444779Y461650D02*
X1446052Y462100D01*
G01X1445854Y463250D02*
X1458010D01*
G01X1446052Y462100D02*
X1458010D01*
G01X1440211Y464299D02*
X1454043Y472450D01*
G01X1440211Y464299D02*
X1454043Y472450D01*
G01X1440211Y464299D02*
X1454043Y472450D01*
G01X1440211Y464299D02*
X1454043Y472450D01*
G01X1442600Y464371D02*
X1440699Y463251D01*
G01X1426814Y459568D02*
X1440211Y464299D01*
G01X1440699Y463251D02*
X1427504Y458592D01*
G01X1424370Y456547D02*
X1426814Y459568D01*
G01X1427504Y458592D02*
X1425378Y455963D01*
G01X1421178Y448315D02*
X1424370Y456547D01*
G01X1425378Y455963D02*
X1422388Y448251D01*
G01X1423186Y440959D02*
X1421178Y448315D01*
G01X1422388Y448251D02*
X1424386Y440934D01*
G01X1422252Y438031D02*
X1423186Y440959D01*
G01X1424386Y440934D02*
X1423452Y438006D01*
G01X1423575Y433187D02*
X1422252Y438031D01*
G01X1423452Y438006D02*
X1424758Y433221D01*
G01X1421800Y424808D02*
X1423575Y433187D01*
G01X1424758Y433221D02*
X1422950Y424687D01*
G01X1425675Y462373D02*
X1439329Y467199D01*
G01X1439817Y466151D02*
X1426365Y461397D01*
G01X1422298Y458200D02*
X1425675Y462373D01*
G01X1426365Y461397D02*
X1423306Y457616D01*
G01X1418534Y448478D02*
X1422298Y458200D01*
G01X1423306Y457616D02*
X1419744Y448415D01*
G01X1420570Y441015D02*
X1418534Y448478D01*
G01X1419744Y448415D02*
X1421770Y440989D01*
G01X1419563Y437861D02*
X1420570Y441015D01*
G01X1421770Y440989D02*
X1420763Y437835D01*
G01X1420909Y432932D02*
X1419563Y437861D01*
G01X1420763Y437835D02*
X1422092Y432966D01*
G01X1419300Y425338D02*
X1420909Y432932D01*
G01X1422092Y432966D02*
X1420450Y425217D01*
G01X1419300Y407398D02*
Y425338D01*
G01X1420450Y425217D02*
Y407054D01*
G01X1417402Y404505D02*
X1419300Y407398D01*
G01X1420450Y407054D02*
X1418240Y403684D01*
G01X1439641Y468956D02*
X1420200Y462088D01*
G01X1439641Y468956D02*
X1420200Y462088D01*
G01X1439150Y470003D02*
X1419897Y463201D01*
G01X1420200Y462088D02*
X1410999Y460300D01*
G01X1419897Y463201D02*
X1411000Y461472D01*
G01X1410999Y460300D02*
X1404007Y461659D01*
G01X1411057Y463622D02*
X1423026Y465947D01*
G01X1431800Y422920D02*
X1433143Y429236D01*
G01X1432950Y422799D02*
X1434176Y428564D01*
G01X1433143Y429236D02*
X1439557Y433879D01*
G01X1434176Y428564D02*
X1440539Y433169D01*
G01X1439557Y433879D02*
X1441885Y441198D01*
G01X1440539Y433169D02*
X1443084Y441173D01*
G01X1441885Y441198D02*
X1440217Y447316D01*
G01X1443084Y441173D02*
X1441416Y447291D01*
G01X1440217Y447316D02*
X1440914Y449509D01*
G01X1441416Y447291D02*
X1441882Y448754D01*
G01X1440914Y449509D02*
X1444016Y451550D01*
G01X1441887Y448772D02*
X1444361Y450400D01*
G01X1444016Y451550D02*
X1446313D01*
G01X1444361Y450400D02*
X1446313D01*
G01X1432950Y422799D02*
X1434176Y428564D01*
G01X1431800Y422920D02*
X1433143Y429236D01*
G01X1434176Y428564D02*
X1440539Y433169D01*
G01X1433143Y429236D02*
X1439557Y433879D01*
G01X1440539Y433169D02*
X1443084Y441173D01*
G01X1439557Y433879D02*
X1441885Y441198D01*
G01X1443084Y441173D02*
X1441416Y447291D01*
G01X1441885Y441198D02*
X1440217Y447316D01*
G01X1441416Y447291D02*
X1441882Y448754D01*
G01X1440217Y447316D02*
X1440914Y449509D01*
G01X1441887Y448772D02*
X1444361Y450400D01*
G01X1440914Y449509D02*
X1444016Y451550D01*
G01X1444361Y450400D02*
X1446313D01*
G01X1444016Y451550D02*
X1446313D01*
G01X1446450Y403250D02*
Y406585D01*
G01X1452296Y412077D02*
X1447600Y406182D01*
G01X1446450Y406585D02*
X1451220Y412572D01*
G01X1455568Y429051D02*
X1452296Y412077D01*
G01X1451220Y412572D02*
X1454418Y429166D01*
G01X1455568Y431240D02*
Y429051D01*
G01X1454418Y429166D02*
Y431369D01*
G01X1455897Y432695D02*
X1455568Y431240D01*
G01X1454418Y431369D02*
X1454830Y433192D01*
G01X1456390Y433344D02*
X1455897Y432695D01*
G01X1454830Y433192D02*
X1455625Y434239D01*
G01X1460957Y435800D02*
X1456390Y433344D01*
G01X1455625Y434239D02*
X1460667Y436950D01*
G01X1464598Y435800D02*
X1460957D01*
G01X1460667Y436950D02*
X1472320D01*
G01X1460667D02*
X1472320D01*
G01X1460667D02*
X1472320D01*
G01X1460667D02*
X1472320D01*
G01X1464598Y435800D02*
X1460957D01*
G01X1455625Y434239D02*
X1460667Y436950D01*
G01X1460957Y435800D02*
X1456390Y433344D01*
G01X1454830Y433192D02*
X1455625Y434239D01*
G01X1456390Y433344D02*
X1455897Y432695D01*
G01X1454418Y431369D02*
X1454830Y433192D01*
G01X1455897Y432695D02*
X1455568Y431240D01*
G01X1454418Y429166D02*
Y431369D01*
G01X1455568Y431240D02*
Y429051D01*
G01X1451220Y412572D02*
X1454418Y429166D01*
G01X1455568Y429051D02*
X1452296Y412077D01*
G01X1446450Y406585D02*
X1451220Y412572D01*
G01X1452296Y412077D02*
X1447600Y406182D01*
G01X1446450Y403250D02*
Y406585D01*
G01X1460805Y422254D02*
X1459531Y420309D01*
G01X1458449Y420758D02*
X1459907Y422984D01*
G01X1463600Y425050D02*
X1460805Y422254D01*
G01X1459907Y422984D02*
X1463123Y426200D01*
G01X1473477Y425050D02*
X1463600D01*
G01X1463123Y426200D02*
X1473000D01*
G01X1463123D02*
X1473000D01*
G01X1473477Y425050D02*
X1463600D01*
G01X1459907Y422984D02*
X1463123Y426200D01*
G01X1463600Y425050D02*
X1460805Y422254D01*
G01X1458449Y420758D02*
X1459907Y422984D01*
G01X1460805Y422254D02*
X1459531Y420309D01*
G01X1437426Y410327D02*
X1438908D01*
G01X1438662Y411477D02*
X1436949D01*
G01X1436050Y408951D02*
X1437426Y410327D01*
G01X1436949Y411477D02*
X1434900Y409428D01*
G01X1436949Y411477D02*
X1434900Y409428D01*
G01X1436050Y408951D02*
X1437426Y410327D01*
G01X1438662Y411477D02*
X1436949D01*
G01X1437426Y410327D02*
X1438908D01*
G01X1461691Y418334D02*
X1463169Y421069D01*
G01X1460599Y418733D02*
X1462236Y421764D01*
G01X1463169Y421069D02*
X1464549Y422450D01*
G01X1462236Y421764D02*
X1464072Y423600D01*
G01X1464549Y422450D02*
X1472470D01*
G01X1464072Y423600D02*
X1472470D01*
G01X1460599Y418733D02*
X1462236Y421764D01*
G01X1461691Y418334D02*
X1463169Y421069D01*
G01X1462236Y421764D02*
X1464072Y423600D01*
G01X1463169Y421069D02*
X1464549Y422450D01*
G01X1464072Y423600D02*
X1472470D01*
G01X1464549Y422450D02*
X1472470D01*
G01X1466661Y429625D02*
X1463926D01*
G01X1467138Y430775D02*
X1463449D01*
G01X1463926Y429625D02*
X1459537Y425234D01*
G01X1463449Y430775D02*
X1458648Y425973D01*
G01X1459537Y425234D02*
X1456982Y421492D01*
G01X1458648Y425973D02*
X1455904Y421955D01*
G01X1456982Y421492D02*
X1454840Y411226D01*
G01X1455904Y421955D02*
X1453769Y411729D01*
G01X1454840Y411226D02*
X1453197Y409164D01*
G01X1451545Y407092D02*
X1450704Y406036D01*
G01X1453769Y411729D02*
X1449642Y406547D01*
G01X1450704Y406036D02*
X1450212Y403955D01*
G01X1449642Y406547D02*
X1449033Y403969D01*
G01X1467138Y430775D02*
X1463449D01*
G01X1466661Y429625D02*
X1463926D01*
G01X1463449Y430775D02*
X1458648Y425973D01*
G01X1463926Y429625D02*
X1459537Y425234D01*
G01X1458648Y425973D02*
X1455904Y421955D01*
G01X1459537Y425234D02*
X1456982Y421492D01*
G01X1455904Y421955D02*
X1453769Y411729D01*
G01X1456982Y421492D02*
X1454840Y411226D01*
G01X1453769Y411729D02*
X1449642Y406547D01*
G01X1454840Y411226D02*
X1453197Y409164D01*
G01X1453769Y411729D02*
X1449642Y406547D01*
G01X1451545Y407092D02*
X1450704Y406036D01*
G01X1449642Y406547D02*
X1449033Y403969D01*
G01X1450704Y406036D02*
X1450212Y403955D01*
G01X1464133Y413540D02*
X1466767Y416171D01*
G01X1463077Y414111D02*
X1466291Y417321D01*
G01X1463077Y414111D02*
X1466291Y417321D01*
G01X1464133Y413540D02*
X1466767Y416171D01*
G01X1412303Y492400D02*
X1409745D01*
G01X1412442Y491250D02*
X1409934D01*
G01X1412591Y479402D02*
X1403881D01*
G01X1412684Y480552D02*
X1403762D01*
G01X1436004Y479795D02*
X1430881D01*
G01X1435945Y480945D02*
X1430404D01*
G01X1430881Y479795D02*
X1422586Y471499D01*
G01X1430404Y480945D02*
X1422013Y472554D01*
G01X1422586Y471499D02*
X1408776Y468567D01*
G01X1422013Y472554D02*
X1408776Y469743D01*
G01X1435991Y491298D02*
X1432345D01*
G01X1436091Y492448D02*
X1431868D01*
G01X1432345Y491298D02*
X1429370Y488323D01*
G01X1431868Y492448D02*
X1428452Y489032D01*
G01X1429370Y488323D02*
X1421014Y474050D01*
G01X1428452Y489032D02*
X1420278Y475070D01*
G01X1421014Y474050D02*
X1410795Y471879D01*
G01X1420278Y475070D02*
X1410788Y473054D01*
G01X1412442Y491250D02*
X1409934D01*
G01X1412303Y492400D02*
X1409745D01*
G01X1412684Y480552D02*
X1403762D01*
G01X1412591Y479402D02*
X1403881D01*
G01X1435945Y480945D02*
X1430404D01*
G01X1436004Y479795D02*
X1430881D01*
G01X1430404Y480945D02*
X1422013Y472554D01*
G01X1430881Y479795D02*
X1422586Y471499D01*
G01X1422013Y472554D02*
X1408776Y469743D01*
G01X1422586Y471499D02*
X1408776Y468567D01*
G01X1436091Y492448D02*
X1431868D01*
G01X1435991Y491298D02*
X1432345D01*
G01X1431868Y492448D02*
X1428452Y489032D01*
G01X1432345Y491298D02*
X1429370Y488323D01*
G01X1428452Y489032D02*
X1420278Y475070D01*
G01X1429370Y488323D02*
X1421014Y474050D01*
G01X1420278Y475070D02*
X1410788Y473054D01*
G01X1421014Y474050D02*
X1410795Y471879D01*
G01X1454357Y471300D02*
X1451905Y469855D01*
G01X1449579Y468484D02*
X1448372Y467773D01*
G01X1446046Y466402D02*
X1444883Y465717D01*
G01X1460883Y471300D02*
X1454357D01*
G01X1454043Y472450D02*
X1460883D01*
G01X1455200Y475214D02*
X1439817Y466151D01*
G01X1439329Y467199D02*
X1454886Y476364D01*
G01X1468200Y475214D02*
X1455200D01*
G01X1454886Y476364D02*
X1468200D01*
G01X1475573Y479570D02*
X1455383D01*
G01X1475573Y478420D02*
X1455697D01*
G01X1455383Y479570D02*
X1439153Y470004D01*
G01X1439151Y470003D02*
X1439150D01*
G01X1455697Y478420D02*
X1439641Y468956D01*
G01X1439151Y470003D02*
X1439150D01*
G01X1411057Y464794D02*
X1422723Y467060D01*
G01X1423026Y465947D02*
X1439395Y471728D01*
G01X1422723Y467060D02*
X1438907Y472776D01*
G01X1439395Y471728D02*
X1455942Y481470D01*
G01X1438907Y472776D02*
X1455630Y482621D01*
G01X1455942Y481470D02*
X1460194D01*
G01X1455631Y482620D02*
X1460194D01*
G01X1454043Y472450D02*
X1460883D01*
G01Y471300D02*
X1454357D01*
G01D02*
X1451905Y469855D01*
G01X1449579Y468484D02*
X1448372Y467773D01*
G01X1446046Y466402D02*
X1444883Y465717D01*
G01X1454886Y476364D02*
X1468200D01*
G01Y475214D02*
X1455200D01*
G01X1439329Y467199D02*
X1454886Y476364D01*
G01X1455200Y475214D02*
X1439817Y466151D01*
G01X1475573Y478420D02*
X1455697D01*
G01X1475573Y479570D02*
X1455383D01*
G01X1455697Y478420D02*
X1439641Y468956D01*
G01X1455383Y479570D02*
X1439153Y470004D01*
G01X1455697Y478420D02*
X1439641Y468956D01*
G01X1439151Y470003D02*
X1439150D01*
G01X1411057Y464794D02*
X1422723Y467060D01*
G01D02*
X1438907Y472776D01*
G01X1423026Y465947D02*
X1439395Y471728D01*
G01X1438907Y472776D02*
X1455630Y482621D01*
G01X1439395Y471728D02*
X1455942Y481470D01*
G01X1455631Y482620D02*
X1460194D01*
G01X1455942Y481470D02*
X1460194D01*
G01X1490505Y18852D02*
X1493016Y15085D01*
G01X1489782Y17862D02*
X1491932Y14636D01*
G01X1493016Y15085D02*
X1493482Y12752D01*
G01X1491932Y14636D02*
X1492398Y12303D01*
G01X1493482Y12752D02*
X1494363Y11430D01*
G01X1492398Y12303D02*
X1492524Y12113D01*
G01X1493482Y12752D02*
X1494363Y11430D01*
G01X1492525Y12114D02*
X1493533Y10601D01*
G01X1494363Y11430D02*
X1499197Y8206D01*
G01X1493533Y10601D02*
X1498748Y7123D01*
G01X1499197Y8206D02*
X1501464Y7752D01*
G01X1498748Y7123D02*
X1501464Y6579D01*
G01Y7752D02*
X1518097Y11079D01*
G01X1501464Y6579D02*
X1518097Y9906D01*
G01Y11079D02*
X1525520Y9597D01*
G01X1518097Y9906D02*
X1525520Y8424D01*
G01Y9597D02*
X1527975Y10089D01*
G01X1525520Y8424D02*
X1527968Y8914D01*
G01X1489782Y17862D02*
X1491932Y14636D01*
G01X1490505Y18852D02*
X1493016Y15085D01*
G01X1491932Y14636D02*
X1492398Y12303D01*
G01X1493016Y15085D02*
X1493482Y12752D01*
G01X1492398Y12303D02*
X1492524Y12113D01*
G01X1492525Y12114D02*
X1493533Y10601D01*
G01X1493482Y12752D02*
X1494363Y11430D01*
G01X1493533Y10601D02*
X1498748Y7123D01*
G01X1494363Y11430D02*
X1499197Y8206D01*
G01X1498748Y7123D02*
X1501464Y6579D01*
G01X1499197Y8206D02*
X1501464Y7752D01*
G01Y6579D02*
X1518097Y9906D01*
G01X1501464Y7752D02*
X1518097Y11079D01*
G01Y9906D02*
X1525520Y8424D01*
G01X1518097Y11079D02*
X1525520Y9597D01*
G01Y8424D02*
X1527968Y8914D01*
G01X1525520Y9597D02*
X1527975Y10089D01*
G01X1493672Y19454D02*
X1495490Y16727D01*
G01X1494394Y20444D02*
X1496320Y17557D01*
G01X1495490Y16727D02*
X1501500Y12720D01*
G01X1496320Y17557D02*
X1501949Y13803D01*
G01X1501500Y12720D02*
X1506802Y11659D01*
G01X1501949Y13803D02*
X1506802Y12832D01*
G01Y11659D02*
X1517790Y13857D01*
G01X1506802Y12832D02*
X1517838Y15040D01*
G01X1517790Y13857D02*
X1526789Y11286D01*
G01X1517838Y15040D02*
X1526830Y12471D01*
G01X1526789Y11286D02*
X1545044Y15165D01*
G01X1526830Y12471D02*
X1545090Y16351D01*
G01X1466525Y29942D02*
X1495870Y21558D01*
G01X1467247Y30932D02*
X1496593Y22548D01*
G01X1495870Y21558D02*
X1497783Y18688D01*
G01X1496593Y22548D02*
X1498613Y19518D01*
G01X1497783Y18688D02*
X1502197Y15745D01*
G01X1498613Y19518D02*
X1502646Y16828D01*
G01X1502197Y15745D02*
X1506285Y14927D01*
G01X1502646Y16828D02*
X1506285Y16100D01*
G01Y14927D02*
X1516236Y16917D01*
G01X1506285Y16100D02*
X1516284Y18100D01*
G01X1516236Y16917D02*
X1526828Y13890D01*
G01X1516284Y18100D02*
X1526869Y15075D01*
G01X1526828Y13890D02*
X1545134Y17775D01*
G01X1526869Y15075D02*
X1545179Y18961D01*
G01X1494394Y20444D02*
X1496320Y17557D01*
G01X1493672Y19454D02*
X1495490Y16727D01*
G01X1496320Y17557D02*
X1501949Y13803D01*
G01X1495490Y16727D02*
X1501500Y12720D01*
G01X1501949Y13803D02*
X1506802Y12832D01*
G01X1501500Y12720D02*
X1506802Y11659D01*
G01Y12832D02*
X1517838Y15040D01*
G01X1506802Y11659D02*
X1517790Y13857D01*
G01X1517838Y15040D02*
X1526830Y12471D01*
G01X1517790Y13857D02*
X1526789Y11286D01*
G01X1526830Y12471D02*
X1545090Y16351D01*
G01X1526789Y11286D02*
X1545044Y15165D01*
G01X1467247Y30932D02*
X1496593Y22548D01*
G01X1466525Y29942D02*
X1495870Y21558D01*
G01X1496593Y22548D02*
X1498613Y19518D01*
G01X1495870Y21558D02*
X1497783Y18688D01*
G01X1498613Y19518D02*
X1502646Y16828D01*
G01X1497783Y18688D02*
X1502197Y15745D01*
G01X1502646Y16828D02*
X1506285Y16100D01*
G01X1502197Y15745D02*
X1506285Y14927D01*
G01Y16100D02*
X1516284Y18100D01*
G01X1506285Y14927D02*
X1516236Y16917D01*
G01X1516284Y18100D02*
X1526869Y15075D01*
G01X1516236Y16917D02*
X1526828Y13890D01*
G01X1526869Y15075D02*
X1545179Y18961D01*
G01X1526828Y13890D02*
X1545134Y17775D01*
G01X1468718Y32067D02*
X1485740Y27202D01*
G01X1469423Y33063D02*
X1486022Y28318D01*
G01X1485740Y27202D02*
X1505915Y22773D01*
G01X1486022Y28318D02*
X1506301Y23867D01*
G01X1505915Y22773D02*
X1513133Y19208D01*
G01X1506301Y23867D02*
X1513291Y20414D01*
G01X1513133Y19208D02*
X1515616Y19705D01*
G01X1513291Y20414D02*
X1515664Y20888D01*
G01X1515616Y19705D02*
X1526498Y16596D01*
G01X1515664Y20888D02*
X1526539Y17781D01*
G01X1526498Y16596D02*
X1544987Y20519D01*
G01X1526539Y17781D02*
X1544988Y21695D01*
G01X1469423Y33063D02*
X1486022Y28318D01*
G01X1468718Y32067D02*
X1485740Y27202D01*
G01X1486022Y28318D02*
X1506301Y23867D01*
G01X1485740Y27202D02*
X1505915Y22773D01*
G01X1506301Y23867D02*
X1513291Y20414D01*
G01X1505915Y22773D02*
X1513133Y19208D01*
G01X1513291Y20414D02*
X1515664Y20888D01*
G01X1513133Y19208D02*
X1515616Y19705D01*
G01X1515664Y20888D02*
X1526539Y17781D01*
G01X1515616Y19705D02*
X1526498Y16596D01*
G01X1526539Y17781D02*
X1544988Y21695D01*
G01X1526498Y16596D02*
X1544987Y20519D01*
G01X1492142Y37611D02*
X1543749Y26642D01*
G01X1492144Y38787D02*
X1543749Y27818D01*
G01X1492144Y38787D02*
X1543749Y27818D01*
G01X1492142Y37611D02*
X1543749Y26642D01*
G01X1491587Y48819D02*
X1530837Y40478D01*
G01Y41654D02*
X1491587Y49995D01*
G01X1483907Y47188D02*
X1491587Y48819D01*
G01Y49995D02*
X1483985Y48381D01*
G01X1491587Y49995D02*
X1483985Y48381D01*
G01X1483907Y47188D02*
X1491587Y48819D01*
G01X1530837Y41654D02*
X1491587Y49995D01*
G01Y48819D02*
X1530837Y40478D01*
G01X1491653Y51448D02*
X1531019Y43083D01*
G01Y44259D02*
X1491653Y52624D01*
G01X1483991Y49822D02*
X1491653Y51448D01*
G01Y52624D02*
X1484069Y51015D01*
G01X1491653Y52624D02*
X1484069Y51015D01*
G01X1483991Y49822D02*
X1491653Y51448D01*
G01X1531019Y44259D02*
X1491653Y52624D01*
G01Y51448D02*
X1531019Y43083D01*
G01X1483341Y35744D02*
X1492142Y37611D01*
G01X1483419Y36937D02*
X1492144Y38787D01*
G01X1483501Y38351D02*
X1492282Y40214D01*
G01X1483579Y39544D02*
X1492282Y41390D01*
G01Y40214D02*
X1543852Y29259D01*
G01X1492282Y41390D02*
X1543852Y30435D01*
G01X1483484Y41018D02*
X1492135Y42853D01*
G01X1483562Y42211D02*
X1492135Y44029D01*
G01Y42853D02*
X1543930Y31845D01*
G01X1492135Y44029D02*
X1543930Y33021D01*
G01X1544039Y34436D02*
X1492073Y45482D01*
G01X1544039Y35612D02*
X1492073Y46658D01*
G01Y45482D02*
X1483521Y43668D01*
G01X1492073Y46658D02*
X1483599Y44861D01*
G01X1483419Y36937D02*
X1492144Y38787D01*
G01X1483341Y35744D02*
X1492142Y37611D01*
G01X1483579Y39544D02*
X1492282Y41390D01*
G01X1483501Y38351D02*
X1492282Y40214D01*
G01Y41390D02*
X1543852Y30435D01*
G01X1492282Y40214D02*
X1543852Y29259D01*
G01X1483562Y42211D02*
X1492135Y44029D01*
G01X1483484Y41018D02*
X1492135Y42853D01*
G01Y44029D02*
X1543930Y33021D01*
G01X1492135Y42853D02*
X1543930Y31845D01*
G01X1544039Y35612D02*
X1492073Y46658D01*
G01X1544039Y34436D02*
X1492073Y45482D01*
G01Y46658D02*
X1483599Y44861D01*
G01X1492073Y45482D02*
X1483521Y43668D01*
G01X1491623Y54012D02*
X1530997Y45644D01*
G01Y46820D02*
X1491623Y55188D01*
G01X1484150Y52426D02*
X1491623Y54012D01*
G01Y55188D02*
X1484228Y53619D01*
G01X1491552Y56626D02*
X1531078Y48227D01*
G01Y49403D02*
X1491552Y57802D01*
G01X1484206Y55066D02*
X1491552Y56626D01*
G01Y57802D02*
X1484284Y56259D01*
G01X1472428Y61884D02*
X1484243Y57717D01*
G01X1472965Y62915D02*
X1484321Y58910D01*
G01X1484243Y57717D02*
X1491364Y59227D01*
G01X1484321Y58910D02*
X1491364Y60403D01*
G01Y59227D02*
X1531079Y50793D01*
G01X1491364Y60403D02*
X1531079Y51969D01*
G01X1491091Y61869D02*
X1531103Y53364D01*
G01Y54540D02*
X1491091Y63045D01*
G01X1484182Y60402D02*
X1491091Y61869D01*
G01Y63045D02*
X1484259Y61595D01*
G01X1473804Y64059D02*
X1484182Y60402D01*
G01X1484259Y61595D02*
X1474341Y65090D01*
G01X1491623Y55188D02*
X1484228Y53619D01*
G01X1484150Y52426D02*
X1491623Y54012D01*
G01X1530997Y46820D02*
X1491623Y55188D01*
G01Y54012D02*
X1530997Y45644D01*
G01X1491552Y57802D02*
X1484284Y56259D01*
G01X1484206Y55066D02*
X1491552Y56626D01*
G01X1531078Y49403D02*
X1491552Y57802D01*
G01Y56626D02*
X1531078Y48227D01*
G01X1472965Y62915D02*
X1484321Y58910D01*
G01X1472428Y61884D02*
X1484243Y57717D01*
G01X1484321Y58910D02*
X1491364Y60403D01*
G01X1484243Y57717D02*
X1491364Y59227D01*
G01Y60403D02*
X1531079Y51969D01*
G01X1491364Y59227D02*
X1531079Y50793D01*
G01X1484259Y61595D02*
X1474341Y65090D01*
G01X1473804Y64059D02*
X1484182Y60402D01*
G01X1491091Y63045D02*
X1484259Y61595D01*
G01X1484182Y60402D02*
X1491091Y61869D01*
G01X1531103Y54540D02*
X1491091Y63045D01*
G01Y61869D02*
X1531103Y53364D01*
G01X1475749Y67256D02*
X1466405Y73945D01*
G01X1484241Y64263D02*
X1475749Y67256D01*
G01X1475212Y66225D02*
X1484163Y63070D01*
G01X1490865Y65667D02*
X1484241Y64263D01*
G01X1484163Y63070D02*
X1490865Y64491D01*
G01X1531143Y57114D02*
X1490865Y65667D01*
G01Y64491D02*
X1531143Y55938D01*
G01X1490865Y64491D02*
X1531143Y55938D01*
G01Y57114D02*
X1490865Y65667D01*
G01X1484163Y63070D02*
X1490865Y64491D01*
G01Y65667D02*
X1484241Y64263D01*
G01X1475212Y66225D02*
X1484163Y63070D01*
G01X1484241Y64263D02*
X1475749Y67256D01*
G01D02*
X1466405Y73945D01*
G01X1477312Y69365D02*
X1468683Y75546D01*
G01X1467650Y74870D02*
X1476775Y68334D01*
G01X1484307Y66897D02*
X1477312Y69365D01*
G01X1476783Y68332D02*
X1484229Y65704D01*
G01X1490722Y68259D02*
X1484307Y66897D01*
G01X1484229Y65704D02*
X1490722Y67083D01*
G01X1531118Y59676D02*
X1490722Y68259D01*
G01Y67083D02*
X1531118Y58500D01*
G01X1490722Y67083D02*
X1531118Y58500D01*
G01Y59676D02*
X1490722Y68259D01*
G01X1484229Y65704D02*
X1490722Y67083D01*
G01Y68259D02*
X1484307Y66897D01*
G01X1476783Y68332D02*
X1484229Y65704D01*
G01X1484307Y66897D02*
X1477312Y69365D01*
G01X1467650Y74870D02*
X1476775Y68334D01*
G01X1477312Y69365D02*
X1468683Y75546D01*
G01X1497732Y75898D02*
X1530132Y68840D01*
G01X1530130Y67663D02*
X1497262Y74823D01*
G01X1478117Y89607D02*
X1497732Y75898D01*
G01X1497262Y74823D02*
X1477306Y88770D01*
G01X1497262Y74823D02*
X1477306Y88770D01*
G01X1478117Y89607D02*
X1497732Y75898D01*
G01X1530130Y67663D02*
X1497262Y74823D01*
G01X1497732Y75898D02*
X1530132Y68840D01*
G01X1496176Y73639D02*
X1530057Y66262D01*
G01X1530054Y65085D02*
X1495706Y72564D01*
G01X1476666Y87286D02*
X1496176Y73639D01*
G01X1495706Y72564D02*
X1475854Y86451D01*
G01X1495706Y72564D02*
X1475854Y86451D01*
G01X1476666Y87286D02*
X1496176Y73639D01*
G01X1530054Y65085D02*
X1495706Y72564D01*
G01X1496176Y73639D02*
X1530057Y66262D01*
G01X1501951Y80309D02*
X1530191Y74176D01*
G01X1530207Y72995D02*
X1501483Y79233D01*
G01X1497880Y83137D02*
X1501951Y80309D01*
G01X1501483Y79233D02*
X1496988Y82355D01*
G01X1495048Y88624D02*
X1497880Y83137D01*
G01X1496988Y82355D02*
X1494073Y88005D01*
G01X1494210Y89718D02*
X1495048Y88624D01*
G01X1494073Y88005D02*
X1493414Y88864D01*
G01X1491708Y91370D02*
X1494210Y89718D01*
G01X1493414Y88864D02*
X1491214Y90318D01*
G01X1480667Y94715D02*
X1491708Y91370D01*
G01X1491214Y90318D02*
X1479972Y93723D01*
G01X1491214Y90318D02*
X1479972Y93723D01*
G01X1480667Y94715D02*
X1491708Y91370D01*
G01X1493414Y88864D02*
X1491214Y90318D01*
G01X1491708Y91370D02*
X1494210Y89718D01*
G01X1494073Y88005D02*
X1493414Y88864D01*
G01X1494210Y89718D02*
X1495048Y88624D01*
G01X1496988Y82355D02*
X1494073Y88005D01*
G01X1495048Y88624D02*
X1497880Y83137D01*
G01X1501483Y79233D02*
X1496988Y82355D01*
G01X1497880Y83137D02*
X1501951Y80309D01*
G01X1530207Y72995D02*
X1501483Y79233D01*
G01X1501951Y80309D02*
X1530191Y74176D01*
G01X1470346Y82638D02*
X1468195Y92756D01*
G01X1467123Y92268D02*
X1469314Y81961D01*
G01X1484014Y72856D02*
X1482876Y73671D01*
G01X1481587Y75392D02*
X1480680Y75242D01*
G01D02*
X1479541Y76057D01*
G01X1478253Y77779D02*
X1477346Y77628D01*
G01D02*
X1476207Y78443D01*
G01X1474919Y80165D02*
X1474012Y80015D01*
G01D02*
X1470346Y82638D01*
G01X1469314Y81961D02*
X1483539Y71781D01*
G01X1530925Y62890D02*
X1484014Y72856D01*
G01X1483539Y71781D02*
X1530925Y61714D01*
G01X1483539Y71781D02*
X1530925Y61714D01*
G01Y62890D02*
X1484014Y72856D01*
G01X1469314Y81961D02*
X1483539Y71781D01*
G01X1484014Y72856D02*
X1482876Y73671D01*
G01X1469314Y81961D02*
X1483539Y71781D01*
G01X1481587Y75392D02*
X1480680Y75242D01*
G01X1469314Y81961D02*
X1483539Y71781D01*
G01X1480680Y75242D02*
X1479541Y76057D01*
G01X1469314Y81961D02*
X1483539Y71781D01*
G01X1478253Y77779D02*
X1477346Y77628D01*
G01X1469314Y81961D02*
X1483539Y71781D01*
G01X1477346Y77628D02*
X1476207Y78443D01*
G01X1469314Y81961D02*
X1483539Y71781D01*
G01X1474919Y80165D02*
X1474012Y80015D01*
G01X1469314Y81961D02*
X1483539Y71781D01*
G01X1474012Y80015D02*
X1470346Y82638D01*
G01X1467123Y92268D02*
X1469314Y81961D01*
G01X1470346Y82638D02*
X1468195Y92756D01*
G01X1530201Y86782D02*
X1510983Y82192D01*
G01X1530123Y85581D02*
X1510889Y80987D01*
G01X1510983Y82192D02*
X1509201Y82924D01*
G01X1510889Y80987D02*
X1508465Y81983D01*
G01X1509201Y82924D02*
X1500605Y94627D01*
G01X1508465Y81983D02*
X1499880Y93671D01*
G01D02*
X1493102Y96229D01*
G01X1530123Y85581D02*
X1510889Y80987D01*
G01X1530201Y86782D02*
X1510983Y82192D01*
G01X1510889Y80987D02*
X1508465Y81983D01*
G01X1510983Y82192D02*
X1509201Y82924D01*
G01X1508465Y81983D02*
X1499880Y93671D01*
G01X1509201Y82924D02*
X1500605Y94627D01*
G01X1499880Y93671D02*
X1493102Y96229D01*
G01X1479144Y92490D02*
X1490378Y88958D01*
G01X1478445Y91504D02*
X1489836Y87922D01*
G01X1490378Y88958D02*
X1492231Y87522D01*
G01X1489836Y87922D02*
X1491393Y86715D01*
G01X1492231Y87522D02*
X1494185Y84792D01*
G01X1491393Y86715D02*
X1493194Y84200D01*
G01X1494185Y84792D02*
X1496046Y80993D01*
G01X1493194Y84200D02*
X1495151Y80203D01*
G01X1496046Y80993D02*
X1500897Y77805D01*
G01X1495151Y80203D02*
X1500444Y76726D01*
G01X1500897Y77805D02*
X1530148Y71434D01*
G01X1500444Y76726D02*
X1530164Y70253D01*
G01X1478445Y91504D02*
X1489836Y87922D01*
G01X1479144Y92490D02*
X1490378Y88958D01*
G01X1489836Y87922D02*
X1491393Y86715D01*
G01X1490378Y88958D02*
X1492231Y87522D01*
G01X1491393Y86715D02*
X1493194Y84200D01*
G01X1492231Y87522D02*
X1494185Y84792D01*
G01X1493194Y84200D02*
X1495151Y80203D01*
G01X1494185Y84792D02*
X1496046Y80993D01*
G01X1495151Y80203D02*
X1500444Y76726D01*
G01X1496046Y80993D02*
X1500897Y77805D01*
G01X1500444Y76726D02*
X1530164Y70253D01*
G01X1500897Y77805D02*
X1530148Y71434D01*
G01X1534236Y94642D02*
X1527097Y90855D01*
G01D02*
X1521522Y92361D01*
G01X1527235Y89626D02*
X1520796Y91365D01*
G01X1521522Y92361D02*
X1517351Y98797D01*
G01X1520796Y91365D02*
X1516539Y97933D01*
G01X1534236Y94642D02*
X1527097Y90855D01*
G01X1527235Y89626D02*
X1520796Y91365D01*
G01X1527097Y90855D02*
X1521522Y92361D01*
G01X1520796Y91365D02*
X1516539Y97933D01*
G01X1521522Y92361D02*
X1517351Y98797D01*
G01X1500605Y94627D02*
X1493176Y97431D01*
G01D02*
X1490634Y96816D01*
G01X1493102Y96229D02*
X1490605Y95625D01*
G01X1490634Y96816D02*
X1479917Y99974D01*
G01X1490605Y95625D02*
X1479224Y98978D01*
G01X1479917Y99974D02*
X1467595Y116458D01*
G01X1479224Y98978D02*
X1466522Y115971D01*
G01X1500605Y94627D02*
X1493176Y97431D01*
G01X1493102Y96229D02*
X1490605Y95625D01*
G01X1493176Y97431D02*
X1490634Y96816D01*
G01X1490605Y95625D02*
X1479224Y98978D01*
G01X1490634Y96816D02*
X1479917Y99974D01*
G01X1479224Y98978D02*
X1466522Y115971D01*
G01X1479917Y99974D02*
X1467595Y116458D01*
G01X1517351Y98797D02*
X1512964Y101267D01*
G01X1516539Y97933D02*
X1512549Y100180D01*
G01X1512964Y101267D02*
X1508399Y102273D01*
G01X1512549Y100180D02*
X1507934Y101197D01*
G01X1508399Y102273D02*
X1502900Y106026D01*
G01X1507934Y101197D02*
X1502432Y104952D01*
G01X1502900Y106026D02*
X1499885Y106707D01*
G01X1502432Y104952D02*
X1499875Y105530D01*
G01X1499885Y106707D02*
X1495660Y105829D01*
G01X1499875Y105530D02*
X1496141Y104754D01*
G01X1495660Y105829D02*
X1489956Y101613D01*
G01X1496141Y104754D02*
X1490445Y100543D01*
G01X1489956Y101613D02*
X1488696Y101330D01*
G01X1490445Y100543D02*
X1488639Y100138D01*
G01X1488696Y101330D02*
X1481958Y103539D01*
G01X1488639Y100138D02*
X1481233Y102566D01*
G01X1481958Y103539D02*
X1479510Y107069D01*
G01X1481233Y102566D02*
X1478462Y106562D01*
G01X1479510Y107069D02*
X1478751Y109566D01*
G01X1477979Y112101D02*
X1476718Y116248D01*
G01X1478462Y106562D02*
X1475531Y116197D01*
G01X1476718Y116248D02*
X1478398Y124148D01*
G01X1475531Y116197D02*
X1477222Y124149D01*
G01X1478398Y124148D02*
X1475734Y136892D01*
G01X1477222Y124149D02*
X1474661Y136399D01*
G01X1475734Y136892D02*
X1468453Y146376D01*
G01X1474661Y136399D02*
X1467403Y145855D01*
G01X1513230Y136785D02*
X1509103D01*
G01X1506453D02*
X1504852D01*
G01X1512970Y135635D02*
X1504375D01*
G01X1506453Y136785D02*
X1504852D01*
G01D02*
X1503463Y138174D01*
G01X1502508Y140049D02*
X1501589D01*
G01D02*
X1500634Y141004D01*
G01X1499680Y142877D02*
X1498760D01*
G01D02*
X1497805Y143832D01*
G01X1496851Y145705D02*
X1495932D01*
G01D02*
X1492363Y149274D01*
G01X1504375Y135635D02*
X1491344Y148665D01*
G01X1492363Y149274D02*
X1491033Y153695D01*
G01X1491344Y148665D02*
X1489973Y153224D01*
G01X1491033Y153695D02*
X1490388Y154761D01*
G01X1489973Y153224D02*
X1489537Y153946D01*
G01X1490388Y154761D02*
X1487838Y156462D01*
G01X1489537Y153946D02*
X1487105Y155568D01*
G01D02*
X1485020Y157652D01*
G01X1516539Y97933D02*
X1512549Y100180D01*
G01X1517351Y98797D02*
X1512964Y101267D01*
G01X1512549Y100180D02*
X1507934Y101197D01*
G01X1512964Y101267D02*
X1508399Y102273D01*
G01X1507934Y101197D02*
X1502432Y104952D01*
G01X1508399Y102273D02*
X1502900Y106026D01*
G01X1502432Y104952D02*
X1499875Y105530D01*
G01X1502900Y106026D02*
X1499885Y106707D01*
G01X1499875Y105530D02*
X1496141Y104754D01*
G01X1499885Y106707D02*
X1495660Y105829D01*
G01X1496141Y104754D02*
X1490445Y100543D01*
G01X1495660Y105829D02*
X1489956Y101613D01*
G01X1490445Y100543D02*
X1488639Y100138D01*
G01X1489956Y101613D02*
X1488696Y101330D01*
G01X1488639Y100138D02*
X1481233Y102566D01*
G01X1488696Y101330D02*
X1481958Y103539D01*
G01X1481233Y102566D02*
X1478462Y106562D01*
G01X1481958Y103539D02*
X1479510Y107069D01*
G01X1478462Y106562D02*
X1475531Y116197D01*
G01X1479510Y107069D02*
X1478751Y109566D01*
G01X1478462Y106562D02*
X1475531Y116197D01*
G01X1477979Y112101D02*
X1476718Y116248D01*
G01X1475531Y116197D02*
X1477222Y124149D01*
G01X1476718Y116248D02*
X1478398Y124148D01*
G01X1477222Y124149D02*
X1474661Y136399D01*
G01X1478398Y124148D02*
X1475734Y136892D01*
G01X1474661Y136399D02*
X1467403Y145855D01*
G01X1475734Y136892D02*
X1468453Y146376D01*
G01X1512970Y135635D02*
X1504375D01*
G01X1513230Y136785D02*
X1509103D01*
G01X1512970Y135635D02*
X1504375D01*
G01D02*
X1491344Y148665D01*
G01X1506453Y136785D02*
X1504852D01*
G01X1504375Y135635D02*
X1491344Y148665D01*
G01X1504852Y136785D02*
X1503463Y138174D01*
G01X1504375Y135635D02*
X1491344Y148665D01*
G01X1502508Y140049D02*
X1501589D01*
G01X1504375Y135635D02*
X1491344Y148665D01*
G01X1501589Y140049D02*
X1500634Y141004D01*
G01X1504375Y135635D02*
X1491344Y148665D01*
G01X1499680Y142877D02*
X1498760D01*
G01X1504375Y135635D02*
X1491344Y148665D01*
G01X1498760Y142877D02*
X1497805Y143832D01*
G01X1504375Y135635D02*
X1491344Y148665D01*
G01X1496851Y145705D02*
X1495932D01*
G01X1504375Y135635D02*
X1491344Y148665D01*
G01X1495932Y145705D02*
X1492363Y149274D01*
G01X1491344Y148665D02*
X1489973Y153224D01*
G01X1492363Y149274D02*
X1491033Y153695D01*
G01X1489973Y153224D02*
X1489537Y153946D01*
G01X1491033Y153695D02*
X1490388Y154761D01*
G01X1489537Y153946D02*
X1487105Y155568D01*
G01X1490388Y154761D02*
X1487838Y156462D01*
G01X1487105Y155568D02*
X1485020Y157652D01*
G01X1487838Y156462D02*
X1485754Y158546D01*
G01D02*
X1485233Y158894D01*
G01X1483930Y160544D02*
X1483029Y160364D01*
G01D02*
X1477352Y164150D01*
G01X1485020Y157652D02*
X1476714Y163193D01*
G01X1477352Y164150D02*
G02X1477082Y165502I541J811D01*
G01X1476714Y163193D02*
G02X1476125Y166140I1179J1768D01*
G01X1477082Y165502D02*
X1478618Y167805D01*
G01X1476125Y166140D02*
X1477661Y168443D01*
G01X1478618Y167805D02*
G03X1478029Y170752I-1768J1179D01*
G01X1478026Y170754D02*
G03X1475079Y170165I-1179J-1768D01*
G01X1477661Y168443D02*
G03X1477391Y169795I-811J541D01*
G01X1478618Y167805D02*
G03X1478029Y170752I-1768J1179D01*
G01X1478026Y170754D02*
G03X1475079Y170165I-1179J-1768D01*
G01X1477388Y169797D02*
G03X1476036Y169526I-541J-811D01*
G01X1475079Y170165D02*
X1473543Y167862D01*
G01X1476036Y169526D02*
X1474500Y167224D01*
G01X1473543Y167862D02*
G02X1472191Y167592I-811J541D01*
G01X1474500Y167224D02*
G02X1471553Y166635I-1768J1179D01*
G01X1472191Y167592D02*
X1469977Y169068D01*
G01X1471553Y166635D02*
X1469147Y168239D01*
G01X1469977Y169068D02*
X1468986Y170560D01*
G01X1469147Y168239D02*
X1467902Y170112D01*
G01X1468986Y170560D02*
X1467970Y175641D01*
G01X1467450Y178240D02*
X1467185Y179564D01*
G01X1466666Y182162D02*
X1466401Y183486D01*
G01D02*
X1466979Y186248D01*
G01D02*
X1470344Y193411D01*
G01X1465880Y186616D02*
X1469139Y193551D01*
G01X1470344Y193411D02*
X1469256Y198591D01*
G01X1469139Y193551D02*
X1468130Y198354D01*
G01X1469256Y198591D02*
G02X1469236Y198842I954J202D01*
G01X1468130Y198354D02*
G02X1468087Y198901I2081J439D01*
G01X1469256Y198591D02*
G02X1469236Y198842I954J202D01*
G01D02*
G02X1471166Y198993I975J-50D01*
G01X1468087Y198901D02*
G02X1472292Y199230I2124J-109D01*
G01X1471166Y198993D02*
X1473057Y190000D01*
G01X1472292Y199230D02*
X1474183Y190237D01*
G01X1473057Y190000D02*
G03X1475573Y188358I2079J438D01*
G01X1475577Y188359D02*
G03X1477219Y190876I-438J2080D01*
G01X1474183Y190237D02*
G03X1475321Y189481I954J201D01*
G01X1473057Y190000D02*
G03X1475573Y188358I2079J438D01*
G01X1475577Y188359D02*
G03X1477219Y190876I-438J2080D01*
G01X1475340Y189485D02*
G03X1476093Y190640I-201J954D01*
G01X1477219Y190876D02*
X1474688Y202906D01*
G01X1476093Y190640D02*
X1473562Y202669D01*
G01X1474688Y202906D02*
G03X1473843Y204563I-3483J-732D01*
G01D02*
G03X1472496Y205491I-2639J-2389D01*
G01X1473562Y202669D02*
G03X1472990Y203791I-2357J-495D01*
G01X1474688Y202906D02*
G03X1473843Y204563I-3483J-732D01*
G01D02*
G03X1472496Y205491I-2639J-2389D01*
G01X1472969Y203814D02*
G03X1472079Y204419I-1765J-1639D01*
G01X1472496Y205491D02*
X1469900Y207600D01*
G01X1471910Y204484D02*
X1468873Y206951D01*
G01X1469900Y207600D02*
X1468733Y212397D01*
G01X1468873Y206951D02*
X1467555Y212373D01*
G01X1468733Y212397D02*
X1469894Y218199D01*
G01X1467555Y212373D02*
X1468721Y218199D01*
G01X1487838Y156462D02*
X1485754Y158546D01*
G01X1485020Y157652D02*
X1476714Y163193D01*
G01X1485754Y158546D02*
X1485233Y158894D01*
G01X1485020Y157652D02*
X1476714Y163193D01*
G01X1483930Y160544D02*
X1483029Y160364D01*
G01X1485020Y157652D02*
X1476714Y163193D01*
G01X1483029Y160364D02*
X1477352Y164150D01*
G01X1476714Y163193D02*
G02X1476125Y166140I1179J1768D01*
G01X1477352Y164150D02*
G02X1477082Y165502I541J811D01*
G01X1476125Y166140D02*
X1477661Y168443D01*
G01X1477082Y165502D02*
X1478618Y167805D01*
G01X1477661Y168443D02*
G03X1477391Y169795I-811J541D01*
G01X1477388Y169797D02*
G03X1476036Y169526I-541J-811D01*
G01X1478618Y167805D02*
G03X1478029Y170752I-1768J1179D01*
G01X1477661Y168443D02*
G03X1477391Y169795I-811J541D01*
G01X1477388Y169797D02*
G03X1476036Y169526I-541J-811D01*
G01X1478026Y170754D02*
G03X1475079Y170165I-1179J-1768D01*
G01X1476036Y169526D02*
X1474500Y167224D01*
G01X1475079Y170165D02*
X1473543Y167862D01*
G01X1474500Y167224D02*
G02X1471553Y166635I-1768J1179D01*
G01X1473543Y167862D02*
G02X1472191Y167592I-811J541D01*
G01X1471553Y166635D02*
X1469147Y168239D01*
G01X1472191Y167592D02*
X1469977Y169068D01*
G01X1469147Y168239D02*
X1467902Y170112D01*
G01X1469977Y169068D02*
X1468986Y170560D01*
G01D02*
X1467970Y175641D01*
G01X1467450Y178240D02*
X1467185Y179564D01*
G01X1466666Y182162D02*
X1466401Y183486D01*
G01D02*
X1466979Y186248D01*
G01X1465880Y186616D02*
X1469139Y193551D01*
G01X1466979Y186248D02*
X1470344Y193411D01*
G01X1469139Y193551D02*
X1468130Y198354D01*
G01X1470344Y193411D02*
X1469256Y198591D01*
G01X1468130Y198354D02*
G02X1468087Y198901I2081J439D01*
G01D02*
G02X1472292Y199230I2124J-109D01*
G01X1469256Y198591D02*
G02X1469236Y198842I954J202D01*
G01X1468087Y198901D02*
G02X1472292Y199230I2124J-109D01*
G01X1469236Y198842D02*
G02X1471166Y198993I975J-50D01*
G01X1472292Y199230D02*
X1474183Y190237D01*
G01X1471166Y198993D02*
X1473057Y190000D01*
G01X1474183Y190237D02*
G03X1475321Y189481I954J201D01*
G01X1475340Y189485D02*
G03X1476093Y190640I-201J954D01*
G01X1473057Y190000D02*
G03X1475573Y188358I2079J438D01*
G01X1474183Y190237D02*
G03X1475321Y189481I954J201D01*
G01X1475340Y189485D02*
G03X1476093Y190640I-201J954D01*
G01X1475577Y188359D02*
G03X1477219Y190876I-438J2080D01*
G01X1476093Y190640D02*
X1473562Y202669D01*
G01X1477219Y190876D02*
X1474688Y202906D01*
G01X1473562Y202669D02*
G03X1472990Y203791I-2357J-495D01*
G01X1472969Y203814D02*
G03X1472079Y204419I-1765J-1639D01*
G01X1474688Y202906D02*
G03X1473843Y204563I-3483J-732D01*
G01X1473562Y202669D02*
G03X1472990Y203791I-2357J-495D01*
G01X1472969Y203814D02*
G03X1472079Y204419I-1765J-1639D01*
G01X1473843Y204563D02*
G03X1472496Y205491I-2639J-2389D01*
G01X1471910Y204484D02*
X1468873Y206951D01*
G01X1472496Y205491D02*
X1469900Y207600D01*
G01X1468873Y206951D02*
X1467555Y212373D01*
G01X1469900Y207600D02*
X1468733Y212397D01*
G01X1467555Y212373D02*
X1468721Y218199D01*
G01X1468733Y212397D02*
X1469894Y218199D01*
G01X1469711Y219114D02*
X1467236Y222853D01*
G01X1468627Y218667D02*
X1466277Y222218D01*
G01X1467236Y222853D02*
G02X1467511Y224204I813J538D01*
G01X1466277Y222218D02*
G02X1466876Y225163I1772J1173D01*
G01X1467511Y224204D02*
X1468566Y224901D01*
G01X1466876Y225163D02*
X1467931Y225861D01*
G01X1468566Y224901D02*
G03X1469165Y227849I-1173J1773D01*
G01X1469085Y227962D02*
G03X1466219Y228448I-1692J-1286D01*
G01X1467931Y225861D02*
G03X1468206Y227213I-538J813D01*
G01X1468566Y224901D02*
G03X1469165Y227849I-1173J1773D01*
G01X1469085Y227962D02*
G03X1466219Y228448I-1692J-1286D01*
G01X1468205Y227214D02*
G03X1468168Y227266I-812J-539D01*
G01X1468566Y224901D02*
G03X1469165Y227849I-1173J1773D01*
G01D02*
G03X1469086Y227961I-1776J-1169D01*
G01X1469085Y227962D02*
G03X1466219Y228448I-1692J-1286D01*
G01X1468168Y227266D02*
G03X1466854Y227489I-776J-590D01*
G01D02*
X1465799Y226790D01*
G01X1468627Y218667D02*
X1466277Y222218D01*
G01X1469711Y219114D02*
X1467236Y222853D01*
G01X1466277Y222218D02*
G02X1466876Y225163I1772J1173D01*
G01X1467236Y222853D02*
G02X1467511Y224204I813J538D01*
G01X1466876Y225163D02*
X1467931Y225861D01*
G01X1467511Y224204D02*
X1468566Y224901D01*
G01X1467931Y225861D02*
G03X1468206Y227213I-538J813D01*
G01X1468205Y227214D02*
G03X1468168Y227266I-812J-539D01*
G01D02*
G03X1466854Y227489I-776J-590D01*
G01X1468566Y224901D02*
G03X1469165Y227849I-1173J1773D01*
G01X1468168Y227266D02*
G03X1466854Y227489I-776J-590D01*
G01X1469165Y227849D02*
G03X1469086Y227961I-1776J-1169D01*
G01X1467931Y225861D02*
G03X1468206Y227213I-538J813D01*
G01X1468205Y227214D02*
G03X1468168Y227266I-812J-539D01*
G01D02*
G03X1466854Y227489I-776J-590D01*
G01X1469085Y227962D02*
G03X1466219Y228448I-1692J-1286D01*
G01X1466854Y227489D02*
X1465799Y226790D01*
G01X1466895Y366935D02*
X1467577Y370153D01*
G01X1465840Y367508D02*
X1466547Y370842D01*
G01X1467577Y370153D02*
X1470836Y372383D01*
G01X1466547Y370842D02*
X1469857Y373108D01*
G01X1470836Y372383D02*
X1471786Y375413D01*
G01X1469857Y373108D02*
X1470594Y375458D01*
G01X1471786Y375413D02*
X1469778Y384078D01*
G01X1470594Y375458D02*
X1468604Y384050D01*
G01X1469778Y384078D02*
X1470071Y385695D01*
G01X1468604Y384050D02*
X1468939Y385900D01*
G01X1470071Y385695D02*
X1470532Y386586D01*
G01X1469048Y386223D02*
X1469509Y387114D01*
G01X1470532Y386586D02*
X1473986Y388877D01*
G01X1469692Y387410D02*
X1473200Y389737D01*
G01X1473986Y388877D02*
X1475858Y391254D01*
G01X1473200Y389737D02*
X1474782Y391747D01*
G01X1475858Y391254D02*
X1476964Y396946D01*
G01X1474782Y391747D02*
X1475769Y396828D01*
G01X1476964Y396946D02*
X1476834Y397265D01*
G01X1476833D02*
X1475473Y400602D01*
G01X1475769Y396828D02*
X1474366Y400269D01*
G01X1475473Y400602D02*
X1475102Y402450D01*
G01X1474366Y400269D02*
X1473930Y402447D01*
G01X1475102Y402450D02*
X1476896Y411411D01*
G01X1473930Y402447D02*
X1475836Y411978D01*
G01X1465840Y367508D02*
X1466547Y370842D01*
G01X1466895Y366935D02*
X1467577Y370153D01*
G01X1466547Y370842D02*
X1469857Y373108D01*
G01X1467577Y370153D02*
X1470836Y372383D01*
G01X1469857Y373108D02*
X1470594Y375458D01*
G01X1470836Y372383D02*
X1471786Y375413D01*
G01X1470594Y375458D02*
X1468604Y384050D01*
G01X1471786Y375413D02*
X1469778Y384078D01*
G01X1468604Y384050D02*
X1468939Y385900D01*
G01X1469778Y384078D02*
X1470071Y385695D01*
G01X1469048Y386223D02*
X1469509Y387114D01*
G01X1470071Y385695D02*
X1470532Y386586D01*
G01X1469692Y387410D02*
X1473200Y389737D01*
G01X1470532Y386586D02*
X1473986Y388877D01*
G01X1473200Y389737D02*
X1474782Y391747D01*
G01X1473986Y388877D02*
X1475858Y391254D01*
G01X1474782Y391747D02*
X1475769Y396828D01*
G01X1475858Y391254D02*
X1476964Y396946D01*
G01X1475769Y396828D02*
X1474366Y400269D01*
G01X1476964Y396946D02*
X1476834Y397265D01*
G01X1475769Y396828D02*
X1474366Y400269D01*
G01X1476833Y397265D02*
X1475473Y400602D01*
G01X1474366Y400269D02*
X1473930Y402447D01*
G01X1475473Y400602D02*
X1475102Y402450D01*
G01X1473930Y402447D02*
X1475836Y411978D01*
G01X1475102Y402450D02*
X1476896Y411411D01*
G01X1472798Y435800D02*
X1471398D01*
G01X1468698D02*
X1467298D01*
G01X1473663Y436665D02*
X1472798Y435800D01*
G01X1472320Y436950D02*
X1472849Y437479D01*
G01X1472320Y436950D02*
X1472849Y437479D01*
G01X1473663Y436665D02*
X1472798Y435800D01*
G01D02*
X1471398D01*
G01X1468698D02*
X1467298D01*
G01X1475460Y427033D02*
X1473477Y425050D01*
G01X1473000Y426200D02*
X1474310Y427510D01*
G01X1475460Y428099D02*
Y427033D01*
G01X1474310Y427510D02*
Y428099D01*
G01Y427510D02*
Y428099D01*
G01X1475460D02*
Y427033D01*
G01X1473000Y426200D02*
X1474310Y427510D01*
G01X1475460Y427033D02*
X1473477Y425050D01*
G01X1467290Y428996D02*
X1466661Y429625D01*
G01X1469900Y428013D02*
X1467138Y430775D01*
G01X1469900Y428013D02*
X1467138Y430775D01*
G01X1467290Y428996D02*
X1466661Y429625D01*
G01X1466767Y416171D02*
X1476073D01*
G01X1466291Y417321D02*
X1476073D01*
G01X1476896Y411411D02*
X1477719Y412234D01*
G01X1475836Y411978D02*
X1477242Y413384D01*
G01X1477719Y412234D02*
X1480313D01*
G01X1477242Y413384D02*
X1480313D01*
G01X1466291Y417321D02*
X1476073D01*
G01X1466767Y416171D02*
X1476073D01*
G01X1475836Y411978D02*
X1477242Y413384D01*
G01X1476896Y411411D02*
X1477719Y412234D01*
G01X1477242Y413384D02*
X1480313D01*
G01X1477719Y412234D02*
X1480313D01*
G01X1540035Y523359D02*
X1521918Y505242D01*
G01X1539221Y524173D02*
X1521105Y506056D01*
G01X1521918Y505242D02*
G02X1520753Y504760I-1166J1168D01*
G01X1521105Y506056D02*
G02X1520752Y505910I-353J354D01*
G01X1520753Y504760D02*
X1511039D01*
G01X1520752Y505910D02*
X1511039D01*
G01Y504760D02*
G03X1510402Y504123I0J-637D01*
G01X1511039Y505910D02*
G03X1509252Y504123I0J-1787D01*
G01X1510402D02*
Y503942D01*
G01X1509252Y504123D02*
Y503894D01*
G01X1508688Y512034D02*
G02X1509438Y512784I750J0D01*
G01X1507538Y512034D02*
G02X1509438Y513934I1900J0D01*
G01Y512784D02*
X1511758D01*
G01X1514194D02*
X1524286D01*
G01X1509438Y513934D02*
X1524285D01*
G01X1524286Y512784D02*
G03X1525451Y513266I-1J1650D01*
G01X1524285Y513934D02*
G03X1524638Y514080I0J500D01*
G01X1525451Y513266D02*
X1538673Y526488D01*
G01X1524638Y514080D02*
X1537860Y527302D01*
G01X1536412Y530260D02*
X1523399Y517247D01*
G01X1537228Y529447D02*
X1524213Y516434D01*
G01X1523399Y517247D02*
G02X1523046Y517100I-354J352D01*
G01X1524213Y516433D02*
G02X1523047Y515950I-1166J1167D01*
G01X1523046Y517100D02*
X1521132D01*
G01X1523047Y515950D02*
X1521132D01*
G01Y517100D02*
G02X1520368Y517864I0J764D01*
G01X1521132Y515950D02*
G02X1519218Y517864I0J1914D01*
G01X1520368D02*
Y519445D01*
G01X1519218Y517864D02*
Y519445D01*
G01X1520368D02*
G03X1516118I-2125J0D01*
G01X1519218D02*
G03X1517268I-975J0D01*
G01X1516118D02*
Y518075D01*
G01X1517268Y519445D02*
Y518075D01*
G01X1516118D02*
G02X1515143Y517100I-975J0D01*
G01X1517268Y518075D02*
G02X1515143Y515950I-2125J0D01*
G01Y517100D02*
X1511167D01*
G01X1515143Y515950D02*
X1511167D01*
G01X1500095Y509207D02*
Y509562D01*
G01X1498945Y509093D02*
Y509562D01*
G01X1500095D02*
G02X1500597Y510064I502J0D01*
G01X1498945Y509562D02*
G02X1500597Y511214I1652J0D01*
G01Y510064D02*
X1502683D01*
G01X1500597Y511214D02*
X1502683D01*
G01Y510064D02*
G03X1503994Y510606I1J1853D01*
G01X1502683Y511214D02*
G03X1503180Y511420I0J703D01*
G01X1503994Y510606D02*
X1504603Y511215D01*
G01X1503180Y511420D02*
X1503789Y512029D01*
G01X1504603Y511215D02*
G03X1505257Y512797I-1583J1581D01*
G01X1503789Y512029D02*
G03X1504107Y512797I-768J768D01*
G01X1505257D02*
Y513352D01*
G01X1504107Y512797D02*
Y513352D01*
G01X1505257D02*
G03X1504789Y514485I-1602J1D01*
G01X1504107Y513352D02*
G03X1503975Y513671I-451J0D01*
G01X1504789Y514485D02*
X1503971Y515303D01*
G01X1503975Y513671D02*
X1503157Y514489D01*
G01X1503971Y515303D02*
G02X1503835Y515629I325J327D01*
G01X1503157Y514489D02*
G02X1502685Y515630I1140J1140D01*
G01X1503835Y515629D02*
Y518859D01*
G01X1502685Y515630D02*
Y518860D01*
G01X1503835Y518859D02*
G02X1504268Y519903I1476J0D01*
G01X1502685Y518860D02*
G02X1503454Y520717I2626J0D01*
G01X1504268Y519903D02*
X1507841Y523476D01*
G01X1503454Y520717D02*
X1507027Y524290D01*
G01X1507841Y523476D02*
G02X1508160Y523608I319J-319D01*
G01X1507027Y524290D02*
G02X1508160Y524758I1132J-1134D01*
G01Y523608D02*
X1517314D01*
G01X1508160Y524758D02*
X1517314D01*
G01Y523608D02*
G03X1518446Y524077I0J1601D01*
G01X1517314Y524758D02*
G03X1517632Y524891I-1J450D01*
G01X1518446Y524077D02*
X1520426Y526057D01*
G01X1517632Y524891D02*
X1526788Y534047D01*
G01X1500365Y525027D02*
X1501294Y525956D01*
G01D02*
X1501295D01*
G01D02*
X1502305Y526966D01*
G01X1501491Y527780D02*
X1499551Y525841D01*
G01X1500110Y524411D02*
G02X1500365Y525027I872J0D01*
G01X1499551Y525841D02*
G03X1498960Y524411I1431J-1429D01*
G01X1500110Y516853D02*
Y524411D01*
G01X1498960D02*
Y517213D01*
G01X1491950Y520936D02*
Y524637D01*
G01X1490800Y520886D02*
Y529936D01*
G01X1487170Y511017D02*
Y509509D01*
G01X1486020Y508513D02*
Y511017D01*
G01X1487386Y511535D02*
G03X1487170Y511017I516J-519D01*
G01X1486020D02*
G02X1486572Y512349I1883J0D01*
G01X1488223Y512372D02*
X1487386Y511535D01*
G01X1486572Y512349D02*
X1487409Y513186D01*
G01X1489347Y512372D02*
G03X1488223I-562J-562D01*
G01X1487409Y513186D02*
G02X1490161I1376J-1376D01*
G01X1493073Y508646D02*
X1489347Y512372D01*
G01X1490161Y513186D02*
X1493886Y509460D01*
G01X1496321Y509991D02*
G02X1493073Y508646I-1902J0D01*
G01X1493886Y509460D02*
G03X1495170Y509991I532J531D01*
G01X1495269Y512532D02*
G02X1496321Y509991I-2544J-2541D01*
G01X1495170D02*
G03X1494455Y511719I-2445J0D01*
G01X1493516Y514287D02*
X1495269Y512532D01*
G01X1494455Y511719D02*
X1492702Y513474D01*
G01X1493517Y515816D02*
G03X1493516Y514287I765J-765D01*
G01X1492702Y513474D02*
G02X1492703Y516630I1579J1577D01*
G01X1496050Y518349D02*
X1493517Y515816D01*
G01X1492703Y516630D02*
X1495236Y519163D01*
G01X1497000Y520643D02*
G02X1496050Y518349I-3244J0D01*
G01X1495236Y519163D02*
G03X1495849Y520643I-1480J1480D01*
G01X1497000Y525292D02*
Y520643D01*
G01X1495850Y520642D02*
Y525293D01*
G01X1497712Y527011D02*
G03X1497000Y525292I1719J-1719D01*
G01X1495850Y525293D02*
G02X1496898Y527825I3582J0D01*
G01X1481050Y509086D02*
Y510700D01*
G01X1479900Y508686D02*
Y510700D01*
G01X1481050D02*
G03X1480502Y512026I-1875J1D01*
G01X1479900Y510700D02*
G03X1479688Y511212I-724J0D01*
G01X1480502Y512026D02*
X1480314Y512214D01*
G01X1479688Y511212D02*
X1479500Y511400D01*
G01X1480314Y512214D02*
G02X1479551Y514056I1842J1842D01*
G01X1479500Y511400D02*
G02X1478400Y514056I2656J2656D01*
G01X1479550Y514055D02*
Y516992D01*
G01X1478400Y514056D02*
Y516993D01*
G01X1479550Y516992D02*
G02X1479714Y517386I556J0D01*
G01X1478400Y516993D02*
G02X1478900Y518200I1707J0D01*
G01X1479714Y517386D02*
X1482154Y519825D01*
G01X1478900Y518200D02*
X1481340Y520639D01*
G01X1482154Y519825D02*
G02X1483901Y520550I1748J-1745D01*
G01X1481340Y520639D02*
G02X1483900Y521700I2561J-2560D01*
G01X1483901Y520550D02*
X1485167D01*
G01X1483900Y521700D02*
X1485167D01*
G01Y520550D02*
G03X1488250Y523633I0J3083D01*
G01X1485167Y521700D02*
G03X1487100Y523633I0J1933D01*
G01X1488250D02*
Y530364D01*
G01X1487100Y523633D02*
Y530365D01*
G01X1539221Y524173D02*
X1521105Y506056D01*
G01X1540035Y523359D02*
X1521918Y505242D01*
G01X1521105Y506056D02*
G02X1520752Y505910I-353J354D01*
G01X1521918Y505242D02*
G02X1520753Y504760I-1166J1168D01*
G01X1520752Y505910D02*
X1511039D01*
G01X1520753Y504760D02*
X1511039D01*
G01Y505910D02*
G03X1509252Y504123I0J-1787D01*
G01X1511039Y504760D02*
G03X1510402Y504123I0J-637D01*
G01X1509252D02*
Y503894D01*
G01X1510402Y504123D02*
Y503942D01*
G01X1507538Y512034D02*
G02X1509438Y513934I1900J0D01*
G01X1508688Y512034D02*
G02X1509438Y512784I750J0D01*
G01Y513934D02*
X1524285D01*
G01X1509438Y512784D02*
X1511758D01*
G01X1509438Y513934D02*
X1524285D01*
G01X1514194Y512784D02*
X1524286D01*
G01X1524285Y513934D02*
G03X1524638Y514080I0J500D01*
G01X1524286Y512784D02*
G03X1525451Y513266I-1J1650D01*
G01X1524638Y514080D02*
X1537860Y527302D01*
G01X1525451Y513266D02*
X1538673Y526488D01*
G01X1537228Y529447D02*
X1524213Y516434D01*
G01X1536412Y530260D02*
X1523399Y517247D01*
G01X1524213Y516433D02*
G02X1523047Y515950I-1166J1167D01*
G01X1523399Y517247D02*
G02X1523046Y517100I-354J352D01*
G01X1523047Y515950D02*
X1521132D01*
G01X1523046Y517100D02*
X1521132D01*
G01Y515950D02*
G02X1519218Y517864I0J1914D01*
G01X1521132Y517100D02*
G02X1520368Y517864I0J764D01*
G01X1519218D02*
Y519445D01*
G01X1520368Y517864D02*
Y519445D01*
G01X1519218D02*
G03X1517268I-975J0D01*
G01X1520368D02*
G03X1516118I-2125J0D01*
G01X1517268D02*
Y518075D01*
G01X1516118Y519445D02*
Y518075D01*
G01X1517268D02*
G02X1515143Y515950I-2125J0D01*
G01X1516118Y518075D02*
G02X1515143Y517100I-975J0D01*
G01Y515950D02*
X1511167D01*
G01X1515143Y517100D02*
X1511167D01*
G01X1498945Y509093D02*
Y509562D01*
G01X1500095Y509207D02*
Y509562D01*
G01X1498945D02*
G02X1500597Y511214I1652J0D01*
G01X1500095Y509562D02*
G02X1500597Y510064I502J0D01*
G01Y511214D02*
X1502683D01*
G01X1500597Y510064D02*
X1502683D01*
G01Y511214D02*
G03X1503180Y511420I0J703D01*
G01X1502683Y510064D02*
G03X1503994Y510606I1J1853D01*
G01X1503180Y511420D02*
X1503789Y512029D01*
G01X1503994Y510606D02*
X1504603Y511215D01*
G01X1503789Y512029D02*
G03X1504107Y512797I-768J768D01*
G01X1504603Y511215D02*
G03X1505257Y512797I-1583J1581D01*
G01X1504107D02*
Y513352D01*
G01X1505257Y512797D02*
Y513352D01*
G01X1504107D02*
G03X1503975Y513671I-451J0D01*
G01X1505257Y513352D02*
G03X1504789Y514485I-1602J1D01*
G01X1503975Y513671D02*
X1503157Y514489D01*
G01X1504789Y514485D02*
X1503971Y515303D01*
G01X1503157Y514489D02*
G02X1502685Y515630I1140J1140D01*
G01X1503971Y515303D02*
G02X1503835Y515629I325J327D01*
G01X1502685Y515630D02*
Y518860D01*
G01X1503835Y515629D02*
Y518859D01*
G01X1502685Y518860D02*
G02X1503454Y520717I2626J0D01*
G01X1503835Y518859D02*
G02X1504268Y519903I1476J0D01*
G01X1503454Y520717D02*
X1507027Y524290D01*
G01X1504268Y519903D02*
X1507841Y523476D01*
G01X1507027Y524290D02*
G02X1508160Y524758I1132J-1134D01*
G01X1507841Y523476D02*
G02X1508160Y523608I319J-319D01*
G01Y524758D02*
X1517314D01*
G01X1508160Y523608D02*
X1517314D01*
G01Y524758D02*
G03X1517632Y524891I-1J450D01*
G01X1517314Y523608D02*
G03X1518446Y524077I0J1601D01*
G01X1517632Y524891D02*
X1526788Y534047D01*
G01X1518446Y524077D02*
X1520426Y526057D01*
G01X1517632Y524891D02*
X1526788Y534047D01*
G01X1517632Y524891D02*
X1526788Y534047D01*
G01X1498960Y524411D02*
Y517213D01*
G01X1500110Y516853D02*
Y524411D01*
G01X1499551Y525841D02*
G03X1498960Y524411I1431J-1429D01*
G01X1500110D02*
G02X1500365Y525027I872J0D01*
G01X1501491Y527780D02*
X1499551Y525841D01*
G01X1500365Y525027D02*
X1501294Y525956D01*
G01X1501491Y527780D02*
X1499551Y525841D01*
G01X1501294Y525956D02*
X1501295D01*
G01X1501491Y527780D02*
X1499551Y525841D01*
G01X1501295Y525956D02*
X1502305Y526966D01*
G01X1490800Y520886D02*
Y529936D01*
G01X1491950Y520936D02*
Y524637D01*
G01X1490800Y520886D02*
Y529936D01*
G01X1495850Y525293D02*
G02X1496898Y527825I3582J0D01*
G01X1497712Y527011D02*
G03X1497000Y525292I1719J-1719D01*
G01X1495850Y520642D02*
Y525293D01*
G01X1497000Y525292D02*
Y520643D01*
G01X1495236Y519163D02*
G03X1495849Y520643I-1480J1480D01*
G01X1497000D02*
G02X1496050Y518349I-3244J0D01*
G01X1492703Y516630D02*
X1495236Y519163D01*
G01X1496050Y518349D02*
X1493517Y515816D01*
G01X1492702Y513474D02*
G02X1492703Y516630I1579J1577D01*
G01X1493517Y515816D02*
G03X1493516Y514287I765J-765D01*
G01X1494455Y511719D02*
X1492702Y513474D01*
G01X1493516Y514287D02*
X1495269Y512532D01*
G01X1495170Y509991D02*
G03X1494455Y511719I-2445J0D01*
G01X1495269Y512532D02*
G02X1496321Y509991I-2544J-2541D01*
G01X1493886Y509460D02*
G03X1495170Y509991I532J531D01*
G01X1496321D02*
G02X1493073Y508646I-1902J0D01*
G01X1490161Y513186D02*
X1493886Y509460D01*
G01X1493073Y508646D02*
X1489347Y512372D01*
G01X1487409Y513186D02*
G02X1490161I1376J-1376D01*
G01X1489347Y512372D02*
G03X1488223I-562J-562D01*
G01X1486572Y512349D02*
X1487409Y513186D01*
G01X1488223Y512372D02*
X1487386Y511535D01*
G01X1486020Y511017D02*
G02X1486572Y512349I1883J0D01*
G01X1487386Y511535D02*
G03X1487170Y511017I516J-519D01*
G01X1486020Y508513D02*
Y511017D01*
G01X1487170D02*
Y509509D01*
G01X1479900Y508686D02*
Y510700D01*
G01X1481050Y509086D02*
Y510700D01*
G01X1479900D02*
G03X1479688Y511212I-724J0D01*
G01X1481050Y510700D02*
G03X1480502Y512026I-1875J1D01*
G01X1479688Y511212D02*
X1479500Y511400D01*
G01X1480502Y512026D02*
X1480314Y512214D01*
G01X1479500Y511400D02*
G02X1478400Y514056I2656J2656D01*
G01X1480314Y512214D02*
G02X1479551Y514056I1842J1842D01*
G01X1478400D02*
Y516993D01*
G01X1479550Y514055D02*
Y516992D01*
G01X1478400Y516993D02*
G02X1478900Y518200I1707J0D01*
G01X1479550Y516992D02*
G02X1479714Y517386I556J0D01*
G01X1478900Y518200D02*
X1481340Y520639D01*
G01X1479714Y517386D02*
X1482154Y519825D01*
G01X1481340Y520639D02*
G02X1483900Y521700I2561J-2560D01*
G01X1482154Y519825D02*
G02X1483901Y520550I1748J-1745D01*
G01X1483900Y521700D02*
X1485167D01*
G01X1483901Y520550D02*
X1485167D01*
G01Y521700D02*
G03X1487100Y523633I0J1933D01*
G01X1485167Y520550D02*
G03X1488250Y523633I0J3083D01*
G01X1487100D02*
Y530365D01*
G01X1488250Y523633D02*
Y530364D01*
G01X1523219Y528850D02*
X1524174Y529805D01*
G01X1526967Y532598D02*
X1527602Y533233D01*
G01X1526788Y534047D02*
G02X1529589Y535206I2800J-2802D01*
G01X1518173Y528243D02*
X1530199Y540269D01*
G01X1529385Y541083D02*
X1517359Y529057D01*
G01X1516193Y527424D02*
G03X1518173Y528243I3J2796D01*
G01X1517359Y529057D02*
G02X1516193Y528574I-1165J1163D01*
G01X1503410Y527424D02*
X1504760D01*
G01X1508710D02*
X1510893D01*
G01X1514843D02*
X1516193D01*
G01Y528574D02*
X1503410D01*
G01X1502305Y526966D02*
G02X1503410Y527424I1105J-1104D01*
G01Y528574D02*
G03X1501491Y527780I-1J-2713D01*
G01X1491950Y528587D02*
Y529937D01*
G01X1491951Y529936D02*
G02X1492720Y531792I2625J0D01*
G01X1490800Y529936D02*
G02X1491906Y532606I3775J0D01*
G01X1492720Y531792D02*
X1496424Y535496D01*
G01X1499217Y538289D02*
X1500172Y539244D01*
G01X1491906Y532606D02*
X1499358Y540058D01*
G01X1500172Y539244D02*
G02X1500863Y539530I691J-692D01*
G01X1499358Y540058D02*
G02X1500863Y540680I1504J-1506D01*
G01Y539530D02*
X1505486D01*
G01X1509436D02*
X1515784D01*
G01X1500863Y540680D02*
X1515784D01*
G01Y539530D02*
G03X1518012Y540453I0J3151D01*
G01X1515784Y540680D02*
G03X1517198Y541267I-1J2000D01*
G01X1518012Y540453D02*
X1523951Y546392D01*
G01X1517198Y541267D02*
X1523137Y547206D01*
G01X1523951Y546392D02*
G02X1525365Y546979I1415J-1413D01*
G01X1523137Y547206D02*
G02X1525364Y548129I2228J-2228D01*
G01X1525365Y546979D02*
X1543006D01*
G01X1525364Y548129D02*
X1543006D01*
G01X1500038Y529337D02*
X1497712Y527011D01*
G01X1496898Y527825D02*
X1499224Y530151D01*
G01X1501589Y533083D02*
G02X1500038Y529337I-5295J-2D01*
G01X1499224Y530151D02*
G03X1500438Y533083I-2930J2931D01*
G01X1501589Y535102D02*
Y533083D01*
G01X1500439Y533082D02*
Y535103D01*
G01X1501913Y535881D02*
G03X1501589Y535102I777J-780D01*
G01X1500439Y535103D02*
G02X1501099Y536695I2252J-1D01*
G01X1502125Y536093D02*
X1501913Y535881D01*
G01X1501099Y536695D02*
X1501311Y536907D01*
G01X1502904Y536417D02*
G03X1502125Y536093I1J-1101D01*
G01X1501311Y536907D02*
G02X1502903Y537567I1593J-1592D01*
G01X1503680Y536417D02*
X1502904D01*
G01X1502903Y537567D02*
X1503680D01*
G01X1504822Y535302D02*
G03X1504528Y536009I-998J-1D01*
G01X1504431Y536106D02*
G03X1503680Y536417I-752J-752D01*
G01Y537567D02*
G02X1505245Y536919I0J-2214D01*
G01X1504528Y536009D02*
X1504431Y536106D01*
G01X1505245Y536919D02*
X1505340Y536824D01*
G01X1504822Y535302D02*
G03X1504528Y536009I-998J-1D01*
G01X1504431Y536106D02*
G03X1503680Y536417I-752J-752D01*
G01X1505340Y536824D02*
G02X1505972Y535302I-1517J-1522D01*
G01X1504822Y534867D02*
Y535302D01*
G01X1505972D02*
Y534867D01*
G01X1507162Y532527D02*
G02X1505569Y533186I-1J2251D01*
G01X1505481Y533274D02*
G02X1504822Y534867I1592J1592D01*
G01X1505972D02*
G03X1506295Y534088I1101J0D01*
G01X1505569Y533186D02*
X1505481Y533274D01*
G01X1506295Y534088D02*
X1506383Y534000D01*
G01X1507162Y532527D02*
G02X1505569Y533186I-1J2251D01*
G01X1505481Y533274D02*
G02X1504822Y534867I1592J1592D01*
G01X1506383Y534000D02*
G03X1507162Y533677I779J778D01*
G01X1508162Y532527D02*
X1507162D01*
G01Y533677D02*
X1508162D01*
G01X1510412Y534777D02*
G02X1508162Y532527I-2250J0D01*
G01Y533677D02*
G03X1509262Y534777I0J1100D01*
G01X1510412Y535602D02*
Y534777D01*
G01X1509262D02*
Y535602D01*
G01X1511188Y536378D02*
G03X1510412Y535602I0J-776D01*
G01X1509262D02*
G02X1511188Y537528I1926J0D01*
G01X1511437Y536378D02*
X1511188D01*
G01Y537528D02*
X1511437D01*
G01X1512462Y535353D02*
G03X1511437Y536378I-1025J0D01*
G01Y537528D02*
G02X1513612Y535353I0J-2175D01*
G01X1512462Y534246D02*
Y535353D01*
G01X1513612D02*
Y534246D01*
G01X1514181Y532527D02*
G02X1512462Y534246I0J1719D01*
G01X1513612D02*
G03X1514181Y533677I569J0D01*
G01X1514886Y532527D02*
X1514181D01*
G01Y533677D02*
X1514886D01*
G01X1516018Y532996D02*
G02X1514886Y532527I-1132J1131D01*
G01Y533677D02*
G03X1515204Y533810I-1J449D01*
G01X1526594Y543572D02*
X1525745Y542723D01*
G01X1522952Y539930D02*
X1521997Y538975D01*
G01X1519204Y536182D02*
X1516018Y532996D01*
G01X1515204Y533810D02*
X1525780Y544386D01*
G01X1527166Y543810D02*
G03X1526594Y543572I1J-810D01*
G01X1525780Y544386D02*
G02X1527166Y544960I1386J-1386D01*
G01X1488250Y530364D02*
G02X1489216Y532694I3294J0D01*
G01X1487100Y530365D02*
G02X1488402Y533508I4445J0D01*
G01X1489216Y532694D02*
X1500558Y544036D01*
G01X1488402Y533508D02*
X1499744Y544850D01*
G01X1500558Y544036D02*
G03X1501399Y546068I-2035J2032D01*
G01X1499744Y544850D02*
G03X1500249Y546069I-1220J1220D01*
G01X1501399Y546068D02*
Y549181D01*
G01X1500249Y546069D02*
Y549182D01*
G01X1501399Y549181D02*
G02X1501541Y549521I480J-1D01*
G01X1500249Y549182D02*
G02X1500727Y550334I1630J-1D01*
G01X1501541Y549521D02*
G02X1502720Y550079I1172J-952D01*
G01X1500843Y550450D02*
G02X1502719Y551229I1879J-1876D01*
G01X1501541Y549521D02*
G02X1502720Y550079I1172J-952D01*
G01X1502719Y551229D02*
G02X1502721I1J-2656D01*
G01X1502720Y550079D02*
X1504089D01*
G01X1502721Y551229D02*
X1504089D01*
G01Y550079D02*
G02X1505114Y549054I0J-1025D01*
G01X1504089Y551229D02*
G02X1506264Y549054I0J-2175D01*
G01X1505114D02*
Y544808D01*
G01X1506264Y549054D02*
Y544808D01*
G01X1505114D02*
G03X1509464I2175J0D01*
G01X1506264D02*
G03X1508314I1025J0D01*
G01X1509464D02*
Y549054D01*
G01X1508314Y544808D02*
Y549054D01*
G01X1509464D02*
G02X1511514I1025J0D01*
G01X1508314D02*
G02X1512664I2175J0D01*
G01X1511514D02*
Y544808D01*
G01X1512664Y549054D02*
Y544808D01*
G01X1511514D02*
G03X1515864I2175J0D01*
G01X1512664D02*
G03X1514714I1025J0D01*
G01X1515864D02*
Y549054D01*
G01X1514714Y544808D02*
Y549054D01*
G01X1515864D02*
G02X1516889Y550079I1025J0D01*
G01X1514714Y549054D02*
G02X1516889Y551229I2175J0D01*
G01Y550079D02*
X1518239D01*
G01X1522189D02*
X1537284D01*
G01X1516889Y551229D02*
X1537284D01*
G01X1523219Y528850D02*
X1524174Y529805D01*
G01X1526967Y532598D02*
X1527602Y533233D01*
G01X1526788Y534047D02*
G02X1529589Y535206I2800J-2802D01*
G01X1503410Y528574D02*
G03X1501491Y527780I-1J-2713D01*
G01X1502305Y526966D02*
G02X1503410Y527424I1105J-1104D01*
G01X1516193Y528574D02*
X1503410D01*
G01Y527424D02*
X1504760D01*
G01X1516193Y528574D02*
X1503410D01*
G01X1508710Y527424D02*
X1510893D01*
G01X1516193Y528574D02*
X1503410D01*
G01X1514843Y527424D02*
X1516193D01*
G01X1517359Y529057D02*
G02X1516193Y528574I-1165J1163D01*
G01Y527424D02*
G03X1518173Y528243I3J2796D01*
G01X1529385Y541083D02*
X1517359Y529057D01*
G01X1518173Y528243D02*
X1530199Y540269D01*
G01X1491950Y528587D02*
Y529937D01*
G01X1490800Y529936D02*
G02X1491906Y532606I3775J0D01*
G01X1491951Y529936D02*
G02X1492720Y531792I2625J0D01*
G01X1491906Y532606D02*
X1499358Y540058D01*
G01X1492720Y531792D02*
X1496424Y535496D01*
G01X1491906Y532606D02*
X1499358Y540058D01*
G01X1499217Y538289D02*
X1500172Y539244D01*
G01X1499358Y540058D02*
G02X1500863Y540680I1504J-1506D01*
G01X1500172Y539244D02*
G02X1500863Y539530I691J-692D01*
G01Y540680D02*
X1515784D01*
G01X1500863Y539530D02*
X1505486D01*
G01X1500863Y540680D02*
X1515784D01*
G01X1509436Y539530D02*
X1515784D01*
G01Y540680D02*
G03X1517198Y541267I-1J2000D01*
G01X1515784Y539530D02*
G03X1518012Y540453I0J3151D01*
G01X1517198Y541267D02*
X1523137Y547206D01*
G01X1518012Y540453D02*
X1523951Y546392D01*
G01X1523137Y547206D02*
G02X1525364Y548129I2228J-2228D01*
G01X1523951Y546392D02*
G02X1525365Y546979I1415J-1413D01*
G01X1525364Y548129D02*
X1543006D01*
G01X1525365Y546979D02*
X1543006D01*
G01X1525780Y544386D02*
G02X1527166Y544960I1386J-1386D01*
G01Y543810D02*
G03X1526594Y543572I1J-810D01*
G01X1515204Y533810D02*
X1525780Y544386D01*
G01X1526594Y543572D02*
X1525745Y542723D01*
G01X1515204Y533810D02*
X1525780Y544386D01*
G01X1522952Y539930D02*
X1521997Y538975D01*
G01X1515204Y533810D02*
X1525780Y544386D01*
G01X1519204Y536182D02*
X1516018Y532996D01*
G01X1514886Y533677D02*
G03X1515204Y533810I-1J449D01*
G01X1516018Y532996D02*
G02X1514886Y532527I-1132J1131D01*
G01X1514181Y533677D02*
X1514886D01*
G01Y532527D02*
X1514181D01*
G01X1513612Y534246D02*
G03X1514181Y533677I569J0D01*
G01Y532527D02*
G02X1512462Y534246I0J1719D01*
G01X1513612Y535353D02*
Y534246D01*
G01X1512462D02*
Y535353D01*
G01X1511437Y537528D02*
G02X1513612Y535353I0J-2175D01*
G01X1512462D02*
G03X1511437Y536378I-1025J0D01*
G01X1511188Y537528D02*
X1511437D01*
G01Y536378D02*
X1511188D01*
G01X1509262Y535602D02*
G02X1511188Y537528I1926J0D01*
G01Y536378D02*
G03X1510412Y535602I0J-776D01*
G01X1509262Y534777D02*
Y535602D01*
G01X1510412D02*
Y534777D01*
G01X1508162Y533677D02*
G03X1509262Y534777I0J1100D01*
G01X1510412D02*
G02X1508162Y532527I-2250J0D01*
G01X1507162Y533677D02*
X1508162D01*
G01Y532527D02*
X1507162D01*
G01X1505972Y534867D02*
G03X1506295Y534088I1101J0D01*
G01X1506383Y534000D02*
G03X1507162Y533677I779J778D01*
G01Y532527D02*
G02X1505569Y533186I-1J2251D01*
G01X1506295Y534088D02*
X1506383Y534000D01*
G01X1505569Y533186D02*
X1505481Y533274D01*
G01X1505972Y534867D02*
G03X1506295Y534088I1101J0D01*
G01X1506383Y534000D02*
G03X1507162Y533677I779J778D01*
G01X1505481Y533274D02*
G02X1504822Y534867I1592J1592D01*
G01X1505972Y535302D02*
Y534867D01*
G01X1504822D02*
Y535302D01*
G01X1503680Y537567D02*
G02X1505245Y536919I0J-2214D01*
G01X1505340Y536824D02*
G02X1505972Y535302I-1517J-1522D01*
G01X1504822D02*
G03X1504528Y536009I-998J-1D01*
G01X1505245Y536919D02*
X1505340Y536824D01*
G01X1504528Y536009D02*
X1504431Y536106D01*
G01X1503680Y537567D02*
G02X1505245Y536919I0J-2214D01*
G01X1505340Y536824D02*
G02X1505972Y535302I-1517J-1522D01*
G01X1504431Y536106D02*
G03X1503680Y536417I-752J-752D01*
G01X1502903Y537567D02*
X1503680D01*
G01Y536417D02*
X1502904D01*
G01X1501311Y536907D02*
G02X1502903Y537567I1593J-1592D01*
G01X1502904Y536417D02*
G03X1502125Y536093I1J-1101D01*
G01X1501099Y536695D02*
X1501311Y536907D01*
G01X1502125Y536093D02*
X1501913Y535881D01*
G01X1500439Y535103D02*
G02X1501099Y536695I2252J-1D01*
G01X1501913Y535881D02*
G03X1501589Y535102I777J-780D01*
G01X1500439Y533082D02*
Y535103D01*
G01X1501589Y535102D02*
Y533083D01*
G01X1499224Y530151D02*
G03X1500438Y533083I-2930J2931D01*
G01X1501589D02*
G02X1500038Y529337I-5295J-2D01*
G01X1496898Y527825D02*
X1499224Y530151D01*
G01X1500038Y529337D02*
X1497712Y527011D01*
G01X1487100Y530365D02*
G02X1488402Y533508I4445J0D01*
G01X1488250Y530364D02*
G02X1489216Y532694I3294J0D01*
G01X1488402Y533508D02*
X1499744Y544850D01*
G01X1489216Y532694D02*
X1500558Y544036D01*
G01X1499744Y544850D02*
G03X1500249Y546069I-1220J1220D01*
G01X1500558Y544036D02*
G03X1501399Y546068I-2035J2032D01*
G01X1500249Y546069D02*
Y549182D01*
G01X1501399Y546068D02*
Y549181D01*
G01X1500249Y549182D02*
G02X1500727Y550334I1630J-1D01*
G01X1501399Y549181D02*
G02X1501541Y549521I480J-1D01*
G01X1500843Y550450D02*
G02X1502719Y551229I1879J-1876D01*
G01D02*
G02X1502721I1J-2656D01*
G01X1501541Y549521D02*
G02X1502720Y550079I1172J-952D01*
G01X1502721Y551229D02*
X1504089D01*
G01X1502720Y550079D02*
X1504089D01*
G01Y551229D02*
G02X1506264Y549054I0J-2175D01*
G01X1504089Y550079D02*
G02X1505114Y549054I0J-1025D01*
G01X1506264D02*
Y544808D01*
G01X1505114Y549054D02*
Y544808D01*
G01X1506264D02*
G03X1508314I1025J0D01*
G01X1505114D02*
G03X1509464I2175J0D01*
G01X1508314D02*
Y549054D01*
G01X1509464Y544808D02*
Y549054D01*
G01X1508314D02*
G02X1512664I2175J0D01*
G01X1509464D02*
G02X1511514I1025J0D01*
G01X1512664D02*
Y544808D01*
G01X1511514Y549054D02*
Y544808D01*
G01X1512664D02*
G03X1514714I1025J0D01*
G01X1511514D02*
G03X1515864I2175J0D01*
G01X1514714D02*
Y549054D01*
G01X1515864Y544808D02*
Y549054D01*
G01X1514714D02*
G02X1516889Y551229I2175J0D01*
G01X1515864Y549054D02*
G02X1516889Y550079I1025J0D01*
G01Y551229D02*
X1537284D01*
G01X1516889Y550079D02*
X1518239D01*
G01X1516889Y551229D02*
X1537284D01*
G01X1522189Y550079D02*
X1537284D01*
G01X1527975Y10089D02*
X1540820Y7360D01*
G01X1527968Y8914D02*
X1540820Y6184D01*
G01Y7360D02*
X1545401Y8334D01*
G01X1540820Y6184D02*
X1545401Y7158D01*
G01Y8334D02*
X1552193Y6891D01*
G01X1545401Y7158D02*
X1552193Y5715D01*
G01Y6891D02*
X1562791Y9142D01*
G01X1552193Y5715D02*
X1562791Y7966D01*
G01Y9142D02*
X1567498Y8142D01*
G01X1562791Y7966D02*
X1567498Y6966D01*
G01Y8142D02*
X1575177Y9773D01*
G01X1567498Y6966D02*
X1575177Y8597D01*
G01Y9773D02*
X1593270Y5934D01*
G01X1575177Y8597D02*
X1593270Y4758D01*
G01X1527968Y8914D02*
X1540820Y6184D01*
G01X1527975Y10089D02*
X1540820Y7360D01*
G01Y6184D02*
X1545401Y7158D01*
G01X1540820Y7360D02*
X1545401Y8334D01*
G01Y7158D02*
X1552193Y5715D01*
G01X1545401Y8334D02*
X1552193Y6891D01*
G01Y5715D02*
X1562791Y7966D01*
G01X1552193Y6891D02*
X1562791Y9142D01*
G01Y7966D02*
X1567498Y6966D01*
G01X1562791Y9142D02*
X1567498Y8142D01*
G01Y6966D02*
X1575177Y8597D01*
G01X1567498Y8142D02*
X1575177Y9773D01*
G01Y8597D02*
X1593270Y4758D01*
G01X1575177Y9773D02*
X1593270Y5934D01*
G01X1545044Y15165D02*
X1546654Y14691D01*
G01X1545090Y16351D02*
X1546700Y15877D01*
G01X1546654Y14691D02*
X1551223Y15662D01*
G01X1546700Y15877D02*
X1551216Y16837D01*
G01X1551223Y15662D02*
X1554595Y14987D01*
G01X1551216Y16837D02*
X1554595Y16160D01*
G01Y14987D02*
X1561043Y16276D01*
G01X1554595Y16160D02*
X1561043Y17449D01*
G01Y16276D02*
X1565192Y15449D01*
G01X1561043Y17449D02*
X1565192Y16622D01*
G01X1561043Y16276D02*
X1565192Y15449D01*
G01D02*
X1565510Y15386D01*
G01D02*
X1577699Y17825D01*
G01X1565192Y16622D02*
X1565510Y16559D01*
G01Y15386D02*
X1577699Y17825D01*
G01D02*
X1577780Y17817D01*
G01X1565510Y16559D02*
X1577720Y19002D01*
G01X1577699Y17825D02*
X1577780Y17817D01*
G01X1577721Y18979D02*
X1577957Y18955D01*
G01X1577699Y17825D02*
X1577780Y17817D01*
G01D02*
X1598013Y13570D01*
G01X1577957Y18955D02*
X1598011Y14746D01*
G01X1545134Y17775D02*
X1546768Y17297D01*
G01X1545179Y18961D02*
X1546813Y18483D01*
G01X1546768Y17297D02*
X1551236Y18246D01*
G01X1546813Y18483D02*
X1551229Y19421D01*
G01X1551236Y18246D02*
X1554147Y17664D01*
G01X1551229Y19421D02*
X1554147Y18837D01*
G01Y17664D02*
X1560944Y19023D01*
G01X1554147Y18837D02*
X1560944Y20196D01*
G01Y19023D02*
X1565192Y18173D01*
G01X1560944Y20196D02*
X1565192Y19346D01*
G01X1560944Y19023D02*
X1565192Y18173D01*
G01D02*
X1565783Y18055D01*
G01X1565785D02*
X1577786Y20456D01*
G01X1565192Y19346D02*
X1565783Y19228D01*
G01X1565785Y18055D02*
X1577786Y20456D01*
G01X1565783Y19228D02*
X1577793Y21631D01*
G01X1577786Y20456D02*
X1598052Y16153D01*
G01X1577793Y21631D02*
X1598052Y17329D01*
G01X1545090Y16351D02*
X1546700Y15877D01*
G01X1545044Y15165D02*
X1546654Y14691D01*
G01X1546700Y15877D02*
X1551216Y16837D01*
G01X1546654Y14691D02*
X1551223Y15662D01*
G01X1551216Y16837D02*
X1554595Y16160D01*
G01X1551223Y15662D02*
X1554595Y14987D01*
G01Y16160D02*
X1561043Y17449D01*
G01X1554595Y14987D02*
X1561043Y16276D01*
G01Y17449D02*
X1565192Y16622D01*
G01D02*
X1565510Y16559D01*
G01X1561043Y16276D02*
X1565192Y15449D01*
G01Y16622D02*
X1565510Y16559D01*
G01X1565192Y15449D02*
X1565510Y15386D01*
G01X1565192Y16622D02*
X1565510Y16559D01*
G01D02*
X1577720Y19002D01*
G01X1565510Y15386D02*
X1577699Y17825D01*
G01X1565510Y16559D02*
X1577720Y19002D01*
G01X1577721Y18979D02*
X1577957Y18955D01*
G01D02*
X1598011Y14746D01*
G01X1577699Y17825D02*
X1577780Y17817D01*
G01X1577957Y18955D02*
X1598011Y14746D01*
G01X1577780Y17817D02*
X1598013Y13570D01*
G01X1545179Y18961D02*
X1546813Y18483D01*
G01X1545134Y17775D02*
X1546768Y17297D01*
G01X1546813Y18483D02*
X1551229Y19421D01*
G01X1546768Y17297D02*
X1551236Y18246D01*
G01X1551229Y19421D02*
X1554147Y18837D01*
G01X1551236Y18246D02*
X1554147Y17664D01*
G01Y18837D02*
X1560944Y20196D01*
G01X1554147Y17664D02*
X1560944Y19023D01*
G01Y20196D02*
X1565192Y19346D01*
G01D02*
X1565783Y19228D01*
G01X1560944Y19023D02*
X1565192Y18173D01*
G01Y19346D02*
X1565783Y19228D01*
G01X1565192Y18173D02*
X1565783Y18055D01*
G01X1565192Y19346D02*
X1565783Y19228D01*
G01D02*
X1577793Y21631D01*
G01X1565785Y18055D02*
X1577786Y20456D01*
G01X1577793Y21631D02*
X1598052Y17329D01*
G01X1577786Y20456D02*
X1598052Y16153D01*
G01X1544987Y20519D02*
X1547305Y20025D01*
G01X1544988Y21695D02*
X1547305Y21201D01*
G01Y20025D02*
X1551247Y20863D01*
G01X1547305Y21201D02*
X1551240Y22038D01*
G01X1551247Y20863D02*
X1553865Y20340D01*
G01X1551240Y22038D02*
X1553865Y21513D01*
G01Y20340D02*
X1560780Y21723D01*
G01X1553865Y21513D02*
X1560780Y22896D01*
G01Y21723D02*
X1565912Y20697D01*
G01X1560780Y22896D02*
X1565912Y21870D01*
G01Y20697D02*
X1577760Y23066D01*
G01D02*
X1577785Y23061D01*
G01X1565912Y21870D02*
X1577757Y24239D01*
G01X1565912Y20697D02*
X1577760Y23066D01*
G01D02*
X1577785Y23061D01*
G01D02*
X1577796Y23059D01*
G01D02*
X1577801Y23058D01*
G01Y23057D02*
X1598020Y18766D01*
G01X1577777Y24239D02*
X1577997Y24193D01*
G01X1565912Y20697D02*
X1577760Y23066D01*
G01X1577801Y23057D02*
X1598020Y18766D01*
G01X1578000Y24192D02*
X1578006Y24191D01*
G01X1565912Y20697D02*
X1577760Y23066D01*
G01X1577801Y23057D02*
X1598020Y18766D01*
G01X1578006Y24191D02*
X1578016Y24189D01*
G01X1565912Y20697D02*
X1577760Y23066D01*
G01X1577801Y23057D02*
X1598020Y18766D01*
G01X1578016Y24189D02*
X1578027Y24187D01*
G01X1565912Y20697D02*
X1577760Y23066D01*
G01X1577801Y23057D02*
X1598020Y18766D01*
G01X1578027Y24187D02*
X1578040Y24184D01*
G01X1577760Y23066D02*
X1577785Y23061D01*
G01D02*
X1577796Y23059D01*
G01D02*
X1577801Y23058D01*
G01Y23057D02*
X1598020Y18766D01*
G01X1578040Y24184D02*
X1598020Y19942D01*
G01X1544988Y21695D02*
X1547305Y21201D01*
G01X1544987Y20519D02*
X1547305Y20025D01*
G01Y21201D02*
X1551240Y22038D01*
G01X1547305Y20025D02*
X1551247Y20863D01*
G01X1551240Y22038D02*
X1553865Y21513D01*
G01X1551247Y20863D02*
X1553865Y20340D01*
G01Y21513D02*
X1560780Y22896D01*
G01X1553865Y20340D02*
X1560780Y21723D01*
G01Y22896D02*
X1565912Y21870D01*
G01X1560780Y21723D02*
X1565912Y20697D01*
G01Y21870D02*
X1577757Y24239D01*
G01X1577777D02*
X1577997Y24193D01*
G01X1578000Y24192D02*
X1578006Y24191D01*
G01D02*
X1578016Y24189D01*
G01D02*
X1578027Y24187D01*
G01D02*
X1578040Y24184D01*
G01X1565912Y20697D02*
X1577760Y23066D01*
G01X1565912Y21870D02*
X1577757Y24239D01*
G01X1577777D02*
X1577997Y24193D01*
G01X1578040Y24184D02*
X1598020Y19942D01*
G01X1577760Y23066D02*
X1577785Y23061D01*
G01X1577777Y24239D02*
X1577997Y24193D01*
G01X1578040Y24184D02*
X1598020Y19942D01*
G01X1577785Y23061D02*
X1577796Y23059D01*
G01X1577777Y24239D02*
X1577997Y24193D01*
G01X1578040Y24184D02*
X1598020Y19942D01*
G01X1577796Y23059D02*
X1577801Y23058D01*
G01X1577777Y24239D02*
X1577997Y24193D01*
G01X1578000Y24192D02*
X1578006Y24191D01*
G01D02*
X1578016Y24189D01*
G01D02*
X1578027Y24187D01*
G01D02*
X1578040Y24184D01*
G01D02*
X1598020Y19942D01*
G01X1577801Y23057D02*
X1598020Y18766D01*
G01X1543749Y26642D02*
X1547358Y27407D01*
G01X1543749Y27818D02*
X1547358Y28583D01*
G01Y27407D02*
X1553858Y26026D01*
G01X1547358Y28583D02*
X1553858Y27202D01*
G01Y26026D02*
X1558280Y26965D01*
G01X1553858Y27202D02*
X1558280Y28141D01*
G01Y26965D02*
X1562809Y26003D01*
G01X1558280Y28141D02*
X1562809Y27179D01*
G01Y26003D02*
X1567700Y27042D01*
G01X1562809Y27179D02*
X1567700Y28218D01*
G01Y27042D02*
X1572585Y26004D01*
G01X1567700Y28218D02*
X1572585Y27180D01*
G01Y26004D02*
X1577477Y27043D01*
G01X1572585Y27180D02*
X1577476Y28219D01*
G01X1577477Y27043D02*
X1581974Y26088D01*
G01X1577476Y28219D02*
X1581974Y27264D01*
G01Y26088D02*
X1587988Y27366D01*
G01X1581974Y27264D02*
X1587988Y28542D01*
G01Y27366D02*
X1593923Y26104D01*
G01X1587988Y28542D02*
X1593923Y27280D01*
G01X1543852Y29259D02*
X1547335Y29997D01*
G01X1543852Y30435D02*
X1547335Y31173D01*
G01Y29997D02*
X1553903Y28601D01*
G01X1547335Y31173D02*
X1553903Y29777D01*
G01Y28601D02*
X1558280Y29531D01*
G01X1553903Y29777D02*
X1558280Y30707D01*
G01Y29531D02*
X1562809Y28569D01*
G01X1558280Y30707D02*
X1562809Y29745D01*
G01Y28569D02*
X1567700Y29608D01*
G01X1562809Y29745D02*
X1567700Y30784D01*
G01Y29608D02*
X1572584Y28570D01*
G01X1567700Y30784D02*
X1572585Y29746D01*
G01X1572584Y28570D02*
X1577476Y29609D01*
G01X1572585Y29746D02*
X1577476Y30785D01*
G01Y29609D02*
X1581885Y28673D01*
G01X1577476Y30785D02*
X1581885Y29849D01*
G01Y28673D02*
X1587876Y29946D01*
G01X1581885Y29849D02*
X1587876Y31122D01*
G01Y29946D02*
X1592582Y28946D01*
G01X1587876Y31122D02*
X1592582Y30122D01*
G01X1543930Y31845D02*
X1547583Y32621D01*
G01D02*
X1554164Y31223D01*
G01X1547583Y33797D02*
X1554164Y32399D01*
G01Y31223D02*
X1558280Y32097D01*
G01X1554164Y32399D02*
X1558280Y33273D01*
G01Y32097D02*
X1562809Y31135D01*
G01X1558280Y33273D02*
X1562809Y32311D01*
G01Y31135D02*
X1567700Y32174D01*
G01X1562809Y32311D02*
X1567700Y33350D01*
G01Y32174D02*
X1572584Y31136D01*
G01X1567700Y33350D02*
X1572585Y32312D01*
G01X1572584Y31136D02*
X1577476Y32175D01*
G01X1572585Y32312D02*
X1577476Y33351D01*
G01Y32175D02*
X1581885Y31239D01*
G01X1577476Y33351D02*
X1581885Y32415D01*
G01Y31239D02*
X1588001Y32538D01*
G01X1581885Y32415D02*
X1588001Y33714D01*
G01Y32538D02*
X1592708Y31538D01*
G01X1543749Y27818D02*
X1547358Y28583D01*
G01X1543749Y26642D02*
X1547358Y27407D01*
G01Y28583D02*
X1553858Y27202D01*
G01X1547358Y27407D02*
X1553858Y26026D01*
G01Y27202D02*
X1558280Y28141D01*
G01X1553858Y26026D02*
X1558280Y26965D01*
G01Y28141D02*
X1562809Y27179D01*
G01X1558280Y26965D02*
X1562809Y26003D01*
G01Y27179D02*
X1567700Y28218D01*
G01X1562809Y26003D02*
X1567700Y27042D01*
G01Y28218D02*
X1572585Y27180D01*
G01X1567700Y27042D02*
X1572585Y26004D01*
G01Y27180D02*
X1577476Y28219D01*
G01X1572585Y26004D02*
X1577477Y27043D01*
G01X1577476Y28219D02*
X1581974Y27264D01*
G01X1577477Y27043D02*
X1581974Y26088D01*
G01Y27264D02*
X1587988Y28542D01*
G01X1581974Y26088D02*
X1587988Y27366D01*
G01Y28542D02*
X1593923Y27280D01*
G01X1587988Y27366D02*
X1593923Y26104D01*
G01X1543852Y30435D02*
X1547335Y31173D01*
G01X1543852Y29259D02*
X1547335Y29997D01*
G01Y31173D02*
X1553903Y29777D01*
G01X1547335Y29997D02*
X1553903Y28601D01*
G01Y29777D02*
X1558280Y30707D01*
G01X1553903Y28601D02*
X1558280Y29531D01*
G01Y30707D02*
X1562809Y29745D01*
G01X1558280Y29531D02*
X1562809Y28569D01*
G01Y29745D02*
X1567700Y30784D01*
G01X1562809Y28569D02*
X1567700Y29608D01*
G01Y30784D02*
X1572585Y29746D01*
G01X1567700Y29608D02*
X1572584Y28570D01*
G01X1572585Y29746D02*
X1577476Y30785D01*
G01X1572584Y28570D02*
X1577476Y29609D01*
G01Y30785D02*
X1581885Y29849D01*
G01X1577476Y29609D02*
X1581885Y28673D01*
G01Y29849D02*
X1587876Y31122D01*
G01X1581885Y28673D02*
X1587876Y29946D01*
G01Y31122D02*
X1592582Y30122D01*
G01X1587876Y29946D02*
X1592582Y28946D01*
G01X1543930Y31845D02*
X1547583Y32621D01*
G01Y33797D02*
X1554164Y32399D01*
G01X1547583Y32621D02*
X1554164Y31223D01*
G01Y32399D02*
X1558280Y33273D01*
G01X1554164Y31223D02*
X1558280Y32097D01*
G01Y33273D02*
X1562809Y32311D01*
G01X1558280Y32097D02*
X1562809Y31135D01*
G01Y32311D02*
X1567700Y33350D01*
G01X1562809Y31135D02*
X1567700Y32174D01*
G01Y33350D02*
X1572585Y32312D01*
G01X1567700Y32174D02*
X1572584Y31136D01*
G01X1572585Y32312D02*
X1577476Y33351D01*
G01X1572584Y31136D02*
X1577476Y32175D01*
G01Y33351D02*
X1581885Y32415D01*
G01X1577476Y32175D02*
X1581885Y31239D01*
G01Y32415D02*
X1588001Y33714D01*
G01X1581885Y31239D02*
X1588001Y32538D01*
G01D02*
X1592708Y31538D01*
G01X1588041Y39430D02*
X1595105Y40932D01*
G01Y42108D02*
X1588041Y40606D01*
G01X1583450Y40406D02*
X1588041Y39430D01*
G01Y40606D02*
X1583450Y41582D01*
G01X1580737Y39830D02*
X1583450Y40406D01*
G01Y41582D02*
X1580737Y41006D01*
G01X1569594Y42196D02*
X1580737Y39830D01*
G01Y41006D02*
X1569594Y43372D01*
G01X1556630Y39444D02*
X1569594Y42196D01*
G01Y43372D02*
X1556630Y40620D01*
G01X1541298Y42702D02*
X1556630Y39444D01*
G01Y40620D02*
X1541298Y43878D01*
G01X1530837Y40478D02*
X1541298Y42702D01*
G01Y43878D02*
X1530837Y41654D01*
G01X1541298Y43878D02*
X1530837Y41654D01*
G01Y40478D02*
X1541298Y42702D01*
G01X1556630Y40620D02*
X1541298Y43878D01*
G01Y42702D02*
X1556630Y39444D01*
G01X1569594Y43372D02*
X1556630Y40620D01*
G01Y39444D02*
X1569594Y42196D01*
G01X1580737Y41006D02*
X1569594Y43372D01*
G01Y42196D02*
X1580737Y39830D01*
G01X1583450Y41582D02*
X1580737Y41006D01*
G01Y39830D02*
X1583450Y40406D01*
G01X1588041Y40606D02*
X1583450Y41582D01*
G01Y40406D02*
X1588041Y39430D01*
G01X1595105Y42108D02*
X1588041Y40606D01*
G01Y39430D02*
X1595105Y40932D01*
G01X1588093Y42048D02*
X1595105Y43539D01*
G01Y44715D02*
X1588093Y43224D01*
G01X1583464Y43032D02*
X1588093Y42048D01*
G01Y43224D02*
X1583464Y44208D01*
G01X1580698Y42445D02*
X1583464Y43032D01*
G01Y44208D02*
X1580698Y43621D01*
G01X1569594Y44803D02*
X1580698Y42445D01*
G01Y43621D02*
X1569593Y45979D01*
G01X1556533Y42030D02*
X1569593Y44803D01*
G01Y45979D02*
X1556533Y43206D01*
G01X1541298Y45268D02*
X1556532Y42030D01*
G01X1556533Y43206D02*
X1541298Y46444D01*
G01X1531019Y43083D02*
X1541298Y45268D01*
G01Y46444D02*
X1531019Y44259D01*
G01X1541298Y46444D02*
X1531019Y44259D01*
G01Y43083D02*
X1541298Y45268D01*
G01X1556533Y43206D02*
X1541298Y46444D01*
G01Y45268D02*
X1556532Y42030D01*
G01X1569593Y45979D02*
X1556533Y43206D01*
G01Y42030D02*
X1569593Y44803D01*
G01X1580698Y43621D02*
X1569593Y45979D01*
G01X1569594Y44803D02*
X1580698Y42445D01*
G01X1583464Y44208D02*
X1580698Y43621D01*
G01Y42445D02*
X1583464Y43032D01*
G01X1588093Y43224D02*
X1583464Y44208D01*
G01Y43032D02*
X1588093Y42048D01*
G01X1595105Y44715D02*
X1588093Y43224D01*
G01Y42048D02*
X1595105Y43539D01*
G01X1543930Y33021D02*
X1547583Y33797D01*
G01X1588001Y33714D02*
X1592708Y32714D01*
G01X1592932Y34152D02*
X1588225Y35152D01*
G01X1592932Y35328D02*
X1588225Y36328D01*
G01Y35152D02*
X1581885Y33805D01*
G01X1588225Y36328D02*
X1581885Y34981D01*
G01Y33805D02*
X1577476Y34741D01*
G01X1581885Y34981D02*
X1577476Y35917D01*
G01Y34741D02*
X1572585Y33702D01*
G01X1577476Y35917D02*
X1572585Y34878D01*
G01Y33702D02*
X1567700Y34740D01*
G01X1572585Y34878D02*
X1567700Y35916D01*
G01Y34740D02*
X1562809Y33701D01*
G01X1567700Y35916D02*
X1562809Y34877D01*
G01Y33701D02*
X1558280Y34663D01*
G01X1562809Y34877D02*
X1558280Y35839D01*
G01Y34663D02*
X1554356Y33829D01*
G01X1558280Y35839D02*
X1554356Y35005D01*
G01Y33829D02*
X1547778Y35228D01*
G01X1554356Y35005D02*
X1547778Y36404D01*
G01Y35228D02*
X1544039Y34436D01*
G01X1547778Y36404D02*
X1544039Y35612D01*
G01X1543930Y33021D02*
X1547583Y33797D01*
G01X1588001Y33714D02*
X1592708Y32714D01*
G01X1592932Y35328D02*
X1588225Y36328D01*
G01X1592932Y34152D02*
X1588225Y35152D01*
G01Y36328D02*
X1581885Y34981D01*
G01X1588225Y35152D02*
X1581885Y33805D01*
G01Y34981D02*
X1577476Y35917D01*
G01X1581885Y33805D02*
X1577476Y34741D01*
G01Y35917D02*
X1572585Y34878D01*
G01X1577476Y34741D02*
X1572585Y33702D01*
G01Y34878D02*
X1567700Y35916D01*
G01X1572585Y33702D02*
X1567700Y34740D01*
G01Y35916D02*
X1562809Y34877D01*
G01X1567700Y34740D02*
X1562809Y33701D01*
G01Y34877D02*
X1558280Y35839D01*
G01X1562809Y33701D02*
X1558280Y34663D01*
G01Y35839D02*
X1554356Y35005D01*
G01X1558280Y34663D02*
X1554356Y33829D01*
G01Y35005D02*
X1547778Y36404D01*
G01X1554356Y33829D02*
X1547778Y35228D01*
G01Y36404D02*
X1544039Y35612D01*
G01X1547778Y35228D02*
X1544039Y34436D01*
G01X1588378Y44716D02*
X1595105Y46146D01*
G01Y47322D02*
X1588378Y45892D01*
G01X1583808Y45687D02*
X1588378Y44716D01*
G01Y45892D02*
X1583805Y46864D01*
G01X1580754Y45040D02*
X1583808Y45688D01*
G01X1583805Y46864D02*
X1580754Y46216D01*
G01X1569593Y47410D02*
X1580754Y45040D01*
G01Y46216D02*
X1569591Y48587D01*
G01X1556438Y44617D02*
X1569593Y47410D01*
G01X1569591Y48587D02*
X1556438Y45793D01*
G01X1541301Y47834D02*
X1556438Y44617D01*
G01Y45793D02*
X1541301Y49010D01*
G01X1530997Y45644D02*
X1541301Y47834D01*
G01Y49010D02*
X1530997Y46820D01*
G01X1588046Y47382D02*
X1594800Y48818D01*
G01Y49994D02*
X1588046Y48558D01*
G01X1583545Y48338D02*
X1588046Y47382D01*
G01Y48558D02*
X1583543Y49515D01*
G01X1580518Y47697D02*
X1583545Y48339D01*
G01X1583543Y49515D02*
X1580518Y48873D01*
G01X1569594Y50017D02*
X1580518Y47697D01*
G01Y48873D02*
X1569593Y51193D01*
G01X1556340Y47203D02*
X1569594Y50017D01*
G01X1569593Y51193D02*
X1556340Y48379D01*
G01X1541301Y50400D02*
X1556340Y47203D01*
G01Y48379D02*
X1541301Y51576D01*
G01X1531078Y48227D02*
X1541301Y50400D01*
G01Y51576D02*
X1531078Y49403D01*
G01X1531079Y50793D02*
X1541298Y52966D01*
G01X1531079Y51969D02*
X1541298Y54142D01*
G01Y52966D02*
X1556245Y49790D01*
G01X1541298Y54142D02*
X1556245Y50966D01*
G01Y49790D02*
X1569591Y52623D01*
G01X1556245Y50966D02*
X1569591Y53799D01*
G01Y52623D02*
X1580266Y50357D01*
G01X1569591Y53799D02*
X1580266Y51533D01*
G01Y50357D02*
X1583356Y51014D01*
G01X1580266Y51533D02*
X1583356Y52190D01*
G01Y51014D02*
X1588108Y50002D01*
G01X1583356Y52190D02*
X1588108Y51178D01*
G01Y50002D02*
X1594799Y51425D01*
G01X1588108Y51178D02*
X1594799Y52601D01*
G01X1588136Y52615D02*
X1594799Y54032D01*
G01Y55208D02*
X1588136Y53791D01*
G01X1583460Y53609D02*
X1588136Y52615D01*
G01Y53791D02*
X1583460Y54785D01*
G01X1580344Y52947D02*
X1583460Y53609D01*
G01Y54785D02*
X1580344Y54123D01*
G01X1569590Y55231D02*
X1580344Y52947D01*
G01Y54123D02*
X1569590Y56407D01*
G01X1556150Y52376D02*
X1569590Y55231D01*
G01Y56407D02*
X1556150Y53552D01*
G01X1541298Y55532D02*
X1556150Y52376D01*
G01Y53552D02*
X1541298Y56708D01*
G01X1531103Y53364D02*
X1541298Y55532D01*
G01Y56708D02*
X1531103Y54540D01*
G01X1541301Y49010D02*
X1530997Y46820D01*
G01Y45644D02*
X1541301Y47834D01*
G01X1556438Y45793D02*
X1541301Y49010D01*
G01Y47834D02*
X1556438Y44617D01*
G01X1569591Y48587D02*
X1556438Y45793D01*
G01Y44617D02*
X1569593Y47410D01*
G01X1580754Y46216D02*
X1569591Y48587D01*
G01X1569593Y47410D02*
X1580754Y45040D01*
G01X1583805Y46864D02*
X1580754Y46216D01*
G01Y45040D02*
X1583808Y45688D01*
G01X1588378Y45892D02*
X1583805Y46864D01*
G01X1583808Y45687D02*
X1588378Y44716D01*
G01X1595105Y47322D02*
X1588378Y45892D01*
G01Y44716D02*
X1595105Y46146D01*
G01X1541301Y51576D02*
X1531078Y49403D01*
G01Y48227D02*
X1541301Y50400D01*
G01X1556340Y48379D02*
X1541301Y51576D01*
G01Y50400D02*
X1556340Y47203D01*
G01X1569593Y51193D02*
X1556340Y48379D01*
G01Y47203D02*
X1569594Y50017D01*
G01X1580518Y48873D02*
X1569593Y51193D01*
G01X1569594Y50017D02*
X1580518Y47697D01*
G01X1583543Y49515D02*
X1580518Y48873D01*
G01Y47697D02*
X1583545Y48339D01*
G01X1588046Y48558D02*
X1583543Y49515D01*
G01X1583545Y48338D02*
X1588046Y47382D01*
G01X1594800Y49994D02*
X1588046Y48558D01*
G01Y47382D02*
X1594800Y48818D01*
G01X1531079Y51969D02*
X1541298Y54142D01*
G01X1531079Y50793D02*
X1541298Y52966D01*
G01Y54142D02*
X1556245Y50966D01*
G01X1541298Y52966D02*
X1556245Y49790D01*
G01Y50966D02*
X1569591Y53799D01*
G01X1556245Y49790D02*
X1569591Y52623D01*
G01Y53799D02*
X1580266Y51533D01*
G01X1569591Y52623D02*
X1580266Y50357D01*
G01Y51533D02*
X1583356Y52190D01*
G01X1580266Y50357D02*
X1583356Y51014D01*
G01Y52190D02*
X1588108Y51178D01*
G01X1583356Y51014D02*
X1588108Y50002D01*
G01Y51178D02*
X1594799Y52601D01*
G01X1588108Y50002D02*
X1594799Y51425D01*
G01X1541298Y56708D02*
X1531103Y54540D01*
G01Y53364D02*
X1541298Y55532D01*
G01X1556150Y53552D02*
X1541298Y56708D01*
G01Y55532D02*
X1556150Y52376D01*
G01X1569590Y56407D02*
X1556150Y53552D01*
G01Y52376D02*
X1569590Y55231D01*
G01X1580344Y54123D02*
X1569590Y56407D01*
G01Y55231D02*
X1580344Y52947D01*
G01X1583460Y54785D02*
X1580344Y54123D01*
G01Y52947D02*
X1583460Y53609D01*
G01X1588136Y53791D02*
X1583460Y54785D01*
G01Y53609D02*
X1588136Y52615D01*
G01X1594799Y55208D02*
X1588136Y53791D01*
G01Y52615D02*
X1594799Y54032D01*
G01X1541292Y59275D02*
X1531143Y57114D01*
G01Y55938D02*
X1541292Y58099D01*
G01X1556054Y56139D02*
X1541292Y59275D01*
G01Y58099D02*
X1556054Y54963D01*
G01X1569588Y59013D02*
X1556054Y56139D01*
G01Y54963D02*
X1569588Y57837D01*
G01X1580322Y56735D02*
X1569588Y59013D01*
G01Y57837D02*
X1580322Y55559D01*
G01X1583326Y57373D02*
X1580322Y56735D01*
G01Y55559D02*
X1583325Y56197D01*
G01X1588095Y56359D02*
X1583326Y57373D01*
G01Y56197D02*
X1588095Y55183D01*
G01X1594870Y57800D02*
X1588095Y56359D01*
G01Y55183D02*
X1594870Y56624D01*
G01X1588095Y55183D02*
X1594870Y56624D01*
G01Y57800D02*
X1588095Y56359D01*
G01X1583326Y56197D02*
X1588095Y55183D01*
G01Y56359D02*
X1583326Y57373D01*
G01X1580322Y55559D02*
X1583325Y56197D01*
G01X1583326Y57373D02*
X1580322Y56735D01*
G01X1569588Y57837D02*
X1580322Y55559D01*
G01Y56735D02*
X1569588Y59013D01*
G01X1556054Y54963D02*
X1569588Y57837D01*
G01Y59013D02*
X1556054Y56139D01*
G01X1541292Y58099D02*
X1556054Y54963D01*
G01Y56139D02*
X1541292Y59275D01*
G01X1531143Y55938D02*
X1541292Y58099D01*
G01Y59275D02*
X1531143Y57114D01*
G01X1541300Y61839D02*
X1531118Y59676D01*
G01Y58500D02*
X1541300Y60663D01*
G01X1555956Y58725D02*
X1541300Y61839D01*
G01Y60663D02*
X1555956Y57549D01*
G01X1569590Y61621D02*
X1555956Y58725D01*
G01Y57549D02*
X1569590Y60444D01*
G01X1580390Y59327D02*
X1569590Y61621D01*
G01Y60444D02*
X1580390Y58151D01*
G01X1583376Y59962D02*
X1580390Y59327D01*
G01Y58151D02*
X1583377Y58786D01*
G01X1588075Y58961D02*
X1583376Y59962D01*
G01X1583377Y58785D02*
X1588075Y57785D01*
G01X1594869Y60407D02*
X1588075Y58961D01*
G01Y57785D02*
X1594869Y59231D01*
G01X1588075Y57785D02*
X1594869Y59231D01*
G01Y60407D02*
X1588075Y58961D01*
G01X1583377Y58785D02*
X1588075Y57785D01*
G01Y58961D02*
X1583376Y59962D01*
G01X1580390Y58151D02*
X1583377Y58786D01*
G01X1583376Y59962D02*
X1580390Y59327D01*
G01X1569590Y60444D02*
X1580390Y58151D01*
G01Y59327D02*
X1569590Y61621D01*
G01X1555956Y57549D02*
X1569590Y60444D01*
G01Y61621D02*
X1555956Y58725D01*
G01X1541300Y60663D02*
X1555956Y57549D01*
G01Y58725D02*
X1541300Y61839D01*
G01X1531118Y58500D02*
X1541300Y60663D01*
G01Y61839D02*
X1531118Y59676D01*
G01X1583824Y69319D02*
X1588822Y68257D01*
G01X1588827Y67080D02*
X1583371Y68239D01*
G01X1577209Y73699D02*
X1583824Y69319D01*
G01X1583371Y68239D02*
X1576760Y72616D01*
G01X1575258Y74095D02*
X1577209Y73699D01*
G01X1576760Y72616D02*
X1575258Y72921D01*
G01X1566875Y72390D02*
X1575258Y74095D01*
G01Y72921D02*
X1567324Y71307D01*
G01X1562857Y69731D02*
X1566875Y72390D01*
G01X1567324Y71307D02*
X1565192Y69897D01*
G01X1562857Y69731D02*
X1566875Y72390D01*
G01X1565192Y69897D02*
X1563492Y68772D01*
G01X1559131Y68985D02*
X1562857Y69731D01*
G01X1563322Y68602D02*
X1563082D01*
G01X1559131Y68985D02*
X1562857Y69731D01*
G01X1563082Y68602D02*
X1559131Y67812D01*
G01X1544515Y71910D02*
X1559131Y68986D01*
G01Y67812D02*
X1544523Y70735D01*
G01X1530132Y68840D02*
X1544515Y71910D01*
G01X1544523Y70735D02*
X1530130Y67663D01*
G01X1544523Y70735D02*
X1530130Y67663D01*
G01X1530132Y68840D02*
X1544515Y71910D01*
G01X1559131Y67812D02*
X1544523Y70735D01*
G01X1544515Y71910D02*
X1559131Y68986D01*
G01X1563322Y68602D02*
X1563082D01*
G01D02*
X1559131Y67812D01*
G01Y68985D02*
X1562857Y69731D01*
G01X1567324Y71307D02*
X1565192Y69897D01*
G01D02*
X1563492Y68772D01*
G01X1562857Y69731D02*
X1566875Y72390D01*
G01X1575258Y72921D02*
X1567324Y71307D01*
G01X1566875Y72390D02*
X1575258Y74095D01*
G01X1576760Y72616D02*
X1575258Y72921D01*
G01Y74095D02*
X1577209Y73699D01*
G01X1583371Y68239D02*
X1576760Y72616D01*
G01X1577209Y73699D02*
X1583824Y69319D01*
G01X1588827Y67080D02*
X1583371Y68239D01*
G01X1583824Y69319D02*
X1588822Y68257D01*
G01X1588492Y65617D02*
X1604225Y68960D01*
G01X1604161Y67770D02*
X1588492Y64441D01*
G01X1581105Y67185D02*
X1588492Y65617D01*
G01Y64441D02*
X1581065Y66017D01*
G01X1577457Y66666D02*
X1581105Y67185D01*
G01X1581065Y66017D02*
X1577417Y65498D01*
G01X1569294Y68400D02*
X1577457Y66666D01*
G01X1577417Y65498D02*
X1569294Y67224D01*
G01X1558725Y66154D02*
X1569294Y68400D01*
G01Y67224D02*
X1558725Y64978D01*
G01X1544132Y69255D02*
X1558725Y66154D01*
G01Y64978D02*
X1544132Y68079D01*
G01X1530057Y66262D02*
X1544132Y69255D01*
G01Y68079D02*
X1530054Y65085D01*
G01X1544132Y68079D02*
X1530054Y65085D01*
G01X1530057Y66262D02*
X1544132Y69255D01*
G01X1558725Y64978D02*
X1544132Y68079D01*
G01Y69255D02*
X1558725Y66154D01*
G01X1569294Y67224D02*
X1558725Y64978D01*
G01Y66154D02*
X1569294Y68400D01*
G01X1577417Y65498D02*
X1569294Y67224D01*
G01Y68400D02*
X1577457Y66666D01*
G01X1581065Y66017D02*
X1577417Y65498D01*
G01X1577457Y66666D02*
X1581105Y67185D01*
G01X1588492Y64441D02*
X1581065Y66017D01*
G01X1581105Y67185D02*
X1588492Y65617D01*
G01X1604161Y67770D02*
X1588492Y64441D01*
G01Y65617D02*
X1604225Y68960D01*
G01X1586547Y87524D02*
X1592638D01*
G01X1592775Y86374D02*
X1587024D01*
G01X1585140Y86117D02*
X1586547Y87524D01*
G01X1587024Y86374D02*
X1585875Y85224D01*
G01X1577749Y81157D02*
X1585140Y86117D01*
G01X1585875Y85224D02*
X1578199Y80074D01*
G01X1574916Y80591D02*
X1577749Y81157D01*
G01X1578199Y80074D02*
X1574937Y79422D01*
G01X1564499Y82277D02*
X1574916Y80591D01*
G01X1574937Y79422D02*
X1564521Y81108D01*
G01X1556832Y80743D02*
X1564499Y82277D01*
G01X1564521Y81108D02*
X1560802Y80365D01*
G01X1556832Y80743D02*
X1564499Y82277D01*
G01X1560802Y80364D02*
X1557083Y79620D01*
G01X1530191Y74176D02*
X1556832Y80743D01*
G01X1557083Y79620D02*
X1530207Y72995D01*
G01X1557083Y79620D02*
X1530207Y72995D01*
G01X1530191Y74176D02*
X1556832Y80743D01*
G01X1564521Y81108D02*
X1560802Y80365D01*
G01Y80364D02*
X1557083Y79620D01*
G01X1556832Y80743D02*
X1564499Y82277D01*
G01X1574937Y79422D02*
X1564521Y81108D01*
G01X1564499Y82277D02*
X1574916Y80591D01*
G01X1578199Y80074D02*
X1574937Y79422D01*
G01X1574916Y80591D02*
X1577749Y81157D01*
G01X1585875Y85224D02*
X1578199Y80074D01*
G01X1577749Y81157D02*
X1585140Y86117D01*
G01X1587024Y86374D02*
X1585875Y85224D01*
G01X1585140Y86117D02*
X1586547Y87524D01*
G01X1592775Y86374D02*
X1587024D01*
G01X1586547Y87524D02*
X1592638D01*
G01X1541161Y65064D02*
X1530925Y62890D01*
G01Y61714D02*
X1541161Y63888D01*
G01X1555172Y62086D02*
X1549939Y63198D01*
G01X1547347Y63749D02*
X1546026Y64030D01*
G01X1543434Y64581D02*
X1541161Y65064D01*
G01Y63888D02*
X1555172Y60910D01*
G01X1569592Y65148D02*
X1555172Y62086D01*
G01Y60910D02*
X1569592Y63972D01*
G01X1578578Y63239D02*
X1569592Y65148D01*
G01Y63972D02*
X1578579Y62063D01*
G01X1581076Y63772D02*
X1578578Y63239D01*
G01X1578579Y62063D02*
X1581082Y62597D01*
G01X1588065Y62350D02*
X1581076Y63772D01*
G01X1581082Y62597D02*
X1588065Y61176D01*
G01X1599862Y64750D02*
X1588065Y62350D01*
G01Y61176D02*
X1599978Y63600D01*
G01X1588065Y61176D02*
X1599978Y63600D01*
G01X1599862Y64750D02*
X1588065Y62350D01*
G01X1581082Y62597D02*
X1588065Y61176D01*
G01Y62350D02*
X1581076Y63772D01*
G01X1578579Y62063D02*
X1581082Y62597D01*
G01X1581076Y63772D02*
X1578578Y63239D01*
G01X1569592Y63972D02*
X1578579Y62063D01*
G01X1578578Y63239D02*
X1569592Y65148D01*
G01X1555172Y60910D02*
X1569592Y63972D01*
G01Y65148D02*
X1555172Y62086D01*
G01X1541161Y63888D02*
X1555172Y60910D01*
G01Y62086D02*
X1549939Y63198D01*
G01X1541161Y63888D02*
X1555172Y60910D01*
G01X1547347Y63749D02*
X1546026Y64030D01*
G01X1541161Y63888D02*
X1555172Y60910D01*
G01X1543434Y64581D02*
X1541161Y65064D01*
G01X1530925Y61714D02*
X1541161Y63888D01*
G01Y65064D02*
X1530925Y62890D01*
G01X1592531Y90487D02*
X1581170D01*
G01X1592668Y89337D02*
X1581325D01*
G01X1581170Y90487D02*
X1555431Y83570D01*
G01X1552872Y82882D02*
X1545578Y80922D01*
G01X1581325Y89337D02*
X1545517Y79714D01*
G01X1545578Y80922D02*
X1530201Y86782D01*
G01X1545517Y79714D02*
X1530123Y85581D01*
G01X1592668Y89337D02*
X1581325D01*
G01X1592531Y90487D02*
X1581170D01*
G01X1581325Y89337D02*
X1545517Y79714D01*
G01X1581170Y90487D02*
X1555431Y83570D01*
G01X1581325Y89337D02*
X1545517Y79714D01*
G01X1552872Y82882D02*
X1545578Y80922D01*
G01X1545517Y79714D02*
X1530123Y85581D01*
G01X1545578Y80922D02*
X1530201Y86782D01*
G01X1530148Y71434D02*
X1554566Y77453D01*
G01X1530164Y70253D02*
X1554831Y76333D01*
G01X1554566Y77453D02*
X1564298Y79661D01*
G01X1554831Y76333D02*
X1564338Y78490D01*
G01X1554566Y77453D02*
X1564298Y79661D01*
G01D02*
X1565192Y79521D01*
G01D02*
X1575498Y77912D01*
G01X1564338Y78490D02*
X1565192Y78357D01*
G01Y79521D02*
X1575498Y77912D01*
G01X1565192Y78357D02*
X1575523Y76744D01*
G01X1575498Y77912D02*
X1584683Y79749D01*
G01X1587282Y80269D02*
X1588606Y80534D01*
G01X1575523Y76744D02*
X1598278Y81295D01*
G01X1530164Y70253D02*
X1554831Y76333D01*
G01X1530148Y71434D02*
X1554566Y77453D01*
G01X1554831Y76333D02*
X1564338Y78490D01*
G01D02*
X1565192Y78357D01*
G01X1554566Y77453D02*
X1564298Y79661D01*
G01X1564338Y78490D02*
X1565192Y78357D01*
G01X1564298Y79661D02*
X1565192Y79521D01*
G01X1564338Y78490D02*
X1565192Y78357D01*
G01D02*
X1575523Y76744D01*
G01X1565192Y79521D02*
X1575498Y77912D01*
G01X1575523Y76744D02*
X1598278Y81295D01*
G01X1575498Y77912D02*
X1584683Y79749D01*
G01X1575523Y76744D02*
X1598278Y81295D01*
G01X1587282Y80269D02*
X1588606Y80534D01*
G01X1575523Y76744D02*
X1598278Y81295D01*
G01X1560425Y96363D02*
X1557056Y93344D01*
G01X1564019Y98038D02*
X1557635Y92317D01*
G01X1557056Y93344D02*
X1554161Y92462D01*
G01D02*
X1554156Y92463D01*
G01X1557635Y92317D02*
X1554228Y91280D01*
G01X1554161Y92462D02*
X1554156Y92463D01*
G01D02*
X1551448Y93088D01*
G01X1554198Y91273D02*
X1553902Y91341D01*
G01X1554156Y92463D02*
X1551448Y93088D01*
G01X1553902Y91341D02*
X1553898Y91342D01*
G01X1554161Y92462D02*
X1554156Y92463D01*
G01D02*
X1551448Y93088D01*
G01X1553898Y91342D02*
X1551002Y92010D01*
G01X1551448Y93088D02*
X1547582Y95505D01*
G01X1551002Y92010D02*
X1547135Y94427D01*
G01D02*
X1544785Y94970D01*
G01D02*
X1542068Y94343D01*
G01D02*
X1537930Y95299D01*
G01D02*
X1527235Y89626D01*
G01X1564019Y98038D02*
X1557635Y92317D01*
G01X1564019Y98038D02*
X1557635Y92317D01*
G01X1564019Y98038D02*
X1557635Y92317D01*
G01X1560425Y96363D02*
X1557056Y93344D01*
G01X1557635Y92317D02*
X1554228Y91280D01*
G01X1557056Y93344D02*
X1554161Y92462D01*
G01X1557635Y92317D02*
X1554228Y91280D01*
G01X1554198Y91273D02*
X1553902Y91341D01*
G01X1553898Y91342D02*
X1551002Y92010D01*
G01X1554161Y92462D02*
X1554156Y92463D01*
G01X1554198Y91273D02*
X1553902Y91341D01*
G01D02*
X1553898Y91342D01*
G01D02*
X1551002Y92010D01*
G01X1554156Y92463D02*
X1551448Y93088D01*
G01X1551002Y92010D02*
X1547135Y94427D01*
G01X1551448Y93088D02*
X1547582Y95505D01*
G01X1547135Y94427D02*
X1544785Y94970D01*
G01D02*
X1542068Y94343D01*
G01D02*
X1537930Y95299D01*
G01D02*
X1527235Y89626D01*
G01X1537930Y95299D02*
X1527235Y89626D01*
G01X1596607Y100704D02*
X1587290Y103816D01*
G01X1596420Y99554D02*
X1587101Y102666D01*
G01X1587290Y103816D02*
X1579348D01*
G01X1587101Y102666D02*
X1579589D01*
G01X1579348Y103816D02*
X1573758Y101371D01*
G01X1579589Y102666D02*
X1573999Y100221D01*
G01X1573758Y101371D02*
X1569305D01*
G01X1573999Y100221D02*
X1569525D01*
G01X1569305Y101371D02*
X1563404Y99032D01*
G01X1569525Y100221D02*
X1564019Y98038D01*
G01X1563404Y99032D02*
X1562399Y98131D01*
G01D02*
X1561481Y98181D01*
G01X1547582Y95505D02*
X1544785Y96151D01*
G01D02*
X1542068Y95524D01*
G01D02*
X1537770Y96517D01*
G01D02*
X1536577Y95884D01*
G01X1596420Y99554D02*
X1587101Y102666D01*
G01X1596607Y100704D02*
X1587290Y103816D01*
G01X1587101Y102666D02*
X1579589D01*
G01X1587290Y103816D02*
X1579348D01*
G01X1579589Y102666D02*
X1573999Y100221D01*
G01X1579348Y103816D02*
X1573758Y101371D01*
G01X1573999Y100221D02*
X1569525D01*
G01X1573758Y101371D02*
X1569305D01*
G01X1569525Y100221D02*
X1564019Y98038D01*
G01X1569305Y101371D02*
X1563404Y99032D01*
G01D02*
X1562399Y98131D01*
G01D02*
X1561481Y98181D01*
G01X1547582Y95505D02*
X1544785Y96151D01*
G01D02*
X1542068Y95524D01*
G01D02*
X1537770Y96517D01*
G01D02*
X1536577Y95884D01*
G01X1594817Y534616D02*
X1584163Y523962D01*
G01X1594003Y535430D02*
X1583348Y524775D01*
G01X1584163Y523962D02*
G02X1583032Y523492I-1133J1131D01*
G01X1583348Y524775D02*
G02X1583030Y524642I-319J317D01*
G01X1583032Y523492D02*
X1540353D01*
G01X1583030Y524642D02*
X1540353D01*
G01Y523492D02*
G03X1540035Y523359I1J-450D01*
G01X1540353Y524642D02*
G03X1539221Y524173I0J-1601D01*
G01X1594003Y535430D02*
X1583348Y524775D01*
G01X1594817Y534616D02*
X1584163Y523962D01*
G01X1583348Y524775D02*
G02X1583030Y524642I-319J317D01*
G01X1584163Y523962D02*
G02X1583032Y523492I-1133J1131D01*
G01X1583030Y524642D02*
X1540353D01*
G01X1583032Y523492D02*
X1540353D01*
G01Y524642D02*
G03X1539221Y524173I0J-1601D01*
G01X1540353Y523492D02*
G03X1540035Y523359I1J-450D01*
G01X1538673Y526488D02*
G02X1538993Y526620I319J-320D01*
G01X1537860Y527302D02*
G02X1538993Y527770I1132J-1134D01*
G01Y526620D02*
X1581298D01*
G01X1538993Y527770D02*
X1581298D01*
G01Y526620D02*
G03X1583214Y527415I3J2700D01*
G01X1581298Y527770D02*
G03X1582398Y528227I1J1550D01*
G01X1583214Y527415D02*
X1593494Y537695D01*
G01X1582398Y528227D02*
X1592680Y538509D01*
G01X1589858Y543433D02*
G03X1586852Y540426I-1503J-1504D01*
G01X1589045Y542619D02*
G03X1587666Y541240I-689J-690D01*
G01X1586852Y540426D02*
X1587836Y539442D01*
G01X1587666Y541240D02*
X1588650Y540256D01*
G01X1587836Y539442D02*
G02Y538064I-688J-689D01*
G01X1588650Y540256D02*
G02Y537250I-1502J-1503D01*
G01X1587836Y538064D02*
X1580809Y531036D01*
G01X1588650Y537250D02*
X1581622Y530222D01*
G01X1580809Y531036D02*
G02X1580456Y530890I-353J354D01*
G01X1581622Y530222D02*
G02X1580457Y529740I-1166J1168D01*
G01X1580456Y530890D02*
X1537933D01*
G01X1580457Y529740D02*
X1537935D01*
G01X1537933Y530890D02*
G03X1536412Y530260I0J-2150D01*
G01X1537935Y529740D02*
G03X1537228Y529447I0J-1000D01*
G01X1527602Y533233D02*
G02X1529589Y534056I1987J-1987D01*
G01D02*
X1572780D01*
G01X1529589Y535206D02*
X1572780D01*
G01Y534056D02*
G03X1575305Y535102I0J3571D01*
G01X1572780Y535206D02*
G03X1574491Y535916I-1J2420D01*
G01X1575305Y535102D02*
X1585551Y545348D01*
G01X1574491Y535916D02*
X1584737Y546162D01*
G01X1585551Y545348D02*
G02X1587731Y546252I2181J-2180D01*
G01X1584737Y546162D02*
G02X1587731Y547402I2994J-2995D01*
G01Y546252D02*
X1609717D01*
G01X1587731Y547402D02*
X1609718D01*
G01X1587985Y565789D02*
G02X1588252Y566430I906J-1D01*
G01X1588330Y566508D02*
G02X1588971Y566775I642J-639D01*
G01Y567925D02*
G03X1587516Y567322I0J-2057D01*
G01X1587985Y565789D02*
G02X1588252Y566430I906J-1D01*
G01X1588330Y566508D02*
G02X1588971Y566775I642J-639D01*
G01X1587438Y567244D02*
G03X1586835Y565789I1454J-1455D01*
G01X1587985Y554993D02*
Y565789D01*
G01X1586835D02*
Y554994D01*
G01X1586958Y552515D02*
G03X1587985Y554993I-2478J2479D01*
G01X1586835Y554994D02*
G02X1586144Y553329I-2355J1D01*
G01X1576017Y541574D02*
X1577038Y542595D01*
G01X1579831Y545388D02*
X1581026Y546583D01*
G01X1583819Y549376D02*
X1586958Y552515D01*
G01X1586144Y553329D02*
X1575203Y542388D01*
G01X1573663Y540600D02*
G03X1576017Y541574I1J3328D01*
G01X1575203Y542388D02*
G02X1573663Y541750I-1540J1540D01*
G01X1571141Y540600D02*
X1573663D01*
G01Y541750D02*
X1571141D01*
G01X1570116Y539575D02*
G02X1571141Y540600I1025J0D01*
G01Y541750D02*
G03X1568966Y539575I0J-2175D01*
G01X1570116Y539453D02*
Y539575D01*
G01X1568966D02*
Y539453D01*
G01X1565766D02*
G03X1570116I2175J0D01*
G01X1568966D02*
G02X1566916I-1025J0D01*
G01X1565766Y539575D02*
Y539453D01*
G01X1566916D02*
Y539575D01*
G01X1563716D02*
G02X1565766I1025J0D01*
G01X1566916D02*
G03X1562566I-2175J0D01*
G01X1563716Y539453D02*
Y539575D01*
G01X1562566D02*
Y539453D01*
G01X1559366D02*
G03X1563716I2175J0D01*
G01X1562566D02*
G02X1560516I-1025J0D01*
G01X1559366Y539575D02*
Y539453D01*
G01X1560516D02*
Y539575D01*
G01X1557316D02*
G02X1559366I1025J0D01*
G01X1560516D02*
G03X1556166I-2175J0D01*
G01X1557316Y539453D02*
Y539575D01*
G01X1556166D02*
Y539453D01*
G01X1552966D02*
G03X1557316I2175J0D01*
G01X1556166D02*
G02X1554116I-1025J0D01*
G01X1552966Y539575D02*
Y539453D01*
G01X1554116D02*
Y539575D01*
G01X1550916D02*
G02X1552966I1025J0D01*
G01X1554116D02*
G03X1549766I-2175J0D01*
G01X1550916Y539453D02*
Y539575D01*
G01X1549766D02*
Y539453D01*
G01X1546566D02*
G03X1550916I2175J0D01*
G01X1549766D02*
G02X1547716I-1025J0D01*
G01X1544516D02*
G02X1546566I1025J0D01*
G01X1547716D02*
G03X1543366I-2175J0D01*
G01X1540166D02*
G03X1544516I2175J0D01*
G01X1543366D02*
G02X1541316I-1025J0D01*
G01X1540166Y539575D02*
Y539453D01*
G01X1541316D02*
Y539575D01*
G01X1538116D02*
G02X1540166I1025J0D01*
G01X1541316D02*
G03X1536966I-2175J0D01*
G01X1538116Y539373D02*
Y539575D01*
G01X1536966D02*
Y539374D01*
G01X1533766Y539453D02*
G03X1535980Y537239I2214J0D01*
G01X1535982D02*
G03X1538116Y539373I0J2134D01*
G01X1536966Y539374D02*
G02X1535981Y538389I-985J0D01*
G01X1533766Y539453D02*
G03X1535980Y537239I2214J0D01*
G01X1535982D02*
G03X1538116Y539373I0J2134D01*
G01X1535980Y538389D02*
G02X1534916Y539453I0J1064D01*
G01X1533766Y539575D02*
Y539453D01*
G01X1534916D02*
Y539575D01*
G01X1532741Y540600D02*
G02X1533766Y539575I0J-1025D01*
G01X1534916D02*
G03X1532741Y541750I-2175J0D01*
G01X1530997Y540600D02*
X1532741D01*
G01Y541750D02*
X1530996D01*
G01X1530199Y540269D02*
G02X1530997Y540600I799J-798D01*
G01X1530996Y541750D02*
G03X1529385Y541083I0J-2279D01*
G01X1543006Y546979D02*
G03X1545256Y549229I0J2250D01*
G01X1543006Y548129D02*
G03X1544106Y549229I0J1100D01*
G01X1545256D02*
Y550765D01*
G01X1544106Y549229D02*
Y550765D01*
G01X1545256D02*
G02X1547306I1025J0D01*
G01X1544106D02*
G02X1548456I2175J0D01*
G01X1547306D02*
Y549154D01*
G01X1548456Y550765D02*
Y549154D01*
G01X1547306D02*
G03X1551656I2175J0D01*
G01X1548456D02*
G03X1550506I1025J0D01*
G01X1551656D02*
Y550765D01*
G01X1550506Y549154D02*
Y550765D01*
G01X1551656D02*
G02X1553706I1025J0D01*
G01X1550506D02*
G02X1554856I2175J0D01*
G01X1553706D02*
Y549154D01*
G01X1554856Y550765D02*
Y549154D01*
G01X1553706D02*
G03X1558056I2175J0D01*
G01X1554856D02*
G03X1556906I1025J0D01*
G01X1558056D02*
Y550765D01*
G01X1556906Y549154D02*
Y550765D01*
G01X1558056D02*
G02X1560106I1025J0D01*
G01X1556906D02*
G02X1561256I2175J0D01*
G01X1560106D02*
Y549154D01*
G01X1561256Y550765D02*
Y549154D01*
G01X1560106D02*
G03X1564456I2175J0D01*
G01X1561256D02*
G03X1563306I1025J0D01*
G01X1564456D02*
Y550765D01*
G01X1563306Y549154D02*
Y550765D01*
G01X1564456D02*
G02X1566506I1025J0D01*
G01X1563306D02*
G02X1567656I2175J0D01*
G01X1566506D02*
Y549192D01*
G01X1567656Y550765D02*
Y549192D01*
G01X1566506D02*
G03X1568719Y546979I2213J0D01*
G01X1567656Y549192D02*
G03X1568719Y548129I1063J0D01*
G01Y546979D02*
X1570065D01*
G01X1568719Y548129D02*
X1570065D01*
G01Y546979D02*
G03X1571734Y547669I1J2360D01*
G01X1570065Y548129D02*
G03X1570921Y548483I1J1210D01*
G01X1571736Y547671D02*
G03X1572846Y550348I-2678J2679D01*
G01X1570922Y548485D02*
G03X1571696Y550349I-1863J1866D01*
G01X1572846Y550348D02*
Y553963D01*
G01X1571696Y550349D02*
Y553964D01*
G01X1572846Y553963D02*
G02X1573276Y554998I1464J-1D01*
G01X1571696Y553964D02*
G02X1572463Y555812I2614J-2D01*
G01X1573276Y554998D02*
X1574357Y556079D01*
G01X1572463Y555812D02*
X1573543Y556893D01*
G01X1574357Y556079D02*
G03X1575360Y558499I-2420J2421D01*
G01X1573543Y556893D02*
G03X1574210Y558500I-1606J1608D01*
G01X1575360Y558499D02*
Y561807D01*
G01Y565757D02*
Y567107D01*
G01Y571057D02*
Y572407D01*
G01X1574210Y558500D02*
Y572408D01*
G01X1575360Y572407D02*
G02X1575909Y573730I1872J-1D01*
G01X1574210Y572408D02*
G02X1575095Y574544I3023J-1D01*
G01X1575909Y573730D02*
X1577002Y574823D01*
G01X1575095Y574544D02*
X1576188Y575637D01*
G01X1577002Y574823D02*
G02X1578243Y575337I1241J-1241D01*
G01X1576188Y575637D02*
G02X1578243Y576487I2054J-2056D01*
G01Y575337D02*
X1581271D01*
G01X1578243Y576487D02*
X1581271D01*
G01Y575337D02*
G02X1582613Y574781I0J-1898D01*
G01X1581271Y576487D02*
G02X1583427Y575595I1J-3048D01*
G01X1582613Y574781D02*
X1583507Y573887D01*
G01X1583427Y575595D02*
X1584321Y574701D01*
G01X1583507Y573887D02*
G03X1585426Y573093I1918J1919D01*
G01X1584321Y574701D02*
G03X1585425Y574243I1105J1104D01*
G01X1585426Y573093D02*
X1593199D01*
G01X1585425Y574243D02*
X1593199D01*
G01X1572304Y543810D02*
X1550543D01*
G01X1546593D02*
X1544096D01*
G01X1540146D02*
X1527166D01*
G01Y544960D02*
X1572304D01*
G01X1574026Y544522D02*
G02X1572304Y543810I-1721J1723D01*
G01Y544960D02*
G03X1573212Y545336I0J1284D01*
G01X1577806Y548302D02*
X1574026Y544522D01*
G01X1573212Y545336D02*
X1576992Y549116D01*
G01X1577806Y551380D02*
G02Y548302I-1539J-1539D01*
G01X1576992Y549116D02*
G03Y550566I-725J725D01*
G01X1576673Y552513D02*
X1577806Y551380D01*
G01X1576992Y550566D02*
X1575859Y551699D01*
G01X1578123Y553964D02*
G03X1576676I-723J-724D01*
G01X1576673Y553961D02*
G03Y552513I724J-724D01*
G01X1575859Y551699D02*
G02Y554775I1538J1538D01*
G01X1578123Y553964D02*
G03X1576676I-723J-724D01*
G01X1576673Y553961D02*
G03Y552513I724J-724D01*
G01X1575862Y554778D02*
G02X1578937I1538J-1538D01*
G01X1579204Y552883D02*
X1578123Y553964D01*
G01X1578937Y554778D02*
X1580018Y553697D01*
G01X1582388Y552883D02*
G02X1579204I-1592J1592D01*
G01X1580018Y553697D02*
G03X1581574I778J778D01*
G01X1583402Y553897D02*
X1582388Y552883D01*
G01X1581574Y553697D02*
X1582588Y554711D01*
G01X1584865Y557432D02*
G02X1583402Y553897I-4999J-1D01*
G01X1582588Y554711D02*
G03X1583715Y557432I-2721J2721D01*
G01X1584865Y567841D02*
Y557432D01*
G01X1583715D02*
Y567841D01*
G01X1585361Y569036D02*
G03X1584865Y567841I1195J-1196D01*
G01X1583715D02*
G02X1584547Y569850I2842J0D01*
G01X1585706Y569381D02*
X1585361Y569036D01*
G01X1584547Y569850D02*
X1584892Y570195D01*
G01X1586975Y569908D02*
G03X1585706Y569381I1J-1795D01*
G01X1584892Y570195D02*
G02X1586975Y571058I2083J-2082D01*
G01X1592163Y569908D02*
X1586975D01*
G01Y571058D02*
X1592163D01*
G01X1537284Y550079D02*
G03X1540719Y551501I1J4856D01*
G01X1537284Y551229D02*
G03X1539905Y552315I0J3706D01*
G01X1540719Y551501D02*
X1543555Y554337D01*
G01X1539905Y552315D02*
X1542741Y555151D01*
G01X1543555Y554337D02*
G02X1545073Y554967I1519J-1517D01*
G01X1542741Y555151D02*
G02X1545073Y556117I2332J-2332D01*
G01Y554967D02*
X1547683D01*
G01X1551633D02*
X1554002D01*
G01X1557952D02*
X1560287D01*
G01X1564237D02*
X1566956D01*
G01X1545073Y556117D02*
X1566956D01*
G01Y554967D02*
G03X1569999Y556226I1J4304D01*
G01X1566956Y556117D02*
G03X1569185Y557040I0J3153D01*
G01X1569999Y556226D02*
X1570982Y557209D01*
G01X1569185Y557040D02*
X1570168Y558023D01*
G01X1570982Y557209D02*
G03X1572004Y559679I-2470J2469D01*
G01X1570168Y558023D02*
G03X1570853Y559679I-1657J1655D01*
G01X1572004D02*
Y573747D01*
G01X1570854Y559678D02*
Y573748D01*
G01X1572004Y573747D02*
G02X1572840Y575763I2851J-1D01*
G01X1570854Y573748D02*
G02X1572026Y576577I4001J0D01*
G01X1572840Y575763D02*
X1575147Y578070D01*
G01X1572026Y576577D02*
X1574333Y578884D01*
G01X1575147Y578070D02*
G02X1576573Y578662I1427J-1425D01*
G01X1574333Y578884D02*
G02X1576572Y579812I2240J-2239D01*
G01X1576573Y578662D02*
X1583036D01*
G01X1576572Y579812D02*
X1583037D01*
G01X1583036Y578662D02*
G02X1583815Y578338I-1J-1101D01*
G01X1583037Y579812D02*
G02X1584629Y579152I-1J-2252D01*
G01X1583815Y578338D02*
X1585284Y576869D01*
G01X1584629Y579152D02*
X1586098Y577683D01*
G01X1585284Y576869D02*
G03X1586877Y576210I1592J1592D01*
G01X1586098Y577683D02*
G03X1586877Y577360I779J778D01*
G01Y576210D02*
X1592965D01*
G01X1586877Y577360D02*
X1592965D01*
G01X1537860Y527302D02*
G02X1538993Y527770I1132J-1134D01*
G01X1538673Y526488D02*
G02X1538993Y526620I319J-320D01*
G01Y527770D02*
X1581298D01*
G01X1538993Y526620D02*
X1581298D01*
G01Y527770D02*
G03X1582398Y528227I1J1550D01*
G01X1581298Y526620D02*
G03X1583214Y527415I3J2700D01*
G01X1582398Y528227D02*
X1592680Y538509D01*
G01X1583214Y527415D02*
X1593494Y537695D01*
G01X1589045Y542619D02*
G03X1587666Y541240I-689J-690D01*
G01X1589858Y543433D02*
G03X1586852Y540426I-1503J-1504D01*
G01X1587666Y541240D02*
X1588650Y540256D01*
G01X1586852Y540426D02*
X1587836Y539442D01*
G01X1588650Y540256D02*
G02Y537250I-1502J-1503D01*
G01X1587836Y539442D02*
G02Y538064I-688J-689D01*
G01X1588650Y537250D02*
X1581622Y530222D01*
G01X1587836Y538064D02*
X1580809Y531036D01*
G01X1581622Y530222D02*
G02X1580457Y529740I-1166J1168D01*
G01X1580809Y531036D02*
G02X1580456Y530890I-353J354D01*
G01X1580457Y529740D02*
X1537935D01*
G01X1580456Y530890D02*
X1537933D01*
G01X1537935Y529740D02*
G03X1537228Y529447I0J-1000D01*
G01X1537933Y530890D02*
G03X1536412Y530260I0J-2150D01*
G01X1527602Y533233D02*
G02X1529589Y534056I1987J-1987D01*
G01Y535206D02*
X1572780D01*
G01X1529589Y534056D02*
X1572780D01*
G01Y535206D02*
G03X1574491Y535916I-1J2420D01*
G01X1572780Y534056D02*
G03X1575305Y535102I0J3571D01*
G01X1574491Y535916D02*
X1584737Y546162D01*
G01X1575305Y535102D02*
X1585551Y545348D01*
G01X1584737Y546162D02*
G02X1587731Y547402I2994J-2995D01*
G01X1585551Y545348D02*
G02X1587731Y546252I2181J-2180D01*
G01Y547402D02*
X1609718D01*
G01X1587731Y546252D02*
X1609717D01*
G01X1530996Y541750D02*
G03X1529385Y541083I0J-2279D01*
G01X1530199Y540269D02*
G02X1530997Y540600I799J-798D01*
G01X1532741Y541750D02*
X1530996D01*
G01X1530997Y540600D02*
X1532741D01*
G01X1534916Y539575D02*
G03X1532741Y541750I-2175J0D01*
G01Y540600D02*
G02X1533766Y539575I0J-1025D01*
G01X1534916Y539453D02*
Y539575D01*
G01X1533766D02*
Y539453D01*
G01X1536966Y539374D02*
G02X1535981Y538389I-985J0D01*
G01X1535980D02*
G02X1534916Y539453I0J1064D01*
G01X1533766D02*
G03X1535980Y537239I2214J0D01*
G01X1536966Y539374D02*
G02X1535981Y538389I-985J0D01*
G01X1535980D02*
G02X1534916Y539453I0J1064D01*
G01X1535982Y537239D02*
G03X1538116Y539373I0J2134D01*
G01X1536966Y539575D02*
Y539374D01*
G01X1538116Y539373D02*
Y539575D01*
G01X1541316D02*
G03X1536966I-2175J0D01*
G01X1538116D02*
G02X1540166I1025J0D01*
G01X1541316Y539453D02*
Y539575D01*
G01X1540166D02*
Y539453D01*
G01X1543366D02*
G02X1541316I-1025J0D01*
G01X1540166D02*
G03X1544516I2175J0D01*
G01X1547716D02*
G03X1543366I-2175J0D01*
G01X1544516D02*
G02X1546566I1025J0D01*
G01X1549766D02*
G02X1547716I-1025J0D01*
G01X1546566D02*
G03X1550916I2175J0D01*
G01X1549766Y539575D02*
Y539453D01*
G01X1550916D02*
Y539575D01*
G01X1554116D02*
G03X1549766I-2175J0D01*
G01X1550916D02*
G02X1552966I1025J0D01*
G01X1554116Y539453D02*
Y539575D01*
G01X1552966D02*
Y539453D01*
G01X1556166D02*
G02X1554116I-1025J0D01*
G01X1552966D02*
G03X1557316I2175J0D01*
G01X1556166Y539575D02*
Y539453D01*
G01X1557316D02*
Y539575D01*
G01X1560516D02*
G03X1556166I-2175J0D01*
G01X1557316D02*
G02X1559366I1025J0D01*
G01X1560516Y539453D02*
Y539575D01*
G01X1559366D02*
Y539453D01*
G01X1562566D02*
G02X1560516I-1025J0D01*
G01X1559366D02*
G03X1563716I2175J0D01*
G01X1562566Y539575D02*
Y539453D01*
G01X1563716D02*
Y539575D01*
G01X1566916D02*
G03X1562566I-2175J0D01*
G01X1563716D02*
G02X1565766I1025J0D01*
G01X1566916Y539453D02*
Y539575D01*
G01X1565766D02*
Y539453D01*
G01X1568966D02*
G02X1566916I-1025J0D01*
G01X1565766D02*
G03X1570116I2175J0D01*
G01X1568966Y539575D02*
Y539453D01*
G01X1570116D02*
Y539575D01*
G01X1571141Y541750D02*
G03X1568966Y539575I0J-2175D01*
G01X1570116D02*
G02X1571141Y540600I1025J0D01*
G01X1573663Y541750D02*
X1571141D01*
G01Y540600D02*
X1573663D01*
G01X1575203Y542388D02*
G02X1573663Y541750I-1540J1540D01*
G01Y540600D02*
G03X1576017Y541574I1J3328D01*
G01X1586144Y553329D02*
X1575203Y542388D01*
G01X1576017Y541574D02*
X1577038Y542595D01*
G01X1586144Y553329D02*
X1575203Y542388D01*
G01X1579831Y545388D02*
X1581026Y546583D01*
G01X1586144Y553329D02*
X1575203Y542388D01*
G01X1583819Y549376D02*
X1586958Y552515D01*
G01X1586835Y554994D02*
G02X1586144Y553329I-2355J1D01*
G01X1586958Y552515D02*
G03X1587985Y554993I-2478J2479D01*
G01X1586835Y565789D02*
Y554994D01*
G01X1587985Y554993D02*
Y565789D01*
G01X1588971Y567925D02*
G03X1587516Y567322I0J-2057D01*
G01X1587438Y567244D02*
G03X1586835Y565789I1454J-1455D01*
G01X1587985D02*
G02X1588252Y566430I906J-1D01*
G01X1588971Y567925D02*
G03X1587516Y567322I0J-2057D01*
G01X1587438Y567244D02*
G03X1586835Y565789I1454J-1455D01*
G01X1588330Y566508D02*
G02X1588971Y566775I642J-639D01*
G01X1543006Y548129D02*
G03X1544106Y549229I0J1100D01*
G01X1543006Y546979D02*
G03X1545256Y549229I0J2250D01*
G01X1544106D02*
Y550765D01*
G01X1545256Y549229D02*
Y550765D01*
G01X1544106D02*
G02X1548456I2175J0D01*
G01X1545256D02*
G02X1547306I1025J0D01*
G01X1548456D02*
Y549154D01*
G01X1547306Y550765D02*
Y549154D01*
G01X1548456D02*
G03X1550506I1025J0D01*
G01X1547306D02*
G03X1551656I2175J0D01*
G01X1550506D02*
Y550765D01*
G01X1551656Y549154D02*
Y550765D01*
G01X1550506D02*
G02X1554856I2175J0D01*
G01X1551656D02*
G02X1553706I1025J0D01*
G01X1554856D02*
Y549154D01*
G01X1553706Y550765D02*
Y549154D01*
G01X1554856D02*
G03X1556906I1025J0D01*
G01X1553706D02*
G03X1558056I2175J0D01*
G01X1556906D02*
Y550765D01*
G01X1558056Y549154D02*
Y550765D01*
G01X1556906D02*
G02X1561256I2175J0D01*
G01X1558056D02*
G02X1560106I1025J0D01*
G01X1561256D02*
Y549154D01*
G01X1560106Y550765D02*
Y549154D01*
G01X1561256D02*
G03X1563306I1025J0D01*
G01X1560106D02*
G03X1564456I2175J0D01*
G01X1563306D02*
Y550765D01*
G01X1564456Y549154D02*
Y550765D01*
G01X1563306D02*
G02X1567656I2175J0D01*
G01X1564456D02*
G02X1566506I1025J0D01*
G01X1567656D02*
Y549192D01*
G01X1566506Y550765D02*
Y549192D01*
G01X1567656D02*
G03X1568719Y548129I1063J0D01*
G01X1566506Y549192D02*
G03X1568719Y546979I2213J0D01*
G01Y548129D02*
X1570065D01*
G01X1568719Y546979D02*
X1570065D01*
G01Y548129D02*
G03X1570921Y548483I1J1210D01*
G01X1570065Y546979D02*
G03X1571734Y547669I1J2360D01*
G01X1570922Y548485D02*
G03X1571696Y550349I-1863J1866D01*
G01X1571736Y547671D02*
G03X1572846Y550348I-2678J2679D01*
G01X1571696Y550349D02*
Y553964D01*
G01X1572846Y550348D02*
Y553963D01*
G01X1571696Y553964D02*
G02X1572463Y555812I2614J-2D01*
G01X1572846Y553963D02*
G02X1573276Y554998I1464J-1D01*
G01X1572463Y555812D02*
X1573543Y556893D01*
G01X1573276Y554998D02*
X1574357Y556079D01*
G01X1573543Y556893D02*
G03X1574210Y558500I-1606J1608D01*
G01X1574357Y556079D02*
G03X1575360Y558499I-2420J2421D01*
G01X1574210Y558500D02*
Y572408D01*
G01X1575360Y558499D02*
Y561807D01*
G01X1574210Y558500D02*
Y572408D01*
G01X1575360Y565757D02*
Y567107D01*
G01X1574210Y558500D02*
Y572408D01*
G01X1575360Y571057D02*
Y572407D01*
G01X1574210Y572408D02*
G02X1575095Y574544I3023J-1D01*
G01X1575360Y572407D02*
G02X1575909Y573730I1872J-1D01*
G01X1575095Y574544D02*
X1576188Y575637D01*
G01X1575909Y573730D02*
X1577002Y574823D01*
G01X1576188Y575637D02*
G02X1578243Y576487I2054J-2056D01*
G01X1577002Y574823D02*
G02X1578243Y575337I1241J-1241D01*
G01Y576487D02*
X1581271D01*
G01X1578243Y575337D02*
X1581271D01*
G01Y576487D02*
G02X1583427Y575595I1J-3048D01*
G01X1581271Y575337D02*
G02X1582613Y574781I0J-1898D01*
G01X1583427Y575595D02*
X1584321Y574701D01*
G01X1582613Y574781D02*
X1583507Y573887D01*
G01X1584321Y574701D02*
G03X1585425Y574243I1105J1104D01*
G01X1583507Y573887D02*
G03X1585426Y573093I1918J1919D01*
G01X1585425Y574243D02*
X1593199D01*
G01X1585426Y573093D02*
X1593199D01*
G01X1586975Y571058D02*
X1592163D01*
G01Y569908D02*
X1586975D01*
G01X1584892Y570195D02*
G02X1586975Y571058I2083J-2082D01*
G01Y569908D02*
G03X1585706Y569381I1J-1795D01*
G01X1584547Y569850D02*
X1584892Y570195D01*
G01X1585706Y569381D02*
X1585361Y569036D01*
G01X1583715Y567841D02*
G02X1584547Y569850I2842J0D01*
G01X1585361Y569036D02*
G03X1584865Y567841I1195J-1196D01*
G01X1583715Y557432D02*
Y567841D01*
G01X1584865D02*
Y557432D01*
G01X1582588Y554711D02*
G03X1583715Y557432I-2721J2721D01*
G01X1584865D02*
G02X1583402Y553897I-4999J-1D01*
G01X1581574Y553697D02*
X1582588Y554711D01*
G01X1583402Y553897D02*
X1582388Y552883D01*
G01X1580018Y553697D02*
G03X1581574I778J778D01*
G01X1582388Y552883D02*
G02X1579204I-1592J1592D01*
G01X1578937Y554778D02*
X1580018Y553697D01*
G01X1579204Y552883D02*
X1578123Y553964D01*
G01X1575859Y551699D02*
G02Y554775I1538J1538D01*
G01X1575862Y554778D02*
G02X1578937I1538J-1538D01*
G01X1578123Y553964D02*
G03X1576676I-723J-724D01*
G01X1575859Y551699D02*
G02Y554775I1538J1538D01*
G01X1575862Y554778D02*
G02X1578937I1538J-1538D01*
G01X1576673Y553961D02*
G03Y552513I724J-724D01*
G01X1576992Y550566D02*
X1575859Y551699D01*
G01X1576673Y552513D02*
X1577806Y551380D01*
G01X1576992Y549116D02*
G03Y550566I-725J725D01*
G01X1577806Y551380D02*
G02Y548302I-1539J-1539D01*
G01X1573212Y545336D02*
X1576992Y549116D01*
G01X1577806Y548302D02*
X1574026Y544522D01*
G01X1572304Y544960D02*
G03X1573212Y545336I0J1284D01*
G01X1574026Y544522D02*
G02X1572304Y543810I-1721J1723D01*
G01X1527166Y544960D02*
X1572304D01*
G01Y543810D02*
X1550543D01*
G01X1527166Y544960D02*
X1572304D01*
G01X1546593Y543810D02*
X1544096D01*
G01X1527166Y544960D02*
X1572304D01*
G01X1540146Y543810D02*
X1527166D01*
G01X1537284Y551229D02*
G03X1539905Y552315I0J3706D01*
G01X1537284Y550079D02*
G03X1540719Y551501I1J4856D01*
G01X1539905Y552315D02*
X1542741Y555151D01*
G01X1540719Y551501D02*
X1543555Y554337D01*
G01X1542741Y555151D02*
G02X1545073Y556117I2332J-2332D01*
G01X1543555Y554337D02*
G02X1545073Y554967I1519J-1517D01*
G01Y556117D02*
X1566956D01*
G01X1545073Y554967D02*
X1547683D01*
G01X1545073Y556117D02*
X1566956D01*
G01X1551633Y554967D02*
X1554002D01*
G01X1545073Y556117D02*
X1566956D01*
G01X1557952Y554967D02*
X1560287D01*
G01X1545073Y556117D02*
X1566956D01*
G01X1564237Y554967D02*
X1566956D01*
G01Y556117D02*
G03X1569185Y557040I0J3153D01*
G01X1566956Y554967D02*
G03X1569999Y556226I1J4304D01*
G01X1569185Y557040D02*
X1570168Y558023D01*
G01X1569999Y556226D02*
X1570982Y557209D01*
G01X1570168Y558023D02*
G03X1570853Y559679I-1657J1655D01*
G01X1570982Y557209D02*
G03X1572004Y559679I-2470J2469D01*
G01X1570854Y559678D02*
Y573748D01*
G01X1572004Y559679D02*
Y573747D01*
G01X1570854Y573748D02*
G02X1572026Y576577I4001J0D01*
G01X1572004Y573747D02*
G02X1572840Y575763I2851J-1D01*
G01X1572026Y576577D02*
X1574333Y578884D01*
G01X1572840Y575763D02*
X1575147Y578070D01*
G01X1574333Y578884D02*
G02X1576572Y579812I2240J-2239D01*
G01X1575147Y578070D02*
G02X1576573Y578662I1427J-1425D01*
G01X1576572Y579812D02*
X1583037D01*
G01X1576573Y578662D02*
X1583036D01*
G01X1583037Y579812D02*
G02X1584629Y579152I-1J-2252D01*
G01X1583036Y578662D02*
G02X1583815Y578338I-1J-1101D01*
G01X1584629Y579152D02*
X1586098Y577683D01*
G01X1583815Y578338D02*
X1585284Y576869D01*
G01X1586098Y577683D02*
G03X1586877Y577360I779J778D01*
G01X1585284Y576869D02*
G03X1586877Y576210I1592J1592D01*
G01Y577360D02*
X1592965D01*
G01X1586877Y576210D02*
X1592965D01*
G01X1593270Y5934D02*
X1607194Y8893D01*
G01X1593270Y4758D02*
X1607767Y7838D01*
G01X1607194Y8893D02*
X1613751Y15450D01*
G01X1607767Y7838D02*
X1614228Y14300D01*
G01X1613751Y15450D02*
X1617390D01*
G01X1614228Y14300D02*
X1617203D01*
G01X1617390Y15450D02*
X1620820Y14307D01*
G01X1617203Y14300D02*
X1620198Y13301D01*
G01X1620820Y14307D02*
X1622673Y12453D01*
G01X1620198Y13301D02*
X1621523Y11976D01*
G01X1622673Y12453D02*
Y11205D01*
G01X1621523Y11976D02*
Y11205D01*
G01X1593270Y4758D02*
X1607767Y7838D01*
G01X1593270Y5934D02*
X1607194Y8893D01*
G01X1607767Y7838D02*
X1614228Y14300D01*
G01X1607194Y8893D02*
X1613751Y15450D01*
G01X1614228Y14300D02*
X1617203D01*
G01X1613751Y15450D02*
X1617390D01*
G01X1617203Y14300D02*
X1620198Y13301D01*
G01X1617390Y15450D02*
X1620820Y14307D01*
G01X1620198Y13301D02*
X1621523Y11976D01*
G01X1620820Y14307D02*
X1622673Y12453D01*
G01X1621523Y11976D02*
Y11205D01*
G01X1622673Y12453D02*
Y11205D01*
G01X1598013Y13570D02*
X1615748Y17341D01*
G01X1598013Y14746D02*
X1615748Y18517D01*
G01Y17341D02*
X1629788Y14362D01*
G01X1615748Y18517D02*
X1630426Y15403D01*
G01X1629788Y14362D02*
X1630873Y13023D01*
G01X1630426Y15403D02*
X1632023Y13431D01*
G01X1630873Y13023D02*
Y7275D01*
G01X1632023Y13431D02*
Y7275D01*
G01X1598052Y16153D02*
X1615716Y19905D01*
G01X1598052Y17329D02*
X1615716Y21081D01*
G01Y19905D02*
X1625400Y17850D01*
G01X1615716Y21081D02*
X1625521Y19000D01*
G01X1625400Y17850D02*
X1632565D01*
G01X1635215D02*
X1636565D01*
G01X1625521Y19000D02*
X1636816D01*
G01X1636565Y17850D02*
X1639952Y16302D01*
G01X1636816Y19000D02*
X1640619Y17262D01*
G01X1639952Y16302D02*
X1640668Y15586D01*
G01X1640619Y17262D02*
X1641818Y16063D01*
G01X1640668Y15586D02*
Y11555D01*
G01X1641818Y16063D02*
Y11697D01*
G01X1598013Y14746D02*
X1615748Y18517D01*
G01X1598013Y13570D02*
X1615748Y17341D01*
G01Y18517D02*
X1630426Y15403D01*
G01X1615748Y17341D02*
X1629788Y14362D01*
G01X1630426Y15403D02*
X1632023Y13431D01*
G01X1629788Y14362D02*
X1630873Y13023D01*
G01X1632023Y13431D02*
Y7275D01*
G01X1630873Y13023D02*
Y7275D01*
G01X1598052Y17329D02*
X1615716Y21081D01*
G01X1598052Y16153D02*
X1615716Y19905D01*
G01Y21081D02*
X1625521Y19000D01*
G01X1615716Y19905D02*
X1625400Y17850D01*
G01X1625521Y19000D02*
X1636816D01*
G01X1625400Y17850D02*
X1632565D01*
G01X1625521Y19000D02*
X1636816D01*
G01X1635215Y17850D02*
X1636565D01*
G01X1636816Y19000D02*
X1640619Y17262D01*
G01X1636565Y17850D02*
X1639952Y16302D01*
G01X1640619Y17262D02*
X1641818Y16063D01*
G01X1639952Y16302D02*
X1640668Y15586D01*
G01X1641818Y16063D02*
Y11697D01*
G01X1640668Y15586D02*
Y11555D01*
G01X1598020Y18766D02*
X1615862Y22557D01*
G01X1598020Y19942D02*
X1615862Y23733D01*
G01Y22557D02*
X1620092Y21658D01*
G01X1615862Y23733D02*
X1620092Y22834D01*
G01Y21658D02*
X1635792Y24993D01*
G01X1620092Y22834D02*
X1635792Y26169D01*
G01Y24993D02*
X1641405Y23801D01*
G01X1635792Y26169D02*
X1641816Y24890D01*
G01X1641405Y23801D02*
X1648621Y19743D01*
G01X1641816Y24890D02*
X1649527Y20554D01*
G01X1648621Y19743D02*
X1650073Y16329D01*
G01X1649527Y20554D02*
X1651223Y16564D01*
G01X1650073Y16329D02*
Y8675D01*
G01D02*
X1650873Y7875D01*
G01X1598020Y19942D02*
X1615862Y23733D01*
G01X1598020Y18766D02*
X1615862Y22557D01*
G01Y23733D02*
X1620092Y22834D01*
G01X1615862Y22557D02*
X1620092Y21658D01*
G01Y22834D02*
X1635792Y26169D01*
G01X1620092Y21658D02*
X1635792Y24993D01*
G01Y26169D02*
X1641816Y24890D01*
G01X1635792Y24993D02*
X1641405Y23801D01*
G01X1641816Y24890D02*
X1649527Y20554D01*
G01X1641405Y23801D02*
X1648621Y19743D01*
G01X1649527Y20554D02*
X1651223Y16564D01*
G01X1648621Y19743D02*
X1650073Y16329D01*
G01D02*
Y8675D01*
G01D02*
X1650873Y7875D01*
G01X1593923Y26104D02*
X1597812Y26931D01*
G01X1593923Y27280D02*
X1597812Y28107D01*
G01Y26931D02*
X1601406Y26168D01*
G01X1597812Y28107D02*
X1601406Y27344D01*
G01Y26168D02*
X1606175Y27180D01*
G01X1601406Y27344D02*
X1606175Y28356D01*
G01Y27180D02*
X1620093Y24224D01*
G01X1606175Y28356D02*
X1620093Y25400D01*
G01Y24224D02*
X1635964Y27596D01*
G01X1620093Y25400D02*
X1635964Y28772D01*
G01Y27596D02*
X1645461Y25579D01*
G01X1635964Y28772D02*
X1645868Y26669D01*
G01X1645461Y25579D02*
X1658874Y18142D01*
G01X1645868Y26669D02*
X1659755Y18970D01*
G01X1592582Y28946D02*
X1596540Y29787D01*
G01X1592582Y30122D02*
X1596540Y30963D01*
G01Y29787D02*
X1601384Y28758D01*
G01X1596540Y30963D02*
X1601384Y29934D01*
G01Y28758D02*
X1606107Y29761D01*
G01X1601384Y29934D02*
X1606107Y30937D01*
G01Y29761D02*
X1620095Y26790D01*
G01X1606107Y30937D02*
X1620095Y27966D01*
G01Y26790D02*
X1636011Y30172D01*
G01X1620095Y27966D02*
X1636011Y31348D01*
G01Y30172D02*
X1665439Y23922D01*
G01X1636011Y31348D02*
X1665894Y25002D01*
G01X1592708Y31538D02*
X1596610Y32367D01*
G01X1592708Y32714D02*
X1596610Y33543D01*
G01Y32367D02*
X1601455Y31338D01*
G01X1596610Y33543D02*
X1601455Y32514D01*
G01Y31338D02*
X1606107Y32327D01*
G01X1601455Y32514D02*
X1606107Y33503D01*
G01Y32327D02*
X1620094Y29356D01*
G01X1606107Y33503D02*
X1620094Y30532D01*
G01Y29356D02*
X1636191Y32776D01*
G01X1620094Y30532D02*
X1636191Y33952D01*
G01Y32776D02*
X1670895Y25404D01*
G01X1636191Y33952D02*
X1671350Y26484D01*
G01X1637169Y35551D02*
X1620096Y31921D01*
G01D02*
X1606107Y34893D01*
G01X1593923Y27280D02*
X1597812Y28107D01*
G01X1593923Y26104D02*
X1597812Y26931D01*
G01Y28107D02*
X1601406Y27344D01*
G01X1597812Y26931D02*
X1601406Y26168D01*
G01Y27344D02*
X1606175Y28356D01*
G01X1601406Y26168D02*
X1606175Y27180D01*
G01Y28356D02*
X1620093Y25400D01*
G01X1606175Y27180D02*
X1620093Y24224D01*
G01Y25400D02*
X1635964Y28772D01*
G01X1620093Y24224D02*
X1635964Y27596D01*
G01Y28772D02*
X1645868Y26669D01*
G01X1635964Y27596D02*
X1645461Y25579D01*
G01X1645868Y26669D02*
X1659755Y18970D01*
G01X1645461Y25579D02*
X1658874Y18142D01*
G01X1592582Y30122D02*
X1596540Y30963D01*
G01X1592582Y28946D02*
X1596540Y29787D01*
G01Y30963D02*
X1601384Y29934D01*
G01X1596540Y29787D02*
X1601384Y28758D01*
G01Y29934D02*
X1606107Y30937D01*
G01X1601384Y28758D02*
X1606107Y29761D01*
G01Y30937D02*
X1620095Y27966D01*
G01X1606107Y29761D02*
X1620095Y26790D01*
G01Y27966D02*
X1636011Y31348D01*
G01X1620095Y26790D02*
X1636011Y30172D01*
G01Y31348D02*
X1665894Y25002D01*
G01X1636011Y30172D02*
X1665439Y23922D01*
G01X1592708Y32714D02*
X1596610Y33543D01*
G01X1592708Y31538D02*
X1596610Y32367D01*
G01Y33543D02*
X1601455Y32514D01*
G01X1596610Y32367D02*
X1601455Y31338D01*
G01Y32514D02*
X1606107Y33503D01*
G01X1601455Y31338D02*
X1606107Y32327D01*
G01Y33503D02*
X1620094Y30532D01*
G01X1606107Y32327D02*
X1620094Y29356D01*
G01Y30532D02*
X1636191Y33952D01*
G01X1620094Y29356D02*
X1636191Y32776D01*
G01Y33952D02*
X1671350Y26484D01*
G01X1636191Y32776D02*
X1670895Y25404D01*
G01X1637169Y35551D02*
X1620096Y31921D01*
G01D02*
X1606107Y34893D01*
G01X1622721Y42400D02*
X1623900D01*
G01D02*
X1624590Y41710D01*
G01X1625739Y42189D02*
X1624377Y43550D01*
G01X1622721Y42400D02*
X1623900D01*
G01X1624377Y43550D02*
X1622600D01*
G01X1605455Y38732D02*
X1622721Y42400D01*
G01X1622600Y43550D02*
X1605455Y39908D01*
G01X1595105Y40932D02*
X1605455Y38732D01*
G01Y39908D02*
X1595105Y42108D01*
G01X1605455Y39908D02*
X1595105Y42108D01*
G01Y40932D02*
X1605455Y38732D01*
G01X1622600Y43550D02*
X1605455Y39908D01*
G01Y38732D02*
X1622721Y42400D01*
G01X1625739Y42189D02*
X1624377Y43550D01*
G01D02*
X1622600D01*
G01X1622721Y42400D02*
X1623900D01*
G01X1625739Y42189D02*
X1624377Y43550D01*
G01X1623900Y42400D02*
X1624590Y41710D01*
G01X1634249Y42376D02*
Y40312D01*
G01X1635399D02*
Y42853D01*
G01X1633171Y43453D02*
X1634249Y42376D01*
G01X1635399Y42853D02*
X1633744Y44508D01*
G01X1624378Y45321D02*
X1633171Y43453D01*
G01X1633744Y44508D02*
X1624378Y46497D01*
G01X1605554Y41319D02*
X1624378Y45321D01*
G01Y46497D02*
X1605554Y42495D01*
G01X1595105Y43539D02*
X1605554Y41319D01*
G01Y42495D02*
X1595105Y44715D01*
G01X1605554Y42495D02*
X1595105Y44715D01*
G01Y43539D02*
X1605554Y41319D01*
G01X1624378Y46497D02*
X1605554Y42495D01*
G01Y41319D02*
X1624378Y45321D01*
G01X1633744Y44508D02*
X1624378Y46497D01*
G01Y45321D02*
X1633171Y43453D01*
G01X1635399Y42853D02*
X1633744Y44508D01*
G01X1633171Y43453D02*
X1634249Y42376D01*
G01X1635399Y40312D02*
Y42853D01*
G01X1634249Y42376D02*
Y40312D01*
G01X1679998Y26455D02*
X1637169Y35551D01*
G01X1680453Y27535D02*
X1637169Y36727D01*
G01D02*
X1620096Y33097D01*
G01D02*
X1606107Y36069D01*
G01Y34893D02*
X1601500Y33914D01*
G01X1606107Y36069D02*
X1601500Y35090D01*
G01Y33914D02*
X1596656Y34943D01*
G01X1601500Y35090D02*
X1596656Y36119D01*
G01Y34943D02*
X1592932Y34152D01*
G01X1596656Y36119D02*
X1592932Y35328D01*
G01X1680453Y27535D02*
X1637169Y36727D01*
G01X1679998Y26455D02*
X1637169Y35551D01*
G01Y36727D02*
X1620096Y33097D01*
G01D02*
X1606107Y36069D01*
G01D02*
X1601500Y35090D01*
G01X1606107Y34893D02*
X1601500Y33914D01*
G01Y35090D02*
X1596656Y36119D01*
G01X1601500Y33914D02*
X1596656Y34943D01*
G01Y36119D02*
X1592932Y35328D01*
G01X1596656Y34943D02*
X1592932Y34152D01*
G01X1643818Y42986D02*
Y39912D01*
G01X1644968D02*
Y43463D01*
G01X1642842Y43962D02*
X1643818Y42986D01*
G01X1644968Y43463D02*
X1643413Y45019D01*
G01X1624138Y47933D02*
X1642842Y43962D01*
G01X1643413Y45019D02*
X1624138Y49109D01*
G01X1605410Y43955D02*
X1624138Y47933D01*
G01Y49109D02*
X1605410Y45131D01*
G01X1595105Y46146D02*
X1605410Y43955D01*
G01Y45131D02*
X1595105Y47322D01*
G01X1649117Y45255D02*
X1653300Y41073D01*
G01X1654450Y41550D02*
X1649690Y46310D01*
G01X1624094Y50567D02*
X1649117Y45255D01*
G01X1649690Y46310D02*
X1624094Y51743D01*
G01X1605327Y46580D02*
X1624094Y50567D01*
G01Y51743D02*
X1605327Y47756D01*
G01X1594800Y48818D02*
X1605327Y46580D01*
G01Y47756D02*
X1594800Y49994D01*
G01X1594799Y51425D02*
X1604933Y49270D01*
G01X1594799Y52601D02*
X1595038Y52551D01*
G01X1594799Y51425D02*
X1604933Y49270D01*
G01X1595038Y52550D02*
X1604933Y50446D01*
G01Y49270D02*
X1623854Y53288D01*
G01X1604933Y50446D02*
X1614154Y52404D01*
G01X1604933Y49270D02*
X1623854Y53288D01*
G01X1614154Y52404D02*
X1623854Y54464D01*
G01Y53288D02*
X1650332Y47668D01*
G01X1623854Y54464D02*
X1650905Y48723D01*
G01X1650332Y47668D02*
X1656500Y41500D01*
G01X1623856Y55887D02*
X1658553Y48519D01*
G01X1659126Y49574D02*
X1623856Y57063D01*
G01X1604958Y51872D02*
X1623856Y55887D01*
G01Y57063D02*
X1604958Y53048D01*
G01X1594799Y54032D02*
X1604958Y51872D01*
G01Y53048D02*
X1594799Y55208D01*
G01X1605410Y45131D02*
X1595105Y47322D01*
G01Y46146D02*
X1605410Y43955D01*
G01X1624138Y49109D02*
X1605410Y45131D01*
G01Y43955D02*
X1624138Y47933D01*
G01X1643413Y45019D02*
X1624138Y49109D01*
G01Y47933D02*
X1642842Y43962D01*
G01X1644968Y43463D02*
X1643413Y45019D01*
G01X1642842Y43962D02*
X1643818Y42986D01*
G01X1644968Y39912D02*
Y43463D01*
G01X1643818Y42986D02*
Y39912D01*
G01X1605327Y47756D02*
X1594800Y49994D01*
G01Y48818D02*
X1605327Y46580D01*
G01X1624094Y51743D02*
X1605327Y47756D01*
G01Y46580D02*
X1624094Y50567D01*
G01X1649690Y46310D02*
X1624094Y51743D01*
G01Y50567D02*
X1649117Y45255D01*
G01X1654450Y41550D02*
X1649690Y46310D01*
G01X1649117Y45255D02*
X1653300Y41073D01*
G01X1594799Y52601D02*
X1595038Y52551D01*
G01Y52550D02*
X1604933Y50446D01*
G01X1594799Y51425D02*
X1604933Y49270D01*
G01Y50446D02*
X1614154Y52404D01*
G01D02*
X1623854Y54464D01*
G01X1604933Y49270D02*
X1623854Y53288D01*
G01Y54464D02*
X1650905Y48723D01*
G01X1623854Y53288D02*
X1650332Y47668D01*
G01D02*
X1656500Y41500D01*
G01X1604958Y53048D02*
X1594799Y55208D01*
G01Y54032D02*
X1604958Y51872D01*
G01X1623856Y57063D02*
X1604958Y53048D01*
G01Y51872D02*
X1623856Y55887D01*
G01X1659126Y49574D02*
X1623856Y57063D01*
G01Y55887D02*
X1658553Y48519D01*
G01X1604886Y55671D02*
X1594870Y57800D01*
G01Y56624D02*
X1604886Y54495D01*
G01X1623768Y59680D02*
X1604886Y55671D01*
G01Y54495D02*
X1623768Y58504D01*
G01X1660393Y51907D02*
X1623768Y59680D01*
G01Y58504D02*
X1659820Y50852D01*
G01X1623768Y58504D02*
X1659820Y50852D01*
G01X1660393Y51907D02*
X1623768Y59680D01*
G01X1604886Y54495D02*
X1623768Y58504D01*
G01Y59680D02*
X1604886Y55671D01*
G01X1594870Y56624D02*
X1604886Y54495D01*
G01Y55671D02*
X1594870Y57800D01*
G01X1604897Y58275D02*
X1594869Y60407D01*
G01Y59231D02*
X1604897Y57099D01*
G01X1623834Y62297D02*
X1604897Y58275D01*
G01Y57099D02*
X1623834Y61121D01*
G01X1661622Y54277D02*
X1623834Y62297D01*
G01Y61121D02*
X1661049Y53222D01*
G01X1623834Y61121D02*
X1661049Y53222D01*
G01X1661622Y54277D02*
X1623834Y62297D01*
G01X1604897Y57099D02*
X1623834Y61121D01*
G01Y62297D02*
X1604897Y58275D01*
G01X1594869Y59231D02*
X1604897Y57099D01*
G01Y58275D02*
X1594869Y60407D01*
G01X1624932Y68323D02*
X1669688Y58819D01*
G01X1669681Y57644D02*
X1624493Y67240D01*
G01X1618458Y67053D02*
X1624701Y68468D01*
G01X1624492Y67241D02*
X1618401Y65860D01*
G01X1604358Y71694D02*
X1618458Y67053D01*
G01X1618401Y65860D02*
X1604298Y70502D01*
G01X1588822Y68257D02*
X1604358Y71694D01*
G01X1604298Y70502D02*
X1588827Y67080D01*
G01X1604298Y70502D02*
X1588827Y67080D01*
G01X1588822Y68257D02*
X1604358Y71694D01*
G01X1618401Y65860D02*
X1604298Y70502D01*
G01X1604358Y71694D02*
X1618458Y67053D01*
G01X1624492Y67241D02*
X1618401Y65860D01*
G01X1618458Y67053D02*
X1624701Y68468D01*
G01X1669681Y57644D02*
X1624493Y67240D01*
G01X1624932Y68323D02*
X1669688Y58819D01*
G01X1623690Y65608D02*
X1673042Y55451D01*
G01X1672592Y54369D02*
X1648150Y59399D01*
G01X1623690Y65608D02*
X1673042Y55451D01*
G01X1648150Y59399D02*
X1648149D01*
G01X1623690Y65608D02*
X1673042Y55451D01*
G01X1648149Y59399D02*
X1623705Y64430D01*
G01X1618227Y64362D02*
X1623690Y65608D01*
G01D02*
X1673042Y55451D01*
G01X1623705Y64430D02*
X1623703D01*
G01X1618227Y64362D02*
X1623690Y65608D01*
G01X1623703Y64430D02*
X1618171Y63169D01*
G01X1604225Y68960D02*
X1618227Y64362D01*
G01X1618171Y63169D02*
X1604161Y67770D01*
G01X1618171Y63169D02*
X1604161Y67770D01*
G01X1604225Y68960D02*
X1618227Y64362D01*
G01X1623705Y64430D02*
X1623703D01*
G01D02*
X1618171Y63169D01*
G01X1618227Y64362D02*
X1623690Y65608D01*
G01X1672592Y54369D02*
X1648150Y59399D01*
G01D02*
X1648149D01*
G01D02*
X1623705Y64430D01*
G01D02*
X1623703D01*
G01X1623690Y65608D02*
X1673042Y55451D01*
G01X1638405Y75831D02*
X1661899Y67561D01*
G01X1661594Y66449D02*
X1638099Y74719D01*
G01X1618649Y79784D02*
X1638405Y75831D01*
G01D02*
X1661899Y67561D01*
G01X1638099Y74719D02*
X1638100D01*
G01X1618649Y79784D02*
X1638405Y75831D01*
G01X1638100Y74719D02*
X1618200Y78700D01*
G01X1612942Y83588D02*
X1618649Y79783D01*
G01X1618200Y78700D02*
X1612112Y82758D01*
G01X1609121Y89321D02*
X1612942Y83588D01*
G01X1612112Y82758D02*
X1608316Y88454D01*
G01X1607477Y90250D02*
X1609121Y89321D01*
G01X1608316Y88454D02*
X1607174Y89100D01*
G01X1603974Y90250D02*
X1607477D01*
G01X1607174Y89100D02*
X1604111D01*
G01X1592638Y87524D02*
X1603974Y90250D01*
G01X1604111Y89100D02*
X1592775Y86374D01*
G01X1604111Y89100D02*
X1592775Y86374D01*
G01X1592638Y87524D02*
X1603974Y90250D01*
G01X1607174Y89100D02*
X1604111D01*
G01X1603974Y90250D02*
X1607477D01*
G01X1608316Y88454D02*
X1607174Y89100D01*
G01X1607477Y90250D02*
X1609121Y89321D01*
G01X1612112Y82758D02*
X1608316Y88454D01*
G01X1609121Y89321D02*
X1612942Y83588D01*
G01X1618200Y78700D02*
X1612112Y82758D01*
G01X1612942Y83588D02*
X1618649Y79783D01*
G01X1638099Y74719D02*
X1638100D01*
G01D02*
X1618200Y78700D01*
G01X1618649Y79784D02*
X1638405Y75831D01*
G01X1661594Y66449D02*
X1638099Y74719D01*
G01D02*
X1638100D01*
G01X1638405Y75831D02*
X1661899Y67561D01*
G01X1602359Y64040D02*
X1601649Y64750D01*
G01D02*
X1599862D01*
G01X1599978Y63600D02*
X1601172D01*
G01X1602359Y64040D02*
X1601649Y64750D01*
G01X1601172Y63600D02*
X1601882Y62890D01*
G01X1605888Y64040D02*
X1602359D01*
G01X1601882Y62890D02*
X1608452D01*
G01X1601882D02*
X1608452D01*
G01X1605888Y64040D02*
X1602359D01*
G01X1599978Y63600D02*
X1601172D01*
G01D02*
X1601882Y62890D01*
G01X1602359Y64040D02*
X1601649Y64750D01*
G01X1599978Y63600D02*
X1601172D01*
G01X1601649Y64750D02*
X1599862D01*
G01X1657580Y77851D02*
X1650463Y82977D01*
G01X1657103Y76777D02*
X1649935Y81940D01*
G01X1650463Y82977D02*
X1641873Y85811D01*
G01X1649935Y81940D02*
X1641367Y84766D01*
G01X1641723Y85909D02*
X1641331Y85989D01*
G01D02*
X1640727Y86109D01*
G01X1641276Y84826D02*
X1641104Y84861D01*
G01X1641723Y85909D02*
X1641331Y85989D01*
G01D02*
X1640727Y86109D01*
G01D02*
X1636727Y86911D01*
G01X1641104Y84861D02*
X1640502Y84981D01*
G01X1641331Y85989D02*
X1640727Y86109D01*
G01D02*
X1636727Y86911D01*
G01X1640502Y84981D02*
X1636888Y85705D01*
G01X1636509Y86802D02*
X1632733Y86046D01*
G01X1636886Y85704D02*
X1632492Y84825D01*
G01X1632731Y86048D02*
X1624868Y87620D01*
G01X1632283Y84964D02*
X1624564Y86508D01*
G01X1624868Y87620D02*
X1615596Y90862D01*
G01X1624564Y86508D02*
X1614991Y89855D01*
G01X1615596Y90862D02*
X1612460Y93756D01*
G01X1614991Y89855D02*
X1611800Y92800D01*
G01X1612460Y93756D02*
X1606508Y96732D01*
G01X1611800Y92800D02*
X1606236Y95582D01*
G01X1602808Y96732D02*
X1600456Y94381D01*
G01X1603285Y95582D02*
X1601492Y93789D01*
G01X1600456Y94381D02*
X1599935Y92358D01*
G01X1601492Y93789D02*
X1600935Y91627D01*
G01X1599935Y92358D02*
X1599704Y92213D01*
G01X1600935Y91627D02*
X1600156Y91138D01*
G01X1599704Y92213D02*
X1592531Y90487D01*
G01X1600156Y91138D02*
X1592668Y89337D01*
G01X1657103Y76777D02*
X1649935Y81940D01*
G01X1657580Y77851D02*
X1650463Y82977D01*
G01X1649935Y81940D02*
X1641367Y84766D01*
G01X1650463Y82977D02*
X1641873Y85811D01*
G01X1641276Y84826D02*
X1641104Y84861D01*
G01D02*
X1640502Y84981D01*
G01X1641723Y85909D02*
X1641331Y85989D01*
G01X1641276Y84826D02*
X1641104Y84861D01*
G01D02*
X1640502Y84981D01*
G01D02*
X1636888Y85705D01*
G01X1641331Y85989D02*
X1640727Y86109D01*
G01X1641104Y84861D02*
X1640502Y84981D01*
G01D02*
X1636888Y85705D01*
G01X1640727Y86109D02*
X1636727Y86911D01*
G01X1636886Y85704D02*
X1632492Y84825D01*
G01X1636509Y86802D02*
X1632733Y86046D01*
G01X1632283Y84964D02*
X1624564Y86508D01*
G01X1632731Y86048D02*
X1624868Y87620D01*
G01X1624564Y86508D02*
X1614991Y89855D01*
G01X1624868Y87620D02*
X1615596Y90862D01*
G01X1614991Y89855D02*
X1611800Y92800D01*
G01X1615596Y90862D02*
X1612460Y93756D01*
G01X1611800Y92800D02*
X1606236Y95582D01*
G01X1612460Y93756D02*
X1606508Y96732D01*
G01X1603285Y95582D02*
X1601492Y93789D01*
G01X1602808Y96732D02*
X1600456Y94381D01*
G01X1601492Y93789D02*
X1600935Y91627D01*
G01X1600456Y94381D02*
X1599935Y92358D01*
G01X1600935Y91627D02*
X1600156Y91138D01*
G01X1599935Y92358D02*
X1599704Y92213D01*
G01X1600156Y91138D02*
X1592668Y89337D01*
G01X1599704Y92213D02*
X1592531Y90487D01*
G01X1591204Y81053D02*
X1598278Y82468D01*
G01D02*
X1601966Y81730D01*
G01X1598278Y81295D02*
X1601273Y80695D01*
G01X1601966Y81730D02*
X1605038Y77124D01*
G01X1601273Y80695D02*
X1604208Y76294D01*
G01X1605038Y77124D02*
X1606996Y75819D01*
G01X1604208Y76294D02*
X1606547Y74736D01*
G01X1606996Y75819D02*
X1635459Y70125D01*
G01X1606547Y74736D02*
X1635463Y68953D01*
G01X1635459Y70125D02*
X1642614Y71556D01*
G01X1635463Y68953D02*
X1642530Y70366D01*
G01X1642614Y71556D02*
X1663609Y64161D01*
G01X1642530Y70366D02*
X1663302Y63049D01*
G01X1591204Y81053D02*
X1598278Y82468D01*
G01Y81295D02*
X1601273Y80695D01*
G01X1598278Y82468D02*
X1601966Y81730D01*
G01X1601273Y80695D02*
X1604208Y76294D01*
G01X1601966Y81730D02*
X1605038Y77124D01*
G01X1604208Y76294D02*
X1606547Y74736D01*
G01X1605038Y77124D02*
X1606996Y75819D01*
G01X1606547Y74736D02*
X1635463Y68953D01*
G01X1606996Y75819D02*
X1635459Y70125D01*
G01X1635463Y68953D02*
X1642530Y70366D01*
G01X1635459Y70125D02*
X1642614Y71556D01*
G01X1642530Y70366D02*
X1663302Y63049D01*
G01X1642614Y71556D02*
X1663609Y64161D01*
G01X1648040Y86699D02*
X1634087Y91350D01*
G01X1651300Y84400D02*
X1633900Y90200D01*
G01X1634087Y91350D02*
X1630692D01*
G01X1633900Y90200D02*
X1630215D01*
G01X1630692Y91350D02*
X1627396Y94646D01*
G01X1630215Y90200D02*
X1626719Y93696D01*
G01D02*
X1621235Y96365D01*
G01X1651300Y84400D02*
X1633900Y90200D01*
G01X1651300Y84400D02*
X1633900Y90200D01*
G01X1648040Y86699D02*
X1634087Y91350D01*
G01X1633900Y90200D02*
X1630215D01*
G01X1634087Y91350D02*
X1630692D01*
G01X1630215Y90200D02*
X1626719Y93696D01*
G01X1630692Y91350D02*
X1627396Y94646D01*
G01X1626719Y93696D02*
X1621235Y96365D01*
G01X1606508Y96732D02*
X1602808D01*
G01X1606236Y95582D02*
X1603285D01*
G01X1606236D02*
X1603285D01*
G01X1606508Y96732D02*
X1602808D01*
G01X1627396Y94646D02*
X1621605Y97464D01*
G01D02*
X1613493Y99086D01*
G01X1621235Y96365D02*
X1613044Y98003D01*
G01X1613493Y99086D02*
X1608917Y102139D01*
G01X1613044Y98003D02*
X1608568Y100989D01*
G01X1613493Y99086D02*
X1608917Y102139D01*
G01D02*
X1607211D01*
G01D02*
X1603238Y100704D01*
G01X1608568Y100989D02*
X1607413D01*
G01X1607211Y102139D02*
X1603238Y100704D01*
G01X1607413Y100989D02*
X1603440Y99554D01*
G01X1603238Y100704D02*
X1596607D01*
G01X1603440Y99554D02*
X1596420D01*
G01X1627396Y94646D02*
X1621605Y97464D01*
G01X1621235Y96365D02*
X1613044Y98003D01*
G01X1621605Y97464D02*
X1613493Y99086D01*
G01X1613044Y98003D02*
X1608568Y100989D01*
G01D02*
X1607413D01*
G01X1613493Y99086D02*
X1608917Y102139D01*
G01X1608568Y100989D02*
X1607413D01*
G01X1608917Y102139D02*
X1607211D01*
G01X1608568Y100989D02*
X1607413D01*
G01D02*
X1603440Y99554D01*
G01X1607211Y102139D02*
X1603238Y100704D01*
G01X1603440Y99554D02*
X1596420D01*
G01X1603238Y100704D02*
X1596607D01*
G01X1591822Y473612D02*
Y486949D01*
G01X1592972Y473678D02*
Y486472D01*
G01X1591822Y486949D02*
X1598123Y493250D01*
G01X1592972Y486472D02*
X1598600Y492100D01*
G01X1598123Y493250D02*
X1623060D01*
G01X1598600Y492100D02*
X1622583D01*
G01X1623060Y493250D02*
X1626810Y489500D01*
G01X1622583Y492100D02*
X1626333Y488350D01*
G01X1626810Y489500D02*
X1631001D01*
G01X1626333Y488350D02*
X1631478D01*
G01X1631001Y489500D02*
X1635611Y494110D01*
G01X1631478Y488350D02*
X1636088Y492960D01*
G01X1635611Y494110D02*
X1645391D01*
G01X1636088Y492960D02*
X1645868D01*
G01X1645391Y494110D02*
X1650511Y499230D01*
G01X1645868Y492960D02*
X1650988Y498080D01*
G01X1645391Y494110D02*
X1650511Y499230D01*
G01X1592972Y473678D02*
Y486472D01*
G01X1591822Y473612D02*
Y486949D01*
G01X1592972Y486472D02*
X1598600Y492100D01*
G01X1591822Y486949D02*
X1598123Y493250D01*
G01X1598600Y492100D02*
X1622583D01*
G01X1598123Y493250D02*
X1623060D01*
G01X1622583Y492100D02*
X1626333Y488350D01*
G01X1623060Y493250D02*
X1626810Y489500D01*
G01X1626333Y488350D02*
X1631478D01*
G01X1626810Y489500D02*
X1631001D01*
G01X1631478Y488350D02*
X1636088Y492960D01*
G01X1631001Y489500D02*
X1635611Y494110D01*
G01X1636088Y492960D02*
X1645868D01*
G01X1635611Y494110D02*
X1645391D01*
G01X1645868Y492960D02*
X1650988Y498080D01*
G01X1645391Y494110D02*
X1650511Y499230D01*
G01X1654356Y540398D02*
G03X1650106I-2125J0D01*
G01D02*
Y538819D01*
G01X1651256D02*
G02X1647006I-2125J0D01*
G01X1650106D02*
G02X1648156I-975J0D01*
G01X1647006D02*
Y540336D01*
G01X1648156Y538819D02*
Y540336D01*
G01X1647006D02*
G03X1645056I-975J0D01*
G01X1648156D02*
G03X1643906I-2125J0D01*
G01X1645056D02*
Y539456D01*
G01X1643906Y540336D02*
Y539456D01*
G01X1645056D02*
G02X1640806I-2125J0D01*
G01X1643906D02*
G02X1641956I-975J0D01*
G01X1640806D02*
Y540451D01*
G01X1641956Y539456D02*
Y540451D01*
G01X1640806D02*
G03X1638856I-975J0D01*
G01X1641956D02*
G03X1637706I-2125J0D01*
G01X1638856D02*
Y539388D01*
G01X1637706Y540451D02*
Y539388D01*
G01X1638856D02*
G02X1634606I-2125J0D01*
G01X1637706D02*
G02X1635756I-975J0D01*
G01X1634606D02*
Y540595D01*
G01X1635756Y539388D02*
Y540595D01*
G01X1634606D02*
G03X1632656I-975J0D01*
G01X1635756D02*
G03X1631506I-2125J0D01*
G01X1632656D02*
Y540175D01*
G01X1631506Y540595D02*
Y540175D01*
G01X1632656D02*
G02X1630531Y538050I-2125J0D01*
G01X1631506Y540175D02*
G02X1630531Y539200I-975J0D01*
G01Y538050D02*
X1620553D01*
G01X1630531Y539200D02*
X1620552D01*
G01X1620553Y538050D02*
G03X1619633Y537668I1J-1301D01*
G01X1620552Y539200D02*
G03X1618819Y538482I0J-2451D01*
G01X1619633Y537668D02*
X1619064Y537099D01*
G01X1618819Y538482D02*
X1618250Y537912D01*
G01X1619064Y537099D02*
G02X1617375Y536400I-1688J1688D01*
G01X1618250Y537912D02*
G02X1617375Y537550I-874J875D01*
G01Y536400D02*
X1599121D01*
G01X1617375Y537550D02*
X1599120D01*
G01X1599121Y536400D02*
G03X1594817Y534616I1J-6087D01*
G01X1599120Y537550D02*
G03X1594003Y535430I1J-7238D01*
G01X1593494Y537695D02*
G02X1598042Y539580I4549J-4547D01*
G01X1592680Y538509D02*
G02X1598041Y540730I5362J-5362D01*
G01X1598042Y539580D02*
X1615547D01*
G01X1598041Y540730D02*
X1615547D01*
G01Y539580D02*
G03X1618032Y540608I1J3514D01*
G01X1615547Y540730D02*
G03X1617218Y541422I0J2364D01*
G01X1618032Y540608D02*
X1620743Y543319D01*
G01X1617218Y541422D02*
X1619929Y544133D01*
G01X1620743Y543319D02*
G02X1623500Y544461I2757J-2757D01*
G01X1619929Y544133D02*
G02X1623500Y545611I3570J-3572D01*
G01Y544461D02*
X1632008D01*
G01X1623500Y545611D02*
X1632008D01*
G01Y544461D02*
G03X1634133Y546586I0J2125D01*
G01X1632008Y545611D02*
G03X1632983Y546586I0J975D01*
G01X1634133Y546626D02*
G02X1636083I975J0D01*
G01X1632983D02*
G02X1637233I2125J0D01*
G01X1636083Y546586D02*
G03X1640333I2125J0D01*
G01X1637233D02*
G03X1639183I975J0D01*
G01X1640333Y546625D02*
G02X1642283I975J0D01*
G01X1639183D02*
G02X1643433I2125J0D01*
G01X1642283Y546586D02*
G03X1646533I2125J0D01*
G01X1643433D02*
G03X1645383I975J0D01*
G01X1646533Y546628D02*
G02X1648483I975J0D01*
G01X1645383D02*
G02X1649633I2125J0D01*
G01X1648483Y546586D02*
G03X1652733I2125J0D01*
G01X1649633D02*
G03X1651583I975J0D01*
G01X1653203Y551900D02*
X1648780D01*
G01X1653204Y550750D02*
X1648780D01*
G01Y551900D02*
G02X1647935Y552745I0J845D01*
G01X1648780Y550750D02*
G02X1646785Y552745I0J1995D01*
G01X1647935D02*
Y553765D01*
G01X1646785Y552745D02*
Y553765D01*
G01X1647935D02*
G03X1643685I-2125J0D01*
G01X1646785D02*
G03X1644835I-975J0D01*
G01X1643685D02*
Y552875D01*
G01X1644835Y553765D02*
Y552875D01*
G01X1643685D02*
G02X1642710Y551900I-975J0D01*
G01X1644835Y552875D02*
G02X1642710Y550750I-2125J0D01*
G01Y551900D02*
X1632998D01*
G01X1642710Y550750D02*
X1632999D01*
G01X1632998Y551900D02*
G03X1631600Y551321I0J-1978D01*
G01X1632999Y550750D02*
G03X1632414Y550507I1J-828D01*
G01X1631600Y551321D02*
X1629540Y549262D01*
G01X1632414Y550507D02*
X1630354Y548448D01*
G01X1629540Y549262D02*
G02X1628335Y548762I-1206J1203D01*
G01X1630354Y548448D02*
G02X1628336Y547612I-2018J2018D01*
G01X1628335Y548762D02*
X1621005D01*
G01X1628336Y547612D02*
X1621006D01*
G01X1621005Y548762D02*
G03X1618860Y547874I0J-3035D01*
G01X1621006Y547612D02*
G03X1619674Y547060I1J-1885D01*
G01X1618860Y547874D02*
X1615939Y544953D01*
G01X1619674Y547060D02*
X1616753Y544139D01*
G01X1615939Y544953D02*
G02X1614002Y544150I-1938J1937D01*
G01X1616753Y544139D02*
G02X1614001Y543000I-2751J2752D01*
G01X1614002Y544150D02*
X1594588D01*
G01X1614001Y543000D02*
X1594588D01*
G01Y544150D02*
G03X1593455Y543682I-1J-1602D01*
G01X1594588Y543000D02*
G03X1594269Y542868I0J-451D01*
G01X1593454Y543682D02*
X1592221Y542449D01*
G01X1594269Y542868D02*
X1594268D01*
G01X1593454Y543682D02*
X1592221Y542449D01*
G01X1594268Y542868D02*
X1593035Y541635D01*
G01X1592221Y542449D02*
G02X1590843I-689J688D01*
G01X1593035Y541635D02*
G02X1590029I-1503J1502D01*
G01X1590843Y542449D02*
X1589858Y543433D01*
G01X1590029Y541635D02*
X1589045Y542619D01*
G01X1609717Y546252D02*
G03X1611686Y547066I2J2783D01*
G01X1609718Y547402D02*
G03X1610872Y547880I0J1632D01*
G01X1611686Y547066D02*
X1616103Y551483D01*
G01X1610872Y547880D02*
X1615289Y552297D01*
G01X1616103Y551483D02*
G02X1616923Y551823I820J-819D01*
G01X1615289Y552297D02*
G02X1616923Y552973I1633J-1633D01*
G01Y551823D02*
X1626374D01*
G01X1616923Y552973D02*
X1626374D01*
G01Y551823D02*
G03X1628662Y554111I0J2288D01*
G01X1626374Y552973D02*
G03X1627512Y554111I0J1138D01*
G01X1628662D02*
Y556347D01*
G01X1627512Y554111D02*
Y556347D01*
G01X1628662D02*
G02X1629239Y557740I1970J0D01*
G01X1627512Y556347D02*
G02X1628425Y558554I3121J1D01*
G01X1629239Y557740D02*
X1630854Y559355D01*
G01X1628425Y558554D02*
X1630040Y560169D01*
G01X1630854Y559355D02*
G03X1631568Y561079I-1724J1724D01*
G01X1630040Y560169D02*
G03X1630418Y561078I-910J911D01*
G01X1631568Y561079D02*
Y561213D01*
G01X1630418Y561078D02*
Y561213D01*
G01X1631568D02*
G02X1634154I1293J0D01*
G01X1630418D02*
G02X1635304I2443J0D01*
G01X1634154D02*
Y560288D01*
G01X1635304Y561213D02*
Y560288D01*
G01X1634154D02*
G03X1636433Y558009I2279J0D01*
G01X1635304Y560288D02*
G03X1636433Y559159I1129J0D01*
G01Y558009D02*
X1638452D01*
G01X1636433Y559159D02*
X1638452D01*
G01Y558009D02*
G03X1640635Y560192I0J2183D01*
G01X1638452Y559159D02*
G03X1639485Y560192I0J1033D01*
G01X1640635D02*
Y561499D01*
G01X1639485Y560192D02*
Y561499D01*
G01X1640635D02*
G02X1642685I1025J0D01*
G01X1639485D02*
G02X1643835I2175J0D01*
G01X1642685D02*
Y560251D01*
G01X1643835Y561499D02*
Y560251D01*
G01X1642685D02*
G03X1644927Y558009I2242J0D01*
G01X1643835Y560251D02*
G03X1644927Y559159I1092J0D01*
G01Y558009D02*
X1648789D01*
G01X1644927Y559159D02*
X1648789D01*
G01Y558009D02*
G03X1651550Y560770I0J2761D01*
G01X1648789Y559159D02*
G03X1650400Y560770I0J1611D01*
G01D02*
Y571174D01*
G01X1651550D02*
G03X1648618Y574106I-2932J0D01*
G01X1650400Y571174D02*
G03X1648618Y572956I-1782J0D01*
G01Y574106D02*
X1637075D01*
G01X1648618Y572956D02*
X1637075D01*
G01Y574106D02*
G02Y576156I0J1025D01*
G01Y572956D02*
G02Y577306I0J2175D01*
G01Y576156D02*
X1648937D01*
G01X1637075Y577306D02*
X1648937D01*
G01Y576156D02*
G03X1650650Y577869I0J1713D01*
G01X1648937Y577306D02*
G03X1649500Y577869I0J563D01*
G01D02*
Y579265D01*
G01D02*
G02X1651229Y581171I1915J0D01*
G01X1623541Y556682D02*
X1624644D01*
G01Y557832D02*
X1623541D01*
G01X1620342Y559881D02*
G03X1623541Y556682I3199J0D01*
G01Y557832D02*
G02X1621492Y559881I0J2049D01*
G01X1620342Y565469D02*
Y559881D01*
G01X1621492D02*
Y565469D01*
G01X1618292D02*
G02X1620342I1025J0D01*
G01X1621492D02*
G03X1617142I-2175J0D01*
G01X1618292Y564713D02*
Y565469D01*
G01X1617142D02*
Y564713D01*
G01X1615834Y562255D02*
G03X1618292Y564713I0J2458D01*
G01X1617142D02*
G02X1615834Y563405I-1308J0D01*
G01X1614809Y561230D02*
G02X1615834Y562255I1025J0D01*
G01Y563405D02*
G03X1613659Y561230I0J-2175D01*
G01X1614809Y560526D02*
Y561230D01*
G01X1613659D02*
Y560526D01*
G01X1615834Y559501D02*
G02X1614809Y560526I0J1025D01*
G01X1613659D02*
G03X1615834Y558351I2175J0D01*
G01X1616629Y559501D02*
X1615834D01*
G01Y558351D02*
X1616629D01*
G01X1618804Y557326D02*
G03X1616629Y559501I-2175J0D01*
G01Y558351D02*
G02X1617654Y557326I0J-1025D01*
G01X1618804Y557148D02*
Y557326D01*
G01X1617654D02*
Y557148D01*
G01X1616805Y555151D02*
G03X1618804Y557148I2J1997D01*
G01X1617654D02*
G02X1616806Y556301I-847J0D01*
G01X1614630Y555147D02*
X1616805Y555151D01*
G01X1616804Y556302D02*
X1614627Y556297D01*
G01X1614313Y555014D02*
G02X1614630Y555147I319J-317D01*
G01X1614627Y556297D02*
G03X1613499Y555828I4J-1601D01*
G01X1613489Y554190D02*
X1614313Y555014D01*
G01X1613499Y555828D02*
X1612675Y555004D01*
G01X1611792Y553486D02*
G03X1613489Y554190I-5J2408D01*
G01X1612675Y555004D02*
G02X1611790Y554636I-889J890D01*
G01X1611668Y553486D02*
X1611792D01*
G01X1611790Y554636D02*
X1611668D01*
G01X1610770Y552588D02*
G02X1611668Y553486I898J0D01*
G01Y554636D02*
G03X1609620Y552588I0J-2048D01*
G01X1610770Y551604D02*
Y552588D01*
G01X1609620D02*
Y551604D01*
G01X1608564Y549398D02*
G03X1610770Y551604I0J2206D01*
G01X1609620D02*
G02X1608564Y550548I-1056J0D01*
G01X1605870Y549398D02*
X1608564D01*
G01Y550548D02*
X1605870D01*
G01X1603745Y551523D02*
G03X1605870Y549398I2125J0D01*
G01Y550548D02*
G02X1604895Y551523I0J975D01*
G01X1603745Y554675D02*
Y551523D01*
G01X1604895D02*
Y554675D01*
G01X1601795D02*
G02X1603745I975J0D01*
G01X1604895D02*
G03X1600645I-2125J0D01*
G01X1601795Y551523D02*
Y554675D01*
G01X1600645D02*
Y551523D01*
G01X1597545D02*
G03X1601795I2125J0D01*
G01X1600645D02*
G02X1598695I-975J0D01*
G01X1597545Y554675D02*
Y551523D01*
G01X1598695D02*
Y554675D01*
G01X1595595D02*
G02X1597545I975J0D01*
G01X1598695D02*
G03X1594445I-2125J0D01*
G01X1595595Y551523D02*
Y554675D01*
G01X1594445D02*
Y551523D01*
G01X1593470Y549398D02*
G03X1595595Y551523I0J2125D01*
G01X1594445D02*
G02X1593470Y550548I-975J0D01*
G01X1592737Y549398D02*
X1593470D01*
G01Y550548D02*
X1592737D01*
G01X1591181Y550043D02*
G03X1592737Y549398I1554J1550D01*
G01Y550548D02*
G02X1591996Y550856I0J1044D01*
G01X1590813Y550411D02*
X1591181Y550043D01*
G01X1591996Y550856D02*
X1591626Y551226D01*
G01X1590813Y550411D02*
X1591181Y550043D01*
G01X1591626Y551226D02*
X1591625D01*
G01X1590342Y551546D02*
G03X1590813Y550411I1602J-1D01*
G01X1591625Y551226D02*
G02X1591492Y551546I318J320D01*
G01X1590342Y565878D02*
Y551546D01*
G01X1591492D02*
Y565878D01*
G01X1589444Y566775D02*
G02X1590023Y566534I-1J-818D01*
G01X1590101Y566456D02*
G02X1590342Y565878I-577J-580D01*
G01X1591492D02*
G03X1590914Y567270I-1969J-1D01*
G01X1590023Y566534D02*
X1590101Y566456D01*
G01X1590914Y567270D02*
X1590836Y567348D01*
G01X1589444Y566775D02*
G02X1590023Y566534I-1J-818D01*
G01X1590101Y566456D02*
G02X1590342Y565878I-577J-580D01*
G01X1590837Y567348D02*
G03X1589445Y567925I-1393J-1392D01*
G01X1588971Y566775D02*
X1589444D01*
G01X1589445Y567925D02*
X1588971D01*
G01X1593199Y573093D02*
G02X1595174Y572275I0J-2793D01*
G01X1593199Y574243D02*
G02X1595988Y573089I1J-3944D01*
G01X1595174Y572275D02*
X1596836Y570613D01*
G01X1595988Y573089D02*
X1597650Y571427D01*
G01X1596836Y570613D02*
G03X1598861Y569750I2024J1942D01*
G01X1597650Y571427D02*
G03X1598861Y570900I1211J1128D01*
G01Y569750D02*
X1600214D01*
G01X1598861Y570900D02*
X1600214D01*
G01X1593442Y568629D02*
G03X1592163Y569908I-1279J0D01*
G01Y571058D02*
G02X1594592Y568629I0J-2429D01*
G01X1593442Y561362D02*
Y568629D01*
G01X1594592D02*
Y561361D01*
G01X1595922Y558864D02*
G02X1594177Y559587I0J2467D01*
G01X1594175Y559589D02*
G02X1593442Y561362I1774J1772D01*
G01X1594593D02*
G03X1594989Y560402I1357J-2D01*
G01X1595922Y558864D02*
G02X1594177Y559587I0J2467D01*
G01X1594175Y559589D02*
G02X1593442Y561362I1774J1772D01*
G01X1594991Y560401D02*
G03X1595922Y560014I932J930D01*
G01X1606127Y558864D02*
X1595922D01*
G01Y560014D02*
X1605717D01*
G01X1592965Y576210D02*
G03X1594558Y576869I1J2251D01*
G01X1592965Y577360D02*
G03X1593744Y577683I0J1101D01*
G01X1594558Y576869D02*
X1596494Y578805D01*
G01X1593744Y577683D02*
X1595680Y579619D01*
G01X1596494Y578805D02*
G02X1599198Y579925I2704J-2704D01*
G01X1595680Y579619D02*
G02X1599198Y581075I3517J-3519D01*
G01Y579925D02*
X1604383D01*
G01X1599198Y581075D02*
X1604383D01*
G01X1654356Y540398D02*
G03X1650106I-2125J0D01*
G01D02*
Y538819D01*
G01D02*
G02X1648156I-975J0D01*
G01X1651256D02*
G02X1647006I-2125J0D01*
G01X1648156D02*
Y540336D01*
G01X1647006Y538819D02*
Y540336D01*
G01X1648156D02*
G03X1643906I-2125J0D01*
G01X1647006D02*
G03X1645056I-975J0D01*
G01X1643906D02*
Y539456D01*
G01X1645056Y540336D02*
Y539456D01*
G01X1643906D02*
G02X1641956I-975J0D01*
G01X1645056D02*
G02X1640806I-2125J0D01*
G01X1641956D02*
Y540451D01*
G01X1640806Y539456D02*
Y540451D01*
G01X1641956D02*
G03X1637706I-2125J0D01*
G01X1640806D02*
G03X1638856I-975J0D01*
G01X1637706D02*
Y539388D01*
G01X1638856Y540451D02*
Y539388D01*
G01X1637706D02*
G02X1635756I-975J0D01*
G01X1638856D02*
G02X1634606I-2125J0D01*
G01X1635756D02*
Y540595D01*
G01X1634606Y539388D02*
Y540595D01*
G01X1635756D02*
G03X1631506I-2125J0D01*
G01X1634606D02*
G03X1632656I-975J0D01*
G01X1631506D02*
Y540175D01*
G01X1632656Y540595D02*
Y540175D01*
G01X1631506D02*
G02X1630531Y539200I-975J0D01*
G01X1632656Y540175D02*
G02X1630531Y538050I-2125J0D01*
G01Y539200D02*
X1620552D01*
G01X1630531Y538050D02*
X1620553D01*
G01X1620552Y539200D02*
G03X1618819Y538482I0J-2451D01*
G01X1620553Y538050D02*
G03X1619633Y537668I1J-1301D01*
G01X1618819Y538482D02*
X1618250Y537912D01*
G01X1619633Y537668D02*
X1619064Y537099D01*
G01X1618250Y537912D02*
G02X1617375Y537550I-874J875D01*
G01X1619064Y537099D02*
G02X1617375Y536400I-1688J1688D01*
G01Y537550D02*
X1599120D01*
G01X1617375Y536400D02*
X1599121D01*
G01X1599120Y537550D02*
G03X1594003Y535430I1J-7238D01*
G01X1599121Y536400D02*
G03X1594817Y534616I1J-6087D01*
G01X1592680Y538509D02*
G02X1598041Y540730I5362J-5362D01*
G01X1593494Y537695D02*
G02X1598042Y539580I4549J-4547D01*
G01X1598041Y540730D02*
X1615547D01*
G01X1598042Y539580D02*
X1615547D01*
G01Y540730D02*
G03X1617218Y541422I0J2364D01*
G01X1615547Y539580D02*
G03X1618032Y540608I1J3514D01*
G01X1617218Y541422D02*
X1619929Y544133D01*
G01X1618032Y540608D02*
X1620743Y543319D01*
G01X1619929Y544133D02*
G02X1623500Y545611I3570J-3572D01*
G01X1620743Y543319D02*
G02X1623500Y544461I2757J-2757D01*
G01Y545611D02*
X1632008D01*
G01X1623500Y544461D02*
X1632008D01*
G01Y545611D02*
G03X1632983Y546586I0J975D01*
G01X1632008Y544461D02*
G03X1634133Y546586I0J2125D01*
G01X1632983Y546626D02*
G02X1637233I2125J0D01*
G01X1634133D02*
G02X1636083I975J0D01*
G01X1637233Y546586D02*
G03X1639183I975J0D01*
G01X1636083D02*
G03X1640333I2125J0D01*
G01X1639183Y546625D02*
G02X1643433I2125J0D01*
G01X1640333D02*
G02X1642283I975J0D01*
G01X1643433Y546586D02*
G03X1645383I975J0D01*
G01X1642283D02*
G03X1646533I2125J0D01*
G01X1645383Y546628D02*
G02X1649633I2125J0D01*
G01X1646533D02*
G02X1648483I975J0D01*
G01X1649633Y546586D02*
G03X1651583I975J0D01*
G01X1648483D02*
G03X1652733I2125J0D01*
G01X1653204Y550750D02*
X1648780D01*
G01X1653203Y551900D02*
X1648780D01*
G01Y550750D02*
G02X1646785Y552745I0J1995D01*
G01X1648780Y551900D02*
G02X1647935Y552745I0J845D01*
G01X1646785D02*
Y553765D01*
G01X1647935Y552745D02*
Y553765D01*
G01X1646785D02*
G03X1644835I-975J0D01*
G01X1647935D02*
G03X1643685I-2125J0D01*
G01X1644835D02*
Y552875D01*
G01X1643685Y553765D02*
Y552875D01*
G01X1644835D02*
G02X1642710Y550750I-2125J0D01*
G01X1643685Y552875D02*
G02X1642710Y551900I-975J0D01*
G01Y550750D02*
X1632999D01*
G01X1642710Y551900D02*
X1632998D01*
G01X1632999Y550750D02*
G03X1632414Y550507I1J-828D01*
G01X1632998Y551900D02*
G03X1631600Y551321I0J-1978D01*
G01X1632414Y550507D02*
X1630354Y548448D01*
G01X1631600Y551321D02*
X1629540Y549262D01*
G01X1630354Y548448D02*
G02X1628336Y547612I-2018J2018D01*
G01X1629540Y549262D02*
G02X1628335Y548762I-1206J1203D01*
G01X1628336Y547612D02*
X1621006D01*
G01X1628335Y548762D02*
X1621005D01*
G01X1621006Y547612D02*
G03X1619674Y547060I1J-1885D01*
G01X1621005Y548762D02*
G03X1618860Y547874I0J-3035D01*
G01X1619674Y547060D02*
X1616753Y544139D01*
G01X1618860Y547874D02*
X1615939Y544953D01*
G01X1616753Y544139D02*
G02X1614001Y543000I-2751J2752D01*
G01X1615939Y544953D02*
G02X1614002Y544150I-1938J1937D01*
G01X1614001Y543000D02*
X1594588D01*
G01X1614002Y544150D02*
X1594588D01*
G01Y543000D02*
G03X1594269Y542868I0J-451D01*
G01X1594588Y544150D02*
G03X1593455Y543682I-1J-1602D01*
G01X1594269Y542868D02*
X1594268D01*
G01D02*
X1593035Y541635D01*
G01X1593454Y543682D02*
X1592221Y542449D01*
G01X1593035Y541635D02*
G02X1590029I-1503J1502D01*
G01X1592221Y542449D02*
G02X1590843I-689J688D01*
G01X1590029Y541635D02*
X1589045Y542619D01*
G01X1590843Y542449D02*
X1589858Y543433D01*
G01X1609718Y547402D02*
G03X1610872Y547880I0J1632D01*
G01X1609717Y546252D02*
G03X1611686Y547066I2J2783D01*
G01X1610872Y547880D02*
X1615289Y552297D01*
G01X1611686Y547066D02*
X1616103Y551483D01*
G01X1615289Y552297D02*
G02X1616923Y552973I1633J-1633D01*
G01X1616103Y551483D02*
G02X1616923Y551823I820J-819D01*
G01Y552973D02*
X1626374D01*
G01X1616923Y551823D02*
X1626374D01*
G01Y552973D02*
G03X1627512Y554111I0J1138D01*
G01X1626374Y551823D02*
G03X1628662Y554111I0J2288D01*
G01X1627512D02*
Y556347D01*
G01X1628662Y554111D02*
Y556347D01*
G01X1627512D02*
G02X1628425Y558554I3121J1D01*
G01X1628662Y556347D02*
G02X1629239Y557740I1970J0D01*
G01X1628425Y558554D02*
X1630040Y560169D01*
G01X1629239Y557740D02*
X1630854Y559355D01*
G01X1630040Y560169D02*
G03X1630418Y561078I-910J911D01*
G01X1630854Y559355D02*
G03X1631568Y561079I-1724J1724D01*
G01X1630418Y561078D02*
Y561213D01*
G01X1631568Y561079D02*
Y561213D01*
G01X1630418D02*
G02X1635304I2443J0D01*
G01X1631568D02*
G02X1634154I1293J0D01*
G01X1635304D02*
Y560288D01*
G01X1634154Y561213D02*
Y560288D01*
G01X1635304D02*
G03X1636433Y559159I1129J0D01*
G01X1634154Y560288D02*
G03X1636433Y558009I2279J0D01*
G01Y559159D02*
X1638452D01*
G01X1636433Y558009D02*
X1638452D01*
G01Y559159D02*
G03X1639485Y560192I0J1033D01*
G01X1638452Y558009D02*
G03X1640635Y560192I0J2183D01*
G01X1639485D02*
Y561499D01*
G01X1640635Y560192D02*
Y561499D01*
G01X1639485D02*
G02X1643835I2175J0D01*
G01X1640635D02*
G02X1642685I1025J0D01*
G01X1643835D02*
Y560251D01*
G01X1642685Y561499D02*
Y560251D01*
G01X1643835D02*
G03X1644927Y559159I1092J0D01*
G01X1642685Y560251D02*
G03X1644927Y558009I2242J0D01*
G01Y559159D02*
X1648789D01*
G01X1644927Y558009D02*
X1648789D01*
G01Y559159D02*
G03X1650400Y560770I0J1611D01*
G01X1648789Y558009D02*
G03X1651550Y560770I0J2761D01*
G01X1650400D02*
Y571174D01*
G01D02*
G03X1648618Y572956I-1782J0D01*
G01X1651550Y571174D02*
G03X1648618Y574106I-2932J0D01*
G01Y572956D02*
X1637075D01*
G01X1648618Y574106D02*
X1637075D01*
G01Y572956D02*
G02Y577306I0J2175D01*
G01Y574106D02*
G02Y576156I0J1025D01*
G01Y577306D02*
X1648937D01*
G01X1637075Y576156D02*
X1648937D01*
G01Y577306D02*
G03X1649500Y577869I0J563D01*
G01X1648937Y576156D02*
G03X1650650Y577869I0J1713D01*
G01X1649500D02*
Y579265D01*
G01D02*
G02X1651229Y581171I1915J0D01*
G01X1649500Y579265D02*
G02X1651229Y581171I1915J0D01*
G01X1589445Y567925D02*
X1588971D01*
G01Y566775D02*
X1589444D01*
G01X1591492Y565878D02*
G03X1590914Y567270I-1969J-1D01*
G01X1590837Y567348D02*
G03X1589445Y567925I-1393J-1392D01*
G01X1589444Y566775D02*
G02X1590023Y566534I-1J-818D01*
G01X1590914Y567270D02*
X1590836Y567348D01*
G01X1590023Y566534D02*
X1590101Y566456D01*
G01X1591492Y565878D02*
G03X1590914Y567270I-1969J-1D01*
G01X1590837Y567348D02*
G03X1589445Y567925I-1393J-1392D01*
G01X1590101Y566456D02*
G02X1590342Y565878I-577J-580D01*
G01X1591492Y551546D02*
Y565878D01*
G01X1590342D02*
Y551546D01*
G01X1591625Y551226D02*
G02X1591492Y551546I318J320D01*
G01X1590342D02*
G03X1590813Y550411I1602J-1D01*
G01X1591996Y550856D02*
X1591626Y551226D01*
G01D02*
X1591625D01*
G01X1590813Y550411D02*
X1591181Y550043D01*
G01X1592737Y550548D02*
G02X1591996Y550856I0J1044D01*
G01X1591181Y550043D02*
G03X1592737Y549398I1554J1550D01*
G01X1593470Y550548D02*
X1592737D01*
G01Y549398D02*
X1593470D01*
G01X1594445Y551523D02*
G02X1593470Y550548I-975J0D01*
G01Y549398D02*
G03X1595595Y551523I0J2125D01*
G01X1594445Y554675D02*
Y551523D01*
G01X1595595D02*
Y554675D01*
G01X1598695D02*
G03X1594445I-2125J0D01*
G01X1595595D02*
G02X1597545I975J0D01*
G01X1598695Y551523D02*
Y554675D01*
G01X1597545D02*
Y551523D01*
G01X1600645D02*
G02X1598695I-975J0D01*
G01X1597545D02*
G03X1601795I2125J0D01*
G01X1600645Y554675D02*
Y551523D01*
G01X1601795D02*
Y554675D01*
G01X1604895D02*
G03X1600645I-2125J0D01*
G01X1601795D02*
G02X1603745I975J0D01*
G01X1604895Y551523D02*
Y554675D01*
G01X1603745D02*
Y551523D01*
G01X1605870Y550548D02*
G02X1604895Y551523I0J975D01*
G01X1603745D02*
G03X1605870Y549398I2125J0D01*
G01X1608564Y550548D02*
X1605870D01*
G01Y549398D02*
X1608564D01*
G01X1609620Y551604D02*
G02X1608564Y550548I-1056J0D01*
G01Y549398D02*
G03X1610770Y551604I0J2206D01*
G01X1609620Y552588D02*
Y551604D01*
G01X1610770D02*
Y552588D01*
G01X1611668Y554636D02*
G03X1609620Y552588I0J-2048D01*
G01X1610770D02*
G02X1611668Y553486I898J0D01*
G01X1611790Y554636D02*
X1611668D01*
G01Y553486D02*
X1611792D01*
G01X1612675Y555004D02*
G02X1611790Y554636I-889J890D01*
G01X1611792Y553486D02*
G03X1613489Y554190I-5J2408D01*
G01X1613499Y555828D02*
X1612675Y555004D01*
G01X1613489Y554190D02*
X1614313Y555014D01*
G01X1614627Y556297D02*
G03X1613499Y555828I4J-1601D01*
G01X1614313Y555014D02*
G02X1614630Y555147I319J-317D01*
G01X1616804Y556302D02*
X1614627Y556297D01*
G01X1614630Y555147D02*
X1616805Y555151D01*
G01X1617654Y557148D02*
G02X1616806Y556301I-847J0D01*
G01X1616805Y555151D02*
G03X1618804Y557148I2J1997D01*
G01X1617654Y557326D02*
Y557148D01*
G01X1618804D02*
Y557326D01*
G01X1616629Y558351D02*
G02X1617654Y557326I0J-1025D01*
G01X1618804D02*
G03X1616629Y559501I-2175J0D01*
G01X1615834Y558351D02*
X1616629D01*
G01Y559501D02*
X1615834D01*
G01X1613659Y560526D02*
G03X1615834Y558351I2175J0D01*
G01Y559501D02*
G02X1614809Y560526I0J1025D01*
G01X1613659Y561230D02*
Y560526D01*
G01X1614809D02*
Y561230D01*
G01X1615834Y563405D02*
G03X1613659Y561230I0J-2175D01*
G01X1614809D02*
G02X1615834Y562255I1025J0D01*
G01X1617142Y564713D02*
G02X1615834Y563405I-1308J0D01*
G01Y562255D02*
G03X1618292Y564713I0J2458D01*
G01X1617142Y565469D02*
Y564713D01*
G01X1618292D02*
Y565469D01*
G01X1621492D02*
G03X1617142I-2175J0D01*
G01X1618292D02*
G02X1620342I1025J0D01*
G01X1621492Y559881D02*
Y565469D01*
G01X1620342D02*
Y559881D01*
G01X1623541Y557832D02*
G02X1621492Y559881I0J2049D01*
G01X1620342D02*
G03X1623541Y556682I3199J0D01*
G01X1624644Y557832D02*
X1623541D01*
G01Y556682D02*
X1624644D01*
G01X1593199Y574243D02*
G02X1595988Y573089I1J-3944D01*
G01X1593199Y573093D02*
G02X1595174Y572275I0J-2793D01*
G01X1595988Y573089D02*
X1597650Y571427D01*
G01X1595174Y572275D02*
X1596836Y570613D01*
G01X1597650Y571427D02*
G03X1598861Y570900I1211J1128D01*
G01X1596836Y570613D02*
G03X1598861Y569750I2024J1942D01*
G01Y570900D02*
X1600214D01*
G01X1598861Y569750D02*
X1600214D01*
G01X1595922Y560014D02*
X1605717D01*
G01X1606127Y558864D02*
X1595922D01*
G01X1594593Y561362D02*
G03X1594989Y560402I1357J-2D01*
G01X1594991Y560401D02*
G03X1595922Y560014I932J930D01*
G01Y558864D02*
G02X1594177Y559587I0J2467D01*
G01X1594593Y561362D02*
G03X1594989Y560402I1357J-2D01*
G01X1594991Y560401D02*
G03X1595922Y560014I932J930D01*
G01X1594175Y559589D02*
G02X1593442Y561362I1774J1772D01*
G01X1594592Y568629D02*
Y561361D01*
G01X1593442Y561362D02*
Y568629D01*
G01X1592163Y571058D02*
G02X1594592Y568629I0J-2429D01*
G01X1593442D02*
G03X1592163Y569908I-1279J0D01*
G01X1592965Y577360D02*
G03X1593744Y577683I0J1101D01*
G01X1592965Y576210D02*
G03X1594558Y576869I1J2251D01*
G01X1593744Y577683D02*
X1595680Y579619D01*
G01X1594558Y576869D02*
X1596494Y578805D01*
G01X1595680Y579619D02*
G02X1599198Y581075I3517J-3519D01*
G01X1596494Y578805D02*
G02X1599198Y579925I2704J-2704D01*
G01Y581075D02*
X1604383D01*
G01X1599198Y579925D02*
X1604383D01*
G01X1651223Y16564D02*
Y9152D01*
G01D02*
X1652023Y8352D01*
G01X1650873Y7875D02*
Y6775D01*
G01X1652023Y8352D02*
Y6775D01*
G01X1651223Y16564D02*
Y9152D01*
G01D02*
X1652023Y8352D01*
G01D02*
Y6775D01*
G01X1650873Y7875D02*
Y6775D01*
G01X1658874Y18142D02*
X1659523Y16778D01*
G01X1659755Y18970D02*
X1660673Y17038D01*
G01X1659523Y16778D02*
Y10824D01*
G01X1660673Y17038D02*
Y10726D01*
G01X1665439Y23922D02*
X1667990Y22219D01*
G01X1665894Y25002D02*
X1668914Y22986D01*
G01X1667990Y22219D02*
X1669100Y19618D01*
G01X1668914Y22986D02*
X1670250Y19854D01*
G01X1669100Y19618D02*
Y6800D01*
G01X1670250Y19854D02*
Y6850D01*
G01X1670895Y25404D02*
X1672469Y24353D01*
G01X1671350Y26484D02*
X1673303Y25180D01*
G01X1672469Y24353D02*
X1678475Y15195D01*
G01X1673303Y25180D02*
X1679625Y15539D01*
G01X1678475Y15195D02*
Y12000D01*
G01X1679625Y15539D02*
Y11831D01*
G01X1687874Y11293D02*
Y17469D01*
G01X1689024Y11249D02*
Y17775D01*
G01X1687874Y17469D02*
X1684433Y23495D01*
G01X1689024Y17775D02*
X1685298Y24301D01*
G01X1684433Y23495D02*
X1679998Y26455D01*
G01X1685298Y24301D02*
X1680453Y27535D01*
G01X1659755Y18970D02*
X1660673Y17038D01*
G01X1658874Y18142D02*
X1659523Y16778D01*
G01X1660673Y17038D02*
Y10726D01*
G01X1659523Y16778D02*
Y10824D01*
G01X1665894Y25002D02*
X1668914Y22986D01*
G01X1665439Y23922D02*
X1667990Y22219D01*
G01X1668914Y22986D02*
X1670250Y19854D01*
G01X1667990Y22219D02*
X1669100Y19618D01*
G01X1670250Y19854D02*
Y6850D01*
G01X1669100Y19618D02*
Y6800D01*
G01X1671350Y26484D02*
X1673303Y25180D01*
G01X1670895Y25404D02*
X1672469Y24353D01*
G01X1673303Y25180D02*
X1679625Y15539D01*
G01X1672469Y24353D02*
X1678475Y15195D01*
G01X1679625Y15539D02*
Y11831D01*
G01X1678475Y15195D02*
Y12000D01*
G01X1689024Y11249D02*
Y17775D01*
G01X1687874Y11293D02*
Y17469D01*
G01X1689024Y17775D02*
X1685298Y24301D01*
G01X1687874Y17469D02*
X1684433Y23495D01*
G01X1685298Y24301D02*
X1680453Y27535D01*
G01X1684433Y23495D02*
X1679998Y26455D01*
G01X1653300Y41073D02*
Y39900D01*
G01X1654450Y39951D02*
Y41550D01*
G01X1650905Y48723D02*
X1656977Y42650D01*
G01X1656500Y41500D02*
X1661836D01*
G01X1656977Y42650D02*
X1662313D01*
G01X1661836Y41500D02*
X1662786Y40550D01*
G01X1662313Y42650D02*
X1663936Y41027D01*
G01X1662786Y40550D02*
Y39912D01*
G01X1663936Y41027D02*
Y40063D01*
G01X1672250Y41223D02*
Y39846D01*
G01X1673400Y39801D02*
Y41700D01*
G01X1671774Y41699D02*
X1672250Y41223D01*
G01X1673400Y41700D02*
X1672251Y42849D01*
G01X1665374Y41699D02*
X1671774D01*
G01X1672251Y42849D02*
X1665851D01*
G01X1658553Y48519D02*
X1665374Y41699D01*
G01X1665851Y42849D02*
X1659126Y49574D01*
G01X1654450Y39951D02*
Y41550D01*
G01X1653300Y41073D02*
Y39900D01*
G01X1650905Y48723D02*
X1656977Y42650D01*
G01D02*
X1662313D01*
G01X1656500Y41500D02*
X1661836D01*
G01X1662313Y42650D02*
X1663936Y41027D01*
G01X1661836Y41500D02*
X1662786Y40550D01*
G01X1663936Y41027D02*
Y40063D01*
G01X1662786Y40550D02*
Y39912D01*
G01X1665851Y42849D02*
X1659126Y49574D01*
G01X1658553Y48519D02*
X1665374Y41699D01*
G01X1672251Y42849D02*
X1665851D01*
G01X1665374Y41699D02*
X1671774D01*
G01X1673400Y41700D02*
X1672251Y42849D01*
G01X1671774Y41699D02*
X1672250Y41223D01*
G01X1673400Y39801D02*
Y41700D01*
G01X1672250Y41223D02*
Y39846D01*
G01X1666949Y45350D02*
X1660393Y51907D01*
G01X1659820Y50852D02*
X1666472Y44200D01*
G01X1673650Y45350D02*
X1666949D01*
G01X1666472Y44200D02*
X1673173D01*
G01X1675649Y43351D02*
X1673650Y45350D01*
G01X1673173Y44200D02*
X1675172Y42201D01*
G01X1681149Y43351D02*
X1675649D01*
G01X1675172Y42201D02*
X1680672D01*
G01X1682750Y41750D02*
X1681149Y43351D01*
G01X1680672Y42201D02*
X1681600Y41273D01*
G01X1682750Y39850D02*
Y41750D01*
G01X1681600Y41273D02*
Y39900D01*
G01Y41273D02*
Y39900D01*
G01X1682750Y39850D02*
Y41750D01*
G01X1680672Y42201D02*
X1681600Y41273D01*
G01X1682750Y41750D02*
X1681149Y43351D01*
G01X1675172Y42201D02*
X1680672D01*
G01X1681149Y43351D02*
X1675649D01*
G01X1673173Y44200D02*
X1675172Y42201D01*
G01X1675649Y43351D02*
X1673650Y45350D01*
G01X1666472Y44200D02*
X1673173D01*
G01X1673650Y45350D02*
X1666949D01*
G01X1659820Y50852D02*
X1666472Y44200D01*
G01X1666949Y45350D02*
X1660393Y51907D01*
G01X1668049Y47850D02*
X1661622Y54277D01*
G01X1661049Y53222D02*
X1667572Y46700D01*
G01X1674978Y47850D02*
X1668049D01*
G01X1667572Y46700D02*
X1674501D01*
G01X1676439Y46389D02*
X1674978Y47850D01*
G01X1674501Y46700D02*
X1675962Y45239D01*
G01X1683311Y46389D02*
X1676439D01*
G01X1675962Y45239D02*
X1683049D01*
G01X1691409Y42501D02*
X1683311Y46389D01*
G01X1683049Y45239D02*
X1690734Y41549D01*
G01X1692250Y41660D02*
X1691409Y42501D01*
G01X1690734Y41549D02*
X1691100Y41183D01*
G01X1692250Y39751D02*
Y41660D01*
G01X1691100Y41183D02*
Y39900D01*
G01Y41183D02*
Y39900D01*
G01X1692250Y39751D02*
Y41660D01*
G01X1690734Y41549D02*
X1691100Y41183D01*
G01X1692250Y41660D02*
X1691409Y42501D01*
G01X1683049Y45239D02*
X1690734Y41549D01*
G01X1691409Y42501D02*
X1683311Y46389D01*
G01X1675962Y45239D02*
X1683049D01*
G01X1683311Y46389D02*
X1676439D01*
G01X1674501Y46700D02*
X1675962Y45239D01*
G01X1676439Y46389D02*
X1674978Y47850D01*
G01X1667572Y46700D02*
X1674501D01*
G01X1674978Y47850D02*
X1668049D01*
G01X1661049Y53222D02*
X1667572Y46700D01*
G01X1668049Y47850D02*
X1661622Y54277D01*
G01X1711906Y49767D02*
X1716497Y50702D01*
G01X1716510Y49531D02*
X1711906Y48593D01*
G01X1706652Y50837D02*
X1711906Y49767D01*
G01Y48593D02*
X1706203Y49754D01*
G01X1704203Y52458D02*
X1706652Y50837D01*
G01X1706203Y49754D02*
X1703754Y51375D01*
G01X1691219Y55100D02*
X1704203Y52458D01*
G01X1703754Y51375D02*
X1691219Y53926D01*
G01X1687279Y54298D02*
X1691219Y55100D01*
G01Y53926D02*
X1687279Y53124D01*
G01X1682412Y55289D02*
X1687279Y54298D01*
G01Y53124D02*
X1682183Y54162D01*
G01X1682412Y55289D02*
X1687279Y54298D01*
G01X1682183Y54162D02*
X1681911D01*
G01X1680146Y57555D02*
X1682412Y55289D01*
G01X1681911Y54162D02*
X1679577Y56496D01*
G01X1671824Y59246D02*
X1680146Y57555D01*
G01X1679577Y56496D02*
X1671826Y58071D01*
G01X1669688Y58819D02*
X1671824Y59246D01*
G01X1671826Y58071D02*
X1669681Y57644D01*
G01X1671826Y58071D02*
X1669681Y57644D01*
G01X1669688Y58819D02*
X1671824Y59246D01*
G01X1679577Y56496D02*
X1671826Y58071D01*
G01X1671824Y59246D02*
X1680146Y57555D01*
G01X1681911Y54162D02*
X1679577Y56496D01*
G01X1680146Y57555D02*
X1682412Y55289D01*
G01X1687279Y53124D02*
X1682183Y54162D01*
G01D02*
X1681911D01*
G01X1682412Y55289D02*
X1687279Y54298D01*
G01X1691219Y53926D02*
X1687279Y53124D01*
G01Y54298D02*
X1691219Y55100D01*
G01X1703754Y51375D02*
X1691219Y53926D01*
G01Y55100D02*
X1704203Y52458D01*
G01X1706203Y49754D02*
X1703754Y51375D01*
G01X1704203Y52458D02*
X1706652Y50837D01*
G01X1711906Y48593D02*
X1706203Y49754D01*
G01X1706652Y50837D02*
X1711906Y49767D01*
G01X1716510Y49531D02*
X1711906Y48593D01*
G01Y49767D02*
X1716497Y50702D01*
G01X1708677Y43861D02*
X1711697Y43253D01*
G01X1715622Y41294D02*
X1708228Y42778D01*
G01X1699357Y50029D02*
X1708677Y43861D01*
G01X1708228Y42778D02*
X1698908Y48946D01*
G01X1697398Y50428D02*
X1699357Y50029D01*
G01X1698908Y48946D02*
X1697398Y49254D01*
G01X1692516Y49434D02*
X1697398Y50428D01*
G01Y49254D02*
X1692517Y48260D01*
G01X1690335Y49876D02*
X1692516Y49434D01*
G01X1692517Y48260D02*
X1689887Y48793D01*
G01X1687822Y51540D02*
X1688008Y51417D01*
G01Y51416D02*
X1690335Y49876D01*
G01X1689887Y48793D02*
X1687373Y50457D01*
G01X1681387Y52850D02*
X1687822Y51540D01*
G01X1687373Y50457D02*
X1681387Y51676D01*
G01X1679257Y52416D02*
X1681387Y52850D01*
G01Y51676D02*
X1679257Y51242D01*
G01X1676901Y52896D02*
X1679257Y52416D01*
G01Y51242D02*
X1676452Y51813D01*
G01X1673042Y55451D02*
X1676901Y52896D01*
G01X1676452Y51813D02*
X1672592Y54369D01*
G01X1676452Y51813D02*
X1672592Y54369D01*
G01X1673042Y55451D02*
X1676901Y52896D01*
G01X1679257Y51242D02*
X1676452Y51813D01*
G01X1676901Y52896D02*
X1679257Y52416D01*
G01X1681387Y51676D02*
X1679257Y51242D01*
G01Y52416D02*
X1681387Y52850D01*
G01X1687373Y50457D02*
X1681387Y51676D01*
G01Y52850D02*
X1687822Y51540D01*
G01X1689887Y48793D02*
X1687373Y50457D01*
G01X1687822Y51540D02*
X1688008Y51417D01*
G01X1689887Y48793D02*
X1687373Y50457D01*
G01X1688008Y51416D02*
X1690335Y49876D01*
G01X1692517Y48260D02*
X1689887Y48793D01*
G01X1690335Y49876D02*
X1692516Y49434D01*
G01X1697398Y49254D02*
X1692517Y48260D01*
G01X1692516Y49434D02*
X1697398Y50428D01*
G01X1698908Y48946D02*
X1697398Y49254D01*
G01Y50428D02*
X1699357Y50029D01*
G01X1708228Y42778D02*
X1698908Y48946D01*
G01X1699357Y50029D02*
X1708677Y43861D01*
G01X1715622Y41294D02*
X1708228Y42778D01*
G01X1708677Y43861D02*
X1711697Y43253D01*
G01X1715622Y41294D02*
X1708228Y42778D01*
G01X1712215Y58916D02*
X1716418Y59765D01*
G01X1716417Y58591D02*
X1712214Y57742D01*
G01X1692925Y62841D02*
X1712215Y58916D01*
G01X1712214Y57742D02*
X1692925Y61667D01*
G01X1689706Y62186D02*
X1692925Y62841D01*
G01Y61667D02*
X1689706Y61012D01*
G01X1686149Y62910D02*
X1689706Y62186D01*
G01Y61012D02*
X1685700Y61827D01*
G01X1685158Y63566D02*
X1686149Y62910D01*
G01X1685700Y61827D02*
X1684328Y62736D01*
G01X1683514Y66050D02*
X1685158Y63566D01*
G01X1684328Y62736D02*
X1682684Y65220D01*
G01X1681038Y67688D02*
X1683514Y66050D01*
G01X1682684Y65220D02*
X1680589Y66605D01*
G01X1676348Y68644D02*
X1681038Y67688D01*
G01X1680589Y66605D02*
X1678435Y67044D01*
G01X1676348Y68644D02*
X1681038Y67688D01*
G01X1678435Y67044D02*
X1678434D01*
G01X1676348Y68644D02*
X1681038Y67688D01*
G01X1678433Y67043D02*
X1676346Y67470D01*
G01X1666418Y66657D02*
X1676348Y68644D01*
G01X1676346Y67470D02*
X1666418Y65484D01*
G01X1661899Y67561D02*
X1666418Y66657D01*
G01Y65484D02*
X1661594Y66449D01*
G01X1666418Y65484D02*
X1661594Y66449D01*
G01X1661899Y67561D02*
X1666418Y66657D01*
G01X1676346Y67470D02*
X1666418Y65484D01*
G01Y66657D02*
X1676348Y68644D01*
G01X1680589Y66605D02*
X1678435Y67044D01*
G01D02*
X1678434D01*
G01X1678433Y67043D02*
X1676346Y67470D01*
G01X1676348Y68644D02*
X1681038Y67688D01*
G01X1682684Y65220D02*
X1680589Y66605D01*
G01X1681038Y67688D02*
X1683514Y66050D01*
G01X1684328Y62736D02*
X1682684Y65220D01*
G01X1683514Y66050D02*
X1685158Y63566D01*
G01X1685700Y61827D02*
X1684328Y62736D01*
G01X1685158Y63566D02*
X1686149Y62910D01*
G01X1689706Y61012D02*
X1685700Y61827D01*
G01X1686149Y62910D02*
X1689706Y62186D01*
G01X1692925Y61667D02*
X1689706Y61012D01*
G01Y62186D02*
X1692925Y62841D01*
G01X1712214Y57742D02*
X1692925Y61667D01*
G01Y62841D02*
X1712215Y58916D01*
G01X1716417Y58591D02*
X1712214Y57742D01*
G01X1712215Y58916D02*
X1716418Y59765D01*
G01X1715944Y63058D02*
X1711323Y66117D01*
G01X1715496Y61975D02*
X1710874Y65034D01*
G01X1711323Y66117D02*
X1698199Y68788D01*
G01X1710874Y65034D02*
X1698199Y67614D01*
G01Y68788D02*
X1692611Y67652D01*
G01X1698199Y67614D02*
X1692611Y66478D01*
G01Y67652D02*
X1682985Y69608D01*
G01X1692611Y66478D02*
X1682537Y68525D01*
G01X1682985Y69608D02*
X1680611Y71180D01*
G01X1682537Y68525D02*
X1680162Y70097D01*
G01X1680611Y71180D02*
X1676547Y72006D01*
G01X1680162Y70097D02*
X1676219Y70899D01*
G01X1676547Y72006D02*
X1671642Y73943D01*
G01Y73944D02*
X1666740Y75879D01*
G01X1676219Y70899D02*
X1666405Y74774D01*
G01X1666740Y75879D02*
X1657580Y77851D01*
G01X1666405Y74774D02*
X1657103Y76777D01*
G01X1715496Y61975D02*
X1710874Y65034D01*
G01X1715944Y63058D02*
X1711323Y66117D01*
G01X1710874Y65034D02*
X1698199Y67614D01*
G01X1711323Y66117D02*
X1698199Y68788D01*
G01Y67614D02*
X1692611Y66478D01*
G01X1698199Y68788D02*
X1692611Y67652D01*
G01Y66478D02*
X1682537Y68525D01*
G01X1692611Y67652D02*
X1682985Y69608D01*
G01X1682537Y68525D02*
X1680162Y70097D01*
G01X1682985Y69608D02*
X1680611Y71180D01*
G01X1680162Y70097D02*
X1676219Y70899D01*
G01X1680611Y71180D02*
X1676547Y72006D01*
G01X1676219Y70899D02*
X1666405Y74774D01*
G01X1676547Y72006D02*
X1671642Y73943D01*
G01X1676219Y70899D02*
X1666405Y74774D01*
G01X1671642Y73944D02*
X1666740Y75879D01*
G01X1666405Y74774D02*
X1657103Y76777D01*
G01X1666740Y75879D02*
X1657580Y77851D01*
G01X1663609Y64161D02*
X1676698Y61498D01*
G01X1663302Y63049D02*
X1676468Y60370D01*
G01X1676698Y61498D02*
X1679620Y62093D01*
G01X1676927Y60371D02*
X1679620Y60919D01*
G01Y62093D02*
X1682303Y61547D01*
G01X1679620Y60919D02*
X1681854Y60464D01*
G01X1682303Y61547D02*
X1685035Y59740D01*
G01X1681854Y60464D02*
X1684399Y58779D01*
G01X1685035Y59740D02*
X1688180Y59100D01*
G01X1684565Y58613D02*
X1684806D01*
G01X1685035Y59740D02*
X1688180Y59100D01*
G01X1684806Y58613D02*
X1688180Y57926D01*
G01Y59100D02*
X1692914Y60063D01*
G01X1688180Y57926D02*
X1692914Y58889D01*
G01Y60063D02*
X1702185Y58177D01*
G01X1692914Y58889D02*
X1701736Y57094D01*
G01X1702185Y58177D02*
X1709063Y53623D01*
G01X1701736Y57094D02*
X1708614Y52540D01*
G01X1709063Y53623D02*
X1711651Y53097D01*
G01X1708614Y52540D02*
X1711650Y51923D01*
G01X1711651Y53097D02*
X1714763Y53724D01*
G01X1711650Y51923D02*
X1715213Y52641D01*
G01X1663302Y63049D02*
X1676468Y60370D01*
G01X1663609Y64161D02*
X1676698Y61498D01*
G01X1676927Y60371D02*
X1679620Y60919D01*
G01X1676698Y61498D02*
X1679620Y62093D01*
G01Y60919D02*
X1681854Y60464D01*
G01X1679620Y62093D02*
X1682303Y61547D01*
G01X1681854Y60464D02*
X1684399Y58779D01*
G01X1682303Y61547D02*
X1685035Y59740D01*
G01X1684565Y58613D02*
X1684806D01*
G01D02*
X1688180Y57926D01*
G01X1685035Y59740D02*
X1688180Y59100D01*
G01Y57926D02*
X1692914Y58889D01*
G01X1688180Y59100D02*
X1692914Y60063D01*
G01Y58889D02*
X1701736Y57094D01*
G01X1692914Y60063D02*
X1702185Y58177D01*
G01X1701736Y57094D02*
X1708614Y52540D01*
G01X1702185Y58177D02*
X1709063Y53623D01*
G01X1708614Y52540D02*
X1711650Y51923D01*
G01X1709063Y53623D02*
X1711651Y53097D01*
G01X1711650Y51923D02*
X1715213Y52641D01*
G01X1711651Y53097D02*
X1714763Y53724D01*
G01X1712954Y68815D02*
X1698442Y71765D01*
G01X1712505Y67732D02*
X1698442Y70591D01*
G01Y71765D02*
X1693888Y70838D01*
G01X1698442Y70591D02*
X1693888Y69664D01*
G01Y70838D02*
X1688649Y71904D01*
G01X1693888Y69664D02*
X1688200Y70821D01*
G01X1688649Y71904D02*
X1687078Y72942D01*
G01X1688200Y70821D02*
X1686248Y72112D01*
G01X1687078Y72942D02*
X1684941Y76170D01*
G01X1686248Y72112D02*
X1684111Y75340D01*
G01X1684941Y76170D02*
X1682667Y77675D01*
G01X1684111Y75340D02*
X1682218Y76592D01*
G01X1682667Y77675D02*
X1677051Y78818D01*
G01X1682218Y76592D02*
X1677051Y77644D01*
G01Y78818D02*
X1673251Y78044D01*
G01X1677051Y77644D02*
X1673251Y76870D01*
G01Y78044D02*
X1671517Y78397D01*
G01X1673251Y76870D02*
X1672364Y77050D01*
G01X1673251Y78044D02*
X1671517Y78397D01*
G01D02*
X1667807Y79152D01*
G01D02*
X1666566Y79404D01*
G01X1672364Y77050D02*
X1666562Y78230D01*
G01X1666566Y79404D02*
X1665652Y79219D01*
G01X1666562Y78230D02*
X1665652Y78045D01*
G01Y79219D02*
X1658479Y80680D01*
G01X1665652Y78045D02*
X1658030Y79597D01*
G01X1658479Y80680D02*
X1656771Y81810D01*
G01X1658030Y79597D02*
X1656089Y80882D01*
G01X1656770Y81809D02*
X1651835Y85434D01*
G01X1656089Y80882D02*
X1651300Y84400D01*
G01X1651835Y85434D02*
X1650554Y85861D01*
G01X1712505Y67732D02*
X1698442Y70591D01*
G01X1712954Y68815D02*
X1698442Y71765D01*
G01Y70591D02*
X1693888Y69664D01*
G01X1698442Y71765D02*
X1693888Y70838D01*
G01Y69664D02*
X1688200Y70821D01*
G01X1693888Y70838D02*
X1688649Y71904D01*
G01X1688200Y70821D02*
X1686248Y72112D01*
G01X1688649Y71904D02*
X1687078Y72942D01*
G01X1686248Y72112D02*
X1684111Y75340D01*
G01X1687078Y72942D02*
X1684941Y76170D01*
G01X1684111Y75340D02*
X1682218Y76592D01*
G01X1684941Y76170D02*
X1682667Y77675D01*
G01X1682218Y76592D02*
X1677051Y77644D01*
G01X1682667Y77675D02*
X1677051Y78818D01*
G01Y77644D02*
X1673251Y76870D01*
G01X1677051Y78818D02*
X1673251Y78044D01*
G01Y76870D02*
X1672364Y77050D01*
G01D02*
X1666562Y78230D01*
G01X1673251Y78044D02*
X1671517Y78397D01*
G01X1672364Y77050D02*
X1666562Y78230D01*
G01X1671517Y78397D02*
X1667807Y79152D01*
G01X1672364Y77050D02*
X1666562Y78230D01*
G01X1667807Y79152D02*
X1666566Y79404D01*
G01X1666562Y78230D02*
X1665652Y78045D01*
G01X1666566Y79404D02*
X1665652Y79219D01*
G01Y78045D02*
X1658030Y79597D01*
G01X1665652Y79219D02*
X1658479Y80680D01*
G01X1658030Y79597D02*
X1656089Y80882D01*
G01X1658479Y80680D02*
X1656771Y81810D01*
G01X1656089Y80882D02*
X1651300Y84400D01*
G01X1656770Y81809D02*
X1651835Y85434D01*
G01D02*
X1650554Y85861D01*
G01X1650511Y499230D02*
X1664514D01*
G01X1650988Y498080D02*
X1652338D01*
G01X1650511Y499230D02*
X1664514D01*
G01X1654988Y498080D02*
X1664991D01*
G01X1664514Y499230D02*
X1669936Y504652D01*
G01X1664991Y498080D02*
X1670413Y503502D01*
G01X1669936Y504652D02*
X1674902D01*
G01X1670413Y503502D02*
X1674425D01*
G01X1674902Y504652D02*
X1685300Y494254D01*
G01X1674425Y503502D02*
X1684823Y493104D01*
G01X1685300Y494254D02*
X1712496D01*
G01X1684823Y493104D02*
X1712019D01*
G01D02*
X1715016Y490107D01*
G01X1650988Y498080D02*
X1652338D01*
G01X1650988D02*
X1652338D01*
G01X1654988D02*
X1664991D01*
G01X1650511Y499230D02*
X1664514D01*
G01X1664991Y498080D02*
X1670413Y503502D01*
G01X1664514Y499230D02*
X1669936Y504652D01*
G01X1670413Y503502D02*
X1674425D01*
G01X1669936Y504652D02*
X1674902D01*
G01X1674425Y503502D02*
X1684823Y493104D01*
G01X1674902Y504652D02*
X1685300Y494254D01*
G01X1684823Y493104D02*
X1712019D01*
G01X1685300Y494254D02*
X1712496D01*
G01X1712019Y493104D02*
X1715016Y490107D01*
G01X1683075Y548412D02*
Y543856D01*
G01X1681925Y548412D02*
Y543857D01*
G01X1683075Y543856D02*
G02X1682593Y542691I-1650J1D01*
G01X1681925Y543857D02*
G02X1681779Y543504I-500J0D01*
G01X1682593Y542691D02*
X1678434Y538532D01*
G01X1681779Y543504D02*
X1677621Y539346D01*
G01X1678434Y538532D02*
G02X1677269Y538050I-1166J1168D01*
G01X1677621Y539346D02*
G02X1677268Y539200I-353J354D01*
G01X1677269Y538050D02*
X1661056D01*
G01X1677268Y539200D02*
X1661056D01*
G01Y538050D02*
G02X1659406Y539700I0J1650D01*
G01X1661056Y539200D02*
G02X1660556Y539700I0J500D01*
G01X1659406D02*
Y540360D01*
G01X1660556Y539700D02*
Y540360D01*
G01X1659406D02*
G03X1657456I-975J0D01*
G01X1660556D02*
G03X1656306I-2125J0D01*
G01X1657456D02*
Y538681D01*
G01X1656306Y540360D02*
Y538681D01*
G01X1657456D02*
G02X1653206I-2125J0D01*
G01X1656306D02*
G02X1654356I-975J0D01*
G01X1653206D02*
Y540398D01*
G01X1654356Y538681D02*
Y540398D01*
G01X1653206D02*
G03X1651256I-975J0D01*
G01D02*
Y538819D01*
G01X1652733Y546586D02*
G02X1654683I975J0D01*
G01X1651583D02*
G02X1655833I2125J0D01*
G01X1654683D02*
G03X1656808Y544461I2125J0D01*
G01X1655833Y546586D02*
G03X1656808Y545611I975J0D01*
G01Y544461D02*
X1659065D01*
G01X1656808Y545611D02*
X1659065D01*
G01Y544461D02*
G03X1660903Y545221I1J2599D01*
G01X1659065Y545611D02*
G03X1660089Y546035I0J1449D01*
G01X1660903Y545221D02*
X1661241Y545559D01*
G01X1660089Y546035D02*
X1660427Y546373D01*
G01X1661241Y545559D02*
G03X1662000Y547392I-1834J1833D01*
G01X1660427Y546373D02*
G03X1660850Y547393I-1020J1021D01*
G01X1662000Y547392D02*
Y550500D01*
G01X1660850Y547393D02*
Y550500D01*
G01X1672057Y550994D02*
Y552351D01*
G01X1670907Y551232D02*
Y552351D01*
G01X1672057D02*
G03X1670165Y554243I-1892J0D01*
G01X1670907Y552351D02*
G03X1670165Y553093I-742J0D01*
G01Y554243D02*
X1656436D01*
G01X1670165Y553093D02*
X1656437D01*
G01X1656436Y554243D02*
G03X1655270Y553760I0J-1650D01*
G01X1656437Y553093D02*
G03X1656084Y552947I0J-500D01*
G01X1655270Y553760D02*
X1653556Y552046D01*
G01X1656084Y552947D02*
X1654370Y551233D01*
G01X1653556Y552046D02*
G02X1653203Y551900I-353J354D01*
G01X1654370Y551233D02*
G02X1653204Y550750I-1166J1167D01*
G01X1651550Y560770D02*
Y571174D01*
G01X1650650Y577869D02*
Y579265D01*
G01D02*
G02X1651341Y580026I765J0D01*
G01D02*
G02X1651415Y580030I78J-761D01*
G01D02*
X1652219D01*
G01X1651229Y581171D02*
X1651358Y581184D01*
G01X1681925Y548412D02*
Y543857D01*
G01X1683075Y548412D02*
Y543856D01*
G01X1681925Y543857D02*
G02X1681779Y543504I-500J0D01*
G01X1683075Y543856D02*
G02X1682593Y542691I-1650J1D01*
G01X1681779Y543504D02*
X1677621Y539346D01*
G01X1682593Y542691D02*
X1678434Y538532D01*
G01X1677621Y539346D02*
G02X1677268Y539200I-353J354D01*
G01X1678434Y538532D02*
G02X1677269Y538050I-1166J1168D01*
G01X1677268Y539200D02*
X1661056D01*
G01X1677269Y538050D02*
X1661056D01*
G01Y539200D02*
G02X1660556Y539700I0J500D01*
G01X1661056Y538050D02*
G02X1659406Y539700I0J1650D01*
G01X1660556D02*
Y540360D01*
G01X1659406Y539700D02*
Y540360D01*
G01X1660556D02*
G03X1656306I-2125J0D01*
G01X1659406D02*
G03X1657456I-975J0D01*
G01X1656306D02*
Y538681D01*
G01X1657456Y540360D02*
Y538681D01*
G01X1656306D02*
G02X1654356I-975J0D01*
G01X1657456D02*
G02X1653206I-2125J0D01*
G01X1654356D02*
Y540398D01*
G01X1653206Y538681D02*
Y540398D01*
G01D02*
G03X1651256I-975J0D01*
G01D02*
Y538819D01*
G01X1651583Y546586D02*
G02X1655833I2125J0D01*
G01X1652733D02*
G02X1654683I975J0D01*
G01X1655833D02*
G03X1656808Y545611I975J0D01*
G01X1654683Y546586D02*
G03X1656808Y544461I2125J0D01*
G01Y545611D02*
X1659065D01*
G01X1656808Y544461D02*
X1659065D01*
G01Y545611D02*
G03X1660089Y546035I0J1449D01*
G01X1659065Y544461D02*
G03X1660903Y545221I1J2599D01*
G01X1660089Y546035D02*
X1660427Y546373D01*
G01X1660903Y545221D02*
X1661241Y545559D01*
G01X1660427Y546373D02*
G03X1660850Y547393I-1020J1021D01*
G01X1661241Y545559D02*
G03X1662000Y547392I-1834J1833D01*
G01X1660850Y547393D02*
Y550500D01*
G01X1662000Y547392D02*
Y550500D01*
G01X1670907Y551232D02*
Y552351D01*
G01X1672057Y550994D02*
Y552351D01*
G01X1670907D02*
G03X1670165Y553093I-742J0D01*
G01X1672057Y552351D02*
G03X1670165Y554243I-1892J0D01*
G01Y553093D02*
X1656437D01*
G01X1670165Y554243D02*
X1656436D01*
G01X1656437Y553093D02*
G03X1656084Y552947I0J-500D01*
G01X1656436Y554243D02*
G03X1655270Y553760I0J-1650D01*
G01X1656084Y552947D02*
X1654370Y551233D01*
G01X1655270Y553760D02*
X1653556Y552046D01*
G01X1654370Y551233D02*
G02X1653204Y550750I-1166J1167D01*
G01X1653556Y552046D02*
G02X1653203Y551900I-353J354D01*
G01X1651550Y560770D02*
Y571174D01*
G01X1650650Y577869D02*
Y579265D01*
G01D02*
G02X1651341Y580026I765J0D01*
G01D02*
G02X1651415Y580030I78J-761D01*
G01X1651229Y581171D02*
X1651358Y581184D01*
G01X1651415Y580030D02*
X1652219D01*
G01X1772335Y31976D02*
X1783185Y29806D01*
G01X1782771Y28715D02*
X1771886Y30893D01*
G01X1765423Y36583D02*
X1772335Y31976D01*
G01X1771886Y30893D02*
X1764596Y35751D01*
G01X1771886Y30893D02*
X1764596Y35751D01*
G01X1765423Y36583D02*
X1772335Y31976D01*
G01X1782771Y28715D02*
X1771886Y30893D01*
G01X1772335Y31976D02*
X1783185Y29806D01*
G01X1781707Y22119D02*
X1763493Y32543D01*
G01D02*
X1759004Y39277D01*
G01X1763493Y32543D02*
X1759004Y39277D01*
G01X1781707Y22119D02*
X1763493Y32543D01*
G01X1781707Y22119D02*
X1763493Y32543D01*
G01X1781707Y22119D02*
X1763493Y32543D01*
G01X1761867Y41849D02*
X1765423Y36583D01*
G01X1764596Y35751D02*
X1761038Y41019D01*
G01X1757443Y44801D02*
X1761868Y41849D01*
G01X1761038Y41019D02*
X1756994Y43717D01*
G01X1751557Y45977D02*
X1757443Y44801D01*
G01X1756994Y43717D02*
X1751563Y44802D01*
G01X1745730Y44748D02*
X1751557Y45977D01*
G01X1751563Y44802D02*
X1745729Y43572D01*
G01X1739572Y46057D02*
X1745730Y44748D01*
G01X1745729Y43572D02*
X1739115Y44978D01*
G01X1734141Y49704D02*
X1737093Y47722D01*
G01Y47721D02*
X1739572Y46057D01*
G01X1739115Y44978D02*
X1733790Y48554D01*
G01X1732521Y49704D02*
X1734141D01*
G01D02*
X1737093Y47722D01*
G01X1733790Y48554D02*
X1732642D01*
G01X1727703Y48681D02*
X1727708D01*
G01D02*
X1732521Y49704D01*
G01X1732642Y48554D02*
X1727829Y47531D01*
G01X1727703Y48681D02*
X1727708D01*
G01X1727829Y47531D02*
X1727600D01*
G01X1716497Y50702D02*
X1727703Y48681D01*
G01D02*
X1727708D01*
G01X1727600Y47531D02*
X1716510Y49531D01*
G01X1727600Y47531D02*
X1716510Y49531D01*
G01X1716497Y50702D02*
X1727703Y48681D01*
G01X1732642Y48554D02*
X1727829Y47531D01*
G01D02*
X1727600D01*
G01D02*
X1716510Y49531D01*
G01X1727703Y48681D02*
X1727708D01*
G01X1732642Y48554D02*
X1727829Y47531D01*
G01X1727708Y48681D02*
X1732521Y49704D01*
G01X1733790Y48554D02*
X1732642D01*
G01X1732521Y49704D02*
X1734141D01*
G01X1739115Y44978D02*
X1733790Y48554D01*
G01D02*
X1732642D01*
G01X1734141Y49704D02*
X1737093Y47722D01*
G01X1739115Y44978D02*
X1733790Y48554D01*
G01X1737093Y47721D02*
X1739572Y46057D01*
G01X1745729Y43572D02*
X1739115Y44978D01*
G01X1739572Y46057D02*
X1745730Y44748D01*
G01X1751563Y44802D02*
X1745729Y43572D01*
G01X1745730Y44748D02*
X1751557Y45977D01*
G01X1756994Y43717D02*
X1751563Y44802D01*
G01X1751557Y45977D02*
X1757443Y44801D01*
G01X1761038Y41019D02*
X1756994Y43717D01*
G01X1757443Y44801D02*
X1761868Y41849D01*
G01X1764596Y35751D02*
X1761038Y41019D01*
G01X1761867Y41849D02*
X1765423Y36583D01*
G01X1759831Y40112D02*
X1764273Y33448D01*
G01X1756190Y42490D02*
X1759831Y40112D01*
G01X1759004Y39277D02*
X1755747Y41405D01*
G01X1752410Y43244D02*
X1756190Y42490D01*
G01X1755747Y41405D02*
X1752417Y42069D01*
G01X1745485Y41772D02*
X1752410Y43244D01*
G01X1752417Y42069D02*
X1745485Y40596D01*
G01X1728911Y45295D02*
X1732616Y44508D01*
G01X1735208Y43957D02*
X1745485Y41772D01*
G01Y40596D02*
X1728911Y44119D01*
G01X1715619Y42468D02*
X1721085Y43631D01*
G01X1723677Y44182D02*
X1724998Y44463D01*
G01X1727590Y45014D02*
X1728911Y45295D01*
G01Y44119D02*
X1715622Y41294D01*
G01X1714295Y42733D02*
X1715619Y42468D01*
G01X1714295Y42733D02*
X1715619Y42468D01*
G01X1728911Y44119D02*
X1715622Y41294D01*
G01X1715619Y42468D02*
X1721085Y43631D01*
G01X1728911Y44119D02*
X1715622Y41294D01*
G01X1723677Y44182D02*
X1724998Y44463D01*
G01X1728911Y44119D02*
X1715622Y41294D01*
G01X1727590Y45014D02*
X1728911Y45295D01*
G01X1745485Y40596D02*
X1728911Y44119D01*
G01Y45295D02*
X1732616Y44508D01*
G01X1745485Y40596D02*
X1728911Y44119D01*
G01X1735208Y43957D02*
X1745485Y41772D01*
G01X1752417Y42069D02*
X1745485Y40596D01*
G01Y41772D02*
X1752410Y43244D01*
G01X1755747Y41405D02*
X1752417Y42069D01*
G01X1752410Y43244D02*
X1756190Y42490D01*
G01X1759004Y39277D02*
X1755747Y41405D01*
G01X1756190Y42490D02*
X1759831Y40112D01*
G01D02*
X1764273Y33448D01*
G01X1770687Y44584D02*
X1776150Y43490D01*
G01Y42317D02*
X1770238Y43501D01*
G01X1755138Y54953D02*
X1770687Y44584D01*
G01X1770238Y43501D02*
X1754485Y54006D01*
G01X1754946Y55091D02*
X1755138Y54953D01*
G01D02*
X1770687Y44584D01*
G01X1754485Y54006D02*
X1754478Y54011D01*
G01X1741792Y57624D02*
X1742024Y57673D01*
G01D02*
X1754946Y55091D01*
G01D02*
X1755138Y54953D01*
G01X1754478Y54011D02*
X1742031Y56498D01*
G01X1730508Y55227D02*
X1741792Y57623D01*
G01Y57624D02*
X1742024Y57673D01*
G01X1742031Y56498D02*
X1730411Y54030D01*
G01X1721459Y58739D02*
X1730508Y55227D01*
G01X1730411Y54030D02*
X1721134Y57631D01*
G01X1716418Y59765D02*
X1721363Y58758D01*
G01Y58759D02*
X1721459Y58739D01*
G01X1721134Y57631D02*
X1716417Y58591D01*
G01X1721134Y57631D02*
X1716417Y58591D01*
G01X1716418Y59765D02*
X1721363Y58758D01*
G01X1721134Y57631D02*
X1716417Y58591D01*
G01X1721363Y58759D02*
X1721459Y58739D01*
G01X1730411Y54030D02*
X1721134Y57631D01*
G01X1721459Y58739D02*
X1730508Y55227D01*
G01X1742031Y56498D02*
X1730411Y54030D01*
G01X1730508Y55227D02*
X1741792Y57623D01*
G01X1754478Y54011D02*
X1742031Y56498D01*
G01D02*
X1730411Y54030D01*
G01X1741792Y57624D02*
X1742024Y57673D01*
G01X1754478Y54011D02*
X1742031Y56498D01*
G01X1742024Y57673D02*
X1754946Y55091D01*
G01X1754485Y54006D02*
X1754478Y54011D01*
G01D02*
X1742031Y56498D01*
G01X1754946Y55091D02*
X1755138Y54953D01*
G01X1770238Y43501D02*
X1754485Y54006D01*
G01D02*
X1754478Y54011D01*
G01X1755138Y54953D02*
X1770687Y44584D01*
G01X1776150Y42317D02*
X1770238Y43501D01*
G01X1770687Y44584D02*
X1776150Y43490D01*
G01X1775050Y46850D02*
X1770514Y47757D01*
G01X1775050Y45677D02*
X1770065Y46674D01*
G01X1770514Y47757D02*
X1747961Y62794D01*
G01X1770065Y46674D02*
X1747480Y61732D01*
G01X1747961Y62794D02*
X1746657Y63144D01*
G01X1744097Y63830D02*
X1742793Y64179D01*
G01X1740234Y64866D02*
X1738524Y65324D01*
G01X1747480Y61732D02*
X1738485Y64143D01*
G01X1738524Y65324D02*
X1732723Y64165D01*
G01X1738485Y64143D02*
X1733172Y63082D01*
G01X1732723Y64165D02*
X1729621Y62097D01*
G01X1733172Y63082D02*
X1730070Y61014D01*
G01X1729621Y62097D02*
X1725140Y61201D01*
G01X1730070Y61014D02*
X1725139Y60028D01*
G01X1725140Y61201D02*
X1715944Y63058D01*
G01X1725139Y60028D02*
X1718015Y61464D01*
G01X1725140Y61201D02*
X1715944Y63058D01*
G01X1718015Y61464D02*
X1715496Y61975D01*
G01X1775050Y45677D02*
X1770065Y46674D01*
G01X1775050Y46850D02*
X1770514Y47757D01*
G01X1770065Y46674D02*
X1747480Y61732D01*
G01X1770514Y47757D02*
X1747961Y62794D01*
G01X1747480Y61732D02*
X1738485Y64143D01*
G01X1747961Y62794D02*
X1746657Y63144D01*
G01X1747480Y61732D02*
X1738485Y64143D01*
G01X1744097Y63830D02*
X1742793Y64179D01*
G01X1747480Y61732D02*
X1738485Y64143D01*
G01X1740234Y64866D02*
X1738524Y65324D01*
G01X1738485Y64143D02*
X1733172Y63082D01*
G01X1738524Y65324D02*
X1732723Y64165D01*
G01X1733172Y63082D02*
X1730070Y61014D01*
G01X1732723Y64165D02*
X1729621Y62097D01*
G01X1730070Y61014D02*
X1725139Y60028D01*
G01X1729621Y62097D02*
X1725140Y61201D01*
G01X1725139Y60028D02*
X1718015Y61464D01*
G01D02*
X1715496Y61975D01*
G01X1725140Y61201D02*
X1715944Y63058D01*
G01X1714763Y53724D02*
X1716996Y55214D01*
G01X1715213Y52641D02*
X1717445Y54130D01*
G01X1716996Y55214D02*
X1720123Y55838D01*
G01D02*
X1720122D01*
G01D02*
X1720448Y55903D01*
G01X1717445Y54130D02*
X1720348Y54710D01*
G01X1720448Y55903D02*
X1729688Y52371D01*
G01X1720348Y54710D02*
X1729588Y51178D01*
G01X1729688Y52371D02*
X1734754Y53385D01*
G01X1729588Y51178D02*
X1734669Y52195D01*
G01X1734754Y53385D02*
X1741764Y50901D01*
G01X1734669Y52195D02*
X1741701Y49703D01*
G01X1741764Y50901D02*
X1747277Y52220D01*
G01X1741701Y49703D02*
X1747298Y51042D01*
G01X1747277Y52220D02*
X1755271Y50619D01*
G01X1747298Y51042D02*
X1754820Y49537D01*
G01X1755271Y50619D02*
X1762560Y45761D01*
G01X1754820Y49537D02*
X1761730Y44931D01*
G01X1762560Y45761D02*
X1765670Y41094D01*
G01X1761730Y44931D02*
X1764713Y40456D01*
G01X1765670Y41094D02*
X1767162Y38858D01*
G01X1764713Y40456D02*
X1766332Y38028D01*
G01X1767162Y38858D02*
X1773889Y34375D01*
G01X1766332Y38028D02*
X1773646Y33154D01*
G01X1773890Y34375D02*
X1793366Y30479D01*
G01X1773646Y33154D02*
X1773889Y33202D01*
G01X1773890Y34375D02*
X1793366Y30479D01*
G01X1773889Y33202D02*
X1792917Y29396D01*
G01X1715213Y52641D02*
X1717445Y54130D01*
G01X1714763Y53724D02*
X1716996Y55214D01*
G01X1717445Y54130D02*
X1720348Y54710D01*
G01X1716996Y55214D02*
X1720123Y55838D01*
G01X1717445Y54130D02*
X1720348Y54710D01*
G01X1720123Y55838D02*
X1720122D01*
G01X1717445Y54130D02*
X1720348Y54710D01*
G01X1720122Y55838D02*
X1720448Y55903D01*
G01X1720348Y54710D02*
X1729588Y51178D01*
G01X1720448Y55903D02*
X1729688Y52371D01*
G01X1729588Y51178D02*
X1734669Y52195D01*
G01X1729688Y52371D02*
X1734754Y53385D01*
G01X1734669Y52195D02*
X1741701Y49703D01*
G01X1734754Y53385D02*
X1741764Y50901D01*
G01X1741701Y49703D02*
X1747298Y51042D01*
G01X1741764Y50901D02*
X1747277Y52220D01*
G01X1747298Y51042D02*
X1754820Y49537D01*
G01X1747277Y52220D02*
X1755271Y50619D01*
G01X1754820Y49537D02*
X1761730Y44931D01*
G01X1755271Y50619D02*
X1762560Y45761D01*
G01X1761730Y44931D02*
X1764713Y40456D01*
G01X1762560Y45761D02*
X1765670Y41094D01*
G01X1764713Y40456D02*
X1766332Y38028D01*
G01X1765670Y41094D02*
X1767162Y38858D01*
G01X1766332Y38028D02*
X1773646Y33154D01*
G01X1767162Y38858D02*
X1773889Y34375D01*
G01X1766332Y38028D02*
X1773646Y33154D01*
G01D02*
X1773889Y33202D01*
G01D02*
X1792917Y29396D01*
G01X1773890Y34375D02*
X1793366Y30479D01*
G01X1775300Y49780D02*
X1771705Y50499D01*
G01X1775300Y48607D02*
X1771256Y49415D01*
G01X1771705Y50499D02*
X1750070Y64922D01*
G01X1771256Y49416D02*
X1749348Y64022D01*
G01X1750070Y64922D02*
X1745554Y69167D01*
G01X1749348Y64022D02*
X1744914Y68188D01*
G01X1745554Y69167D02*
X1743222Y70158D01*
G01X1744914Y68188D02*
X1743099Y68960D01*
G01X1743222Y70158D02*
X1731595Y67831D01*
G01X1743099Y68960D02*
X1732044Y66748D01*
G01X1731595Y67831D02*
X1731405Y67705D01*
G01D02*
X1731406D01*
G01D02*
X1727724Y65250D01*
G01X1732044Y66748D02*
X1728173Y64167D01*
G01X1727724Y65250D02*
X1722922Y64290D01*
G01X1728173Y64167D02*
X1722921Y63116D01*
G01X1722922Y64290D02*
X1718409Y65204D01*
G01X1722921Y63116D02*
X1717961Y64121D01*
G01X1718409Y65204D02*
X1712954Y68815D01*
G01X1717961Y64121D02*
X1712505Y67732D01*
G01X1775300Y48607D02*
X1771256Y49415D01*
G01X1775300Y49780D02*
X1771705Y50499D01*
G01X1771256Y49416D02*
X1749348Y64022D01*
G01X1771705Y50499D02*
X1750070Y64922D01*
G01X1749348Y64022D02*
X1744914Y68188D01*
G01X1750070Y64922D02*
X1745554Y69167D01*
G01X1744914Y68188D02*
X1743099Y68960D01*
G01X1745554Y69167D02*
X1743222Y70158D01*
G01X1743099Y68960D02*
X1732044Y66748D01*
G01X1743222Y70158D02*
X1731595Y67831D01*
G01X1732044Y66748D02*
X1728173Y64167D01*
G01X1731595Y67831D02*
X1731405Y67705D01*
G01X1732044Y66748D02*
X1728173Y64167D01*
G01X1731405Y67705D02*
X1731406D01*
G01X1732044Y66748D02*
X1728173Y64167D01*
G01X1731406Y67705D02*
X1727724Y65250D01*
G01X1728173Y64167D02*
X1722921Y63116D01*
G01X1727724Y65250D02*
X1722922Y64290D01*
G01X1722921Y63116D02*
X1717961Y64121D01*
G01X1722922Y64290D02*
X1718409Y65204D01*
G01X1717961Y64121D02*
X1712505Y67732D01*
G01X1718409Y65204D02*
X1712954Y68815D01*
G01X1712496Y494254D02*
X1715493Y491257D01*
G01D02*
X1759230D01*
G01X1715016Y490107D02*
X1759707D01*
G01X1759230Y491257D02*
X1772448Y504475D01*
G01X1759707Y490107D02*
X1772925Y503325D01*
G01X1772448Y504475D02*
X1837552D01*
G01X1772925Y503325D02*
X1825577D01*
G01X1772448Y504475D02*
X1837552D01*
G01X1772448D02*
X1837552D01*
G01X1712496Y494254D02*
X1715493Y491257D01*
G01X1715016Y490107D02*
X1759707D01*
G01X1715493Y491257D02*
X1759230D01*
G01X1759707Y490107D02*
X1772925Y503325D01*
G01X1759230Y491257D02*
X1772448Y504475D01*
G01X1772925Y503325D02*
X1825577D01*
G01X1772448Y504475D02*
X1837552D01*
G01X1802870Y14028D02*
Y10422D01*
G01X1801720Y11088D02*
Y13551D01*
G01X1800514Y16384D02*
X1802870Y14028D01*
G01X1801720Y13551D02*
X1799749Y15522D01*
G01X1784227Y29199D02*
X1792374Y22789D01*
G01Y22788D02*
X1800514Y16384D01*
G01X1799749Y15522D02*
X1783578Y28245D01*
G01X1783185Y29806D02*
X1784227Y29199D01*
G01X1783578Y28245D02*
X1782771Y28715D01*
G01X1783578Y28245D02*
X1782771Y28715D01*
G01X1783185Y29806D02*
X1784227Y29199D01*
G01X1799749Y15522D02*
X1783578Y28245D01*
G01X1784227Y29199D02*
X1792374Y22789D01*
G01X1799749Y15522D02*
X1783578Y28245D01*
G01X1792374Y22788D02*
X1800514Y16384D01*
G01X1801720Y13551D02*
X1799749Y15522D01*
G01X1800514Y16384D02*
X1802870Y14028D01*
G01X1801720Y11088D02*
Y13551D01*
G01X1802870Y14028D02*
Y10422D01*
G01X1793111Y14169D02*
Y12446D01*
G01X1791961Y12541D02*
Y13837D01*
G01X1791717Y16389D02*
X1793111Y14169D01*
G01X1791961Y13837D02*
X1790934Y15473D01*
G01X1784841Y19333D02*
X1791717Y16389D01*
G01X1790934Y15473D02*
X1784061Y18416D01*
G01X1782525Y22976D02*
X1784841Y19333D01*
G01X1784061Y18416D02*
X1781707Y22119D01*
G01X1774410Y27621D02*
X1775582Y26950D01*
G01X1777882Y25634D02*
X1779054Y24963D01*
G01X1781353Y23647D02*
X1782525Y22976D01*
G01X1774410Y27621D02*
X1775582Y26950D01*
G01X1777882Y25634D02*
X1779054Y24963D01*
G01X1781353Y23647D02*
X1782525Y22976D01*
G01X1784061Y18416D02*
X1781707Y22119D01*
G01X1782525Y22976D02*
X1784841Y19333D01*
G01X1790934Y15473D02*
X1784061Y18416D01*
G01X1784841Y19333D02*
X1791717Y16389D01*
G01X1791961Y13837D02*
X1790934Y15473D01*
G01X1791717Y16389D02*
X1793111Y14169D01*
G01X1791961Y12541D02*
Y13837D01*
G01X1793111Y14169D02*
Y12446D01*
G01X1793366Y30479D02*
X1803428Y23771D01*
G01X1792917Y29396D02*
X1802695Y22877D01*
G01X1803428Y23771D02*
X1811900Y15299D01*
G01X1802695Y22877D02*
X1810750Y14822D01*
G01X1811900Y15299D02*
Y14060D01*
G01X1810750Y14822D02*
Y14120D01*
G01X1792917Y29396D02*
X1802695Y22877D01*
G01X1793366Y30479D02*
X1803428Y23771D01*
G01X1802695Y22877D02*
X1810750Y14822D01*
G01X1803428Y23771D02*
X1811900Y15299D01*
G01X1810750Y14822D02*
Y14120D01*
G01X1811900Y15299D02*
Y14060D01*
G01X1795900Y39750D02*
Y38604D01*
G01X1794750Y38921D02*
Y39401D01*
G01X1794682Y41578D02*
X1795900Y39750D01*
G01X1794750Y39401D02*
X1793852Y40748D01*
G01X1791983Y43378D02*
X1794682Y41578D01*
G01X1793852Y40748D02*
X1791534Y42294D01*
G01X1783783Y45016D02*
X1791983Y43378D01*
G01X1791534Y42294D02*
X1783783Y43843D01*
G01X1776150Y43490D02*
X1783783Y45016D01*
G01Y43843D02*
X1776150Y42317D01*
G01X1783783Y43843D02*
X1776150Y42317D01*
G01Y43490D02*
X1783783Y45016D01*
G01X1791534Y42294D02*
X1783783Y43843D01*
G01Y45016D02*
X1791983Y43378D01*
G01X1793852Y40748D02*
X1791534Y42294D01*
G01X1791983Y43378D02*
X1794682Y41578D01*
G01X1794750Y39401D02*
X1793852Y40748D01*
G01X1794682Y41578D02*
X1795900Y39750D01*
G01X1794750Y38921D02*
Y39401D01*
G01X1795900Y39750D02*
Y38604D01*
G01X1806530Y41866D02*
Y44921D01*
G01X1805380Y41980D02*
Y44444D01*
G01X1806530Y44921D02*
X1803795Y47656D01*
G01X1802841Y49529D02*
X1801922D01*
G01D02*
X1800967Y50484D01*
G01X1805380Y44444D02*
X1800342Y49482D01*
G01X1800967Y50484D02*
X1792631Y53339D01*
G01X1800342Y49482D02*
X1792552Y52150D01*
G01X1792631Y53339D02*
X1787779Y52368D01*
G01X1792552Y52150D02*
X1788228Y51285D01*
G01X1787779Y52368D02*
X1781409Y48122D01*
G01X1788228Y51285D02*
X1781858Y47039D01*
G01X1781409Y48122D02*
X1775050Y46850D01*
G01X1781858Y47039D02*
X1775050Y45677D01*
G01X1805380Y41980D02*
Y44444D01*
G01X1806530Y41866D02*
Y44921D01*
G01X1805380Y44444D02*
X1800342Y49482D01*
G01X1806530Y44921D02*
X1803795Y47656D01*
G01X1805380Y44444D02*
X1800342Y49482D01*
G01X1802841Y49529D02*
X1801922D01*
G01X1805380Y44444D02*
X1800342Y49482D01*
G01X1801922Y49529D02*
X1800967Y50484D01*
G01X1800342Y49482D02*
X1792552Y52150D01*
G01X1800967Y50484D02*
X1792631Y53339D01*
G01X1792552Y52150D02*
X1788228Y51285D01*
G01X1792631Y53339D02*
X1787779Y52368D01*
G01X1788228Y51285D02*
X1781858Y47039D01*
G01X1787779Y52368D02*
X1781409Y48122D01*
G01X1781858Y47039D02*
X1775050Y45677D01*
G01X1781409Y48122D02*
X1775050Y46850D01*
G01X1773889Y34375D02*
X1773890D01*
G01X1773889D02*
X1773890D01*
G01X1815457Y38804D02*
Y43162D01*
G01X1814307Y38904D02*
Y42803D01*
G01X1815365Y43254D02*
X1812871Y49093D01*
G01X1814307Y42803D02*
X1811966Y48282D01*
G01X1812871Y49093D02*
X1810572Y50387D01*
G01X1811966Y48282D02*
X1810112Y49327D01*
G01X1810572Y50387D02*
X1791906Y56775D01*
G01X1810112Y49327D02*
X1791828Y55586D01*
G01X1791906Y56775D02*
X1788626Y56117D01*
G01X1791828Y55586D02*
X1789073Y55034D01*
G01X1788626Y56117D02*
X1780758Y50872D01*
G01X1789073Y55034D02*
X1781207Y49789D01*
G01X1780758Y50872D02*
X1775300Y49780D01*
G01X1781207Y49789D02*
X1775300Y48607D01*
G01X1814307Y38904D02*
Y42803D01*
G01X1815457Y38804D02*
Y43162D01*
G01X1814307Y42803D02*
X1811966Y48282D01*
G01X1815365Y43254D02*
X1812871Y49093D01*
G01X1811966Y48282D02*
X1810112Y49327D01*
G01X1812871Y49093D02*
X1810572Y50387D01*
G01X1810112Y49327D02*
X1791828Y55586D01*
G01X1810572Y50387D02*
X1791906Y56775D01*
G01X1791828Y55586D02*
X1789073Y55034D01*
G01X1791906Y56775D02*
X1788626Y56117D01*
G01X1789073Y55034D02*
X1781207Y49789D01*
G01X1788626Y56117D02*
X1780758Y50872D01*
G01X1781207Y49789D02*
X1775300Y48607D01*
G01X1780758Y50872D02*
X1775300Y49780D01*
G01X1828227Y503325D02*
X1829577D01*
G01X1832227D02*
X1837075D01*
G01X1828227D02*
X1829577D01*
G01X1832227D02*
X1837075D01*
G01X1837552Y504475D02*
X1839552Y502475D01*
G01X1837075Y503325D02*
X1839075Y501325D01*
G01X1839552Y502475D02*
X1844525D01*
G01X1839075Y501325D02*
X1844048D01*
G01X1844525Y502475D02*
X1847750Y499249D01*
G01X1844048Y501325D02*
X1846600Y498772D01*
G01X1847750Y499249D02*
Y492378D01*
G01X1846600Y498772D02*
Y491901D01*
G01X1847750Y492378D02*
X1849278Y490850D01*
G01X1846600Y491901D02*
X1848801Y489700D01*
G01X1849278Y490850D02*
X1851800D01*
G01X1848801Y489700D02*
X1851790D01*
G01X1837075Y503325D02*
X1839075Y501325D01*
G01X1837552Y504475D02*
X1839552Y502475D01*
G01X1839075Y501325D02*
X1844048D01*
G01X1839552Y502475D02*
X1844525D01*
G01X1844048Y501325D02*
X1846600Y498772D01*
G01X1844525Y502475D02*
X1847750Y499249D01*
G01X1846600Y498772D02*
Y491901D01*
G01X1847750Y499249D02*
Y492378D01*
G01X1846600Y491901D02*
X1848801Y489700D01*
G01X1847750Y492378D02*
X1849278Y490850D01*
G01X1848801Y489700D02*
X1851790D01*
G01X1849278Y490850D02*
X1851800D01*
G54D13*
G01X140126Y89268D02*
Y97505D01*
G01X145072Y86922D02*
X141880Y90114D01*
G01Y87515D02*
X142978D01*
G01X145072Y86922D02*
X141880Y90114D01*
G01X142978Y87515D02*
X144012Y86481D01*
G01X145072Y71532D02*
Y86922D01*
G01X144012Y86481D02*
Y83706D01*
G01X145072Y71532D02*
Y86922D01*
G01X144012Y79880D02*
Y78507D01*
G01X145072Y71532D02*
Y86922D01*
G01X144012Y74593D02*
Y71972D01*
G01X141880Y68340D02*
X145072Y71532D01*
G01X144012Y71972D02*
X142989Y70949D01*
G01X140126Y89268D02*
Y97505D01*
G01X145072Y86922D02*
X141880Y90114D01*
G01Y87515D02*
X142978D01*
G01X145072Y86922D02*
X141880Y90114D01*
G01X142978Y87515D02*
X144012Y86481D01*
G01X145072Y71532D02*
Y86922D01*
G01X144012Y86481D02*
Y83706D01*
G01X145072Y71532D02*
Y86922D01*
G01X144012Y79880D02*
Y78507D01*
G01X145072Y71532D02*
Y86922D01*
G01X144012Y74593D02*
Y71972D01*
G01X141880Y68340D02*
X145072Y71532D01*
G01X144012Y71972D02*
X142989Y70949D01*
G01X138115Y70380D02*
X137599D01*
G01X137576Y69320D02*
X138558D01*
G01X138826Y71091D02*
X138115Y70380D01*
G01X138558Y69320D02*
X139886Y70648D01*
G01X138826Y86353D02*
Y83820D01*
G01Y79680D02*
Y78720D01*
G01Y74380D02*
Y71091D01*
G01X139886Y70648D02*
Y86794D01*
G01X137879Y87300D02*
X138826Y86353D01*
G01X139886Y86794D02*
X136780Y89900D01*
G01X134926Y89154D02*
Y98013D01*
G01X138115Y70380D02*
X137599D01*
G01X137576Y69320D02*
X138558D01*
G01X138826Y71091D02*
X138115Y70380D01*
G01X138558Y69320D02*
X139886Y70648D01*
G01X138826Y86353D02*
Y83820D01*
G01Y79680D02*
Y78720D01*
G01Y74380D02*
Y71091D01*
G01X139886Y70648D02*
Y86794D01*
G01X137879Y87300D02*
X138826Y86353D01*
G01X139886Y86794D02*
X136780Y89900D01*
G01X134926Y89154D02*
Y98013D01*
G01X144012Y71972D02*
X142989Y70949D01*
G01X141880Y68340D02*
X145072Y71532D01*
G01X144012Y86481D02*
Y83706D01*
G01Y79880D02*
Y78507D01*
G01Y74593D02*
Y71972D01*
G01X145072Y71532D02*
Y86922D01*
G01X141880Y87515D02*
X142978D01*
G01D02*
X144012Y86481D01*
G01X145072Y86922D02*
X141880Y90114D01*
G01X140126Y89268D02*
Y97505D01*
G01X144012Y71972D02*
X142989Y70949D01*
G01X141880Y68340D02*
X145072Y71532D01*
G01X144012Y86481D02*
Y83706D01*
G01Y79880D02*
Y78507D01*
G01Y74593D02*
Y71972D01*
G01X145072Y71532D02*
Y86922D01*
G01X141880Y87515D02*
X142978D01*
G01D02*
X144012Y86481D01*
G01X145072Y86922D02*
X141880Y90114D01*
G01X140126Y89268D02*
Y97505D01*
G01X134926Y89154D02*
Y98013D01*
G01X139886Y86794D02*
X136780Y89900D01*
G01X137879Y87300D02*
X138826Y86353D01*
G01X139886Y70648D02*
Y86794D01*
G01X138826Y86353D02*
Y83820D01*
G01X139886Y70648D02*
Y86794D01*
G01X138826Y79680D02*
Y78720D01*
G01X139886Y70648D02*
Y86794D01*
G01X138826Y74380D02*
Y71091D01*
G01X138558Y69320D02*
X139886Y70648D01*
G01X138826Y71091D02*
X138115Y70380D01*
G01X137576Y69320D02*
X138558D01*
G01X138115Y70380D02*
X137599D01*
G01X134926Y89154D02*
Y98013D01*
G01X139886Y86794D02*
X136780Y89900D01*
G01X137879Y87300D02*
X138826Y86353D01*
G01X139886Y70648D02*
Y86794D01*
G01X138826Y86353D02*
Y83820D01*
G01X139886Y70648D02*
Y86794D01*
G01X138826Y79680D02*
Y78720D01*
G01X139886Y70648D02*
Y86794D01*
G01X138826Y74380D02*
Y71091D01*
G01X138558Y69320D02*
X139886Y70648D01*
G01X138826Y71091D02*
X138115Y70380D01*
G01X137576Y69320D02*
X138558D01*
G01X138115Y70380D02*
X137599D01*
G01X141186Y95506D02*
Y97062D01*
G01D02*
X142664Y98540D01*
G01X140126Y97505D02*
X141604Y98983D01*
G01X142664Y98540D02*
Y99372D01*
G01Y101612D02*
Y102372D01*
G01Y104612D02*
Y105372D01*
G01Y107612D02*
Y108372D01*
G01Y110612D02*
Y111372D01*
G01Y113612D02*
Y134505D01*
G01X141604Y98983D02*
Y134948D01*
G01X142664Y134505D02*
X143635Y135476D01*
G01X141604Y134948D02*
X143192Y136536D01*
G01X143635Y135476D02*
X150875D01*
G01X143192Y136536D02*
X150432D01*
G01X150875Y135476D02*
X153200Y137800D01*
G01D02*
X153764Y138365D01*
G01X150432Y136536D02*
X152704Y138808D01*
G01X153764Y138365D02*
Y141047D01*
G01X152704Y138808D02*
Y140604D01*
G01X153764Y141047D02*
X150464Y144347D01*
G01X152704Y140604D02*
X149404Y143904D01*
G01X150464Y144347D02*
Y146468D01*
G01X149404Y143904D02*
Y146911D01*
G01X150464Y146468D02*
X151536Y147540D01*
G01X149404Y146911D02*
X151093Y148600D01*
G01X151536Y147540D02*
X152775D01*
G01D02*
X154264Y149029D01*
G01X151093Y148600D02*
X152332D01*
G01X152775Y147540D02*
X154264Y149029D01*
G01X152332Y148600D02*
X153204Y149472D01*
G01X154264Y149029D02*
Y152304D01*
G01X153204Y149472D02*
Y152747D01*
G01X154264Y152304D02*
X252294Y250334D01*
G01X153204Y152747D02*
X251851Y251394D01*
G01X141186Y95506D02*
Y97062D01*
G01D02*
X142664Y98540D01*
G01X140126Y97505D02*
X141604Y98983D01*
G01X142664Y98540D02*
Y99372D01*
G01Y101612D02*
Y102372D01*
G01Y104612D02*
Y105372D01*
G01Y107612D02*
Y108372D01*
G01Y110612D02*
Y111372D01*
G01Y113612D02*
Y134505D01*
G01X141604Y98983D02*
Y134948D01*
G01X142664Y134505D02*
X143635Y135476D01*
G01X141604Y134948D02*
X143192Y136536D01*
G01X143635Y135476D02*
X150875D01*
G01X143192Y136536D02*
X150432D01*
G01X150875Y135476D02*
X153200Y137800D01*
G01D02*
X153764Y138365D01*
G01X150432Y136536D02*
X152704Y138808D01*
G01X153764Y138365D02*
Y141047D01*
G01X152704Y138808D02*
Y140604D01*
G01X153764Y141047D02*
X150464Y144347D01*
G01X152704Y140604D02*
X149404Y143904D01*
G01X150464Y144347D02*
Y146468D01*
G01X149404Y143904D02*
Y146911D01*
G01X150464Y146468D02*
X151536Y147540D01*
G01X149404Y146911D02*
X151093Y148600D01*
G01X151536Y147540D02*
X152775D01*
G01D02*
X154264Y149029D01*
G01X151093Y148600D02*
X152332D01*
G01X152775Y147540D02*
X154264Y149029D01*
G01X152332Y148600D02*
X153204Y149472D01*
G01X154264Y149029D02*
Y152304D01*
G01X153204Y149472D02*
Y152747D01*
G01X154264Y152304D02*
X252294Y250334D01*
G01X153204Y152747D02*
X251851Y251394D01*
G01X135986Y95220D02*
Y97570D01*
G01X134926Y98013D02*
X137004Y100091D01*
G01X135986Y97570D02*
X138684Y100268D01*
G01X137004Y100091D02*
Y141940D01*
G01X138064Y101720D02*
Y102680D01*
G01X137004Y100091D02*
Y141940D01*
G01X138064Y104920D02*
Y105680D01*
G01X137004Y100091D02*
Y141940D01*
G01X138064Y107920D02*
Y108680D01*
G01X137004Y100091D02*
Y141940D01*
G01X138064Y110920D02*
Y111680D01*
G01X137004Y100091D02*
Y141940D01*
G01X138064Y113920D02*
Y114680D01*
G01X137004Y100091D02*
Y141940D01*
G01X138064Y116920D02*
Y141497D01*
G01X137004Y141940D02*
X139367Y144303D01*
G01X138064Y141497D02*
X139810Y143243D01*
G01X137004Y141940D02*
X139367Y144303D01*
G01D02*
X140462D01*
G01X139810Y143243D02*
X140905D01*
G01X139367Y144303D02*
X140462D01*
G01D02*
X142912Y146753D01*
G01X140905Y143243D02*
X143972Y146310D01*
G01X142912Y146753D02*
Y147848D01*
G01X143972Y146310D02*
Y147405D01*
G01X142912Y147848D02*
X250307Y255243D01*
G01X143972Y147405D02*
X250750Y254183D01*
G01X135986Y95220D02*
Y97570D01*
G01X134926Y98013D02*
X137004Y100091D01*
G01X135986Y97570D02*
X138684Y100268D01*
G01X137004Y100091D02*
Y141940D01*
G01X138064Y101720D02*
Y102680D01*
G01X137004Y100091D02*
Y141940D01*
G01X138064Y104920D02*
Y105680D01*
G01X137004Y100091D02*
Y141940D01*
G01X138064Y107920D02*
Y108680D01*
G01X137004Y100091D02*
Y141940D01*
G01X138064Y110920D02*
Y111680D01*
G01X137004Y100091D02*
Y141940D01*
G01X138064Y113920D02*
Y114680D01*
G01X137004Y100091D02*
Y141940D01*
G01X138064Y116920D02*
Y141497D01*
G01X137004Y141940D02*
X139367Y144303D01*
G01X138064Y141497D02*
X139810Y143243D01*
G01X137004Y141940D02*
X139367Y144303D01*
G01D02*
X140462D01*
G01X139810Y143243D02*
X140905D01*
G01X139367Y144303D02*
X140462D01*
G01D02*
X142912Y146753D01*
G01X140905Y143243D02*
X143972Y146310D01*
G01X142912Y146753D02*
Y147848D01*
G01X143972Y146310D02*
Y147405D01*
G01X142912Y147848D02*
X250307Y255243D01*
G01X143972Y147405D02*
X250750Y254183D01*
G01X141186Y95506D02*
Y97062D01*
G01X140126Y97505D02*
X141604Y98983D01*
G01X141186Y97062D02*
X142664Y98540D01*
G01X141604Y98983D02*
Y134948D01*
G01X142664Y98540D02*
Y99372D01*
G01X141604Y98983D02*
Y134948D01*
G01X142664Y101612D02*
Y102372D01*
G01X141604Y98983D02*
Y134948D01*
G01X142664Y104612D02*
Y105372D01*
G01X141604Y98983D02*
Y134948D01*
G01X142664Y107612D02*
Y108372D01*
G01X141604Y98983D02*
Y134948D01*
G01X142664Y110612D02*
Y111372D01*
G01X141604Y98983D02*
Y134948D01*
G01X142664Y113612D02*
Y134505D01*
G01X141604Y134948D02*
X143192Y136536D01*
G01X142664Y134505D02*
X143635Y135476D01*
G01X143192Y136536D02*
X150432D01*
G01X143635Y135476D02*
X150875D01*
G01X150432Y136536D02*
X152704Y138808D01*
G01X150875Y135476D02*
X153200Y137800D01*
G01X150432Y136536D02*
X152704Y138808D01*
G01X153200Y137800D02*
X153764Y138365D01*
G01X152704Y138808D02*
Y140604D01*
G01X153764Y138365D02*
Y141047D01*
G01X152704Y140604D02*
X149404Y143904D01*
G01X153764Y141047D02*
X150464Y144347D01*
G01X149404Y143904D02*
Y146911D01*
G01X150464Y144347D02*
Y146468D01*
G01X149404Y146911D02*
X151093Y148600D01*
G01X150464Y146468D02*
X151536Y147540D01*
G01X151093Y148600D02*
X152332D01*
G01X151536Y147540D02*
X152775D01*
G01X151093Y148600D02*
X152332D01*
G01D02*
X153204Y149472D01*
G01X152775Y147540D02*
X154264Y149029D01*
G01X153204Y149472D02*
Y152747D01*
G01X154264Y149029D02*
Y152304D01*
G01X153204Y152747D02*
X251851Y251394D01*
G01X154264Y152304D02*
X252294Y250334D01*
G01X141186Y95506D02*
Y97062D01*
G01X140126Y97505D02*
X141604Y98983D01*
G01X141186Y97062D02*
X142664Y98540D01*
G01X141604Y98983D02*
Y134948D01*
G01X142664Y98540D02*
Y99372D01*
G01X141604Y98983D02*
Y134948D01*
G01X142664Y101612D02*
Y102372D01*
G01X141604Y98983D02*
Y134948D01*
G01X142664Y104612D02*
Y105372D01*
G01X141604Y98983D02*
Y134948D01*
G01X142664Y107612D02*
Y108372D01*
G01X141604Y98983D02*
Y134948D01*
G01X142664Y110612D02*
Y111372D01*
G01X141604Y98983D02*
Y134948D01*
G01X142664Y113612D02*
Y134505D01*
G01X141604Y134948D02*
X143192Y136536D01*
G01X142664Y134505D02*
X143635Y135476D01*
G01X143192Y136536D02*
X150432D01*
G01X143635Y135476D02*
X150875D01*
G01X150432Y136536D02*
X152704Y138808D01*
G01X150875Y135476D02*
X153200Y137800D01*
G01X150432Y136536D02*
X152704Y138808D01*
G01X153200Y137800D02*
X153764Y138365D01*
G01X152704Y138808D02*
Y140604D01*
G01X153764Y138365D02*
Y141047D01*
G01X152704Y140604D02*
X149404Y143904D01*
G01X153764Y141047D02*
X150464Y144347D01*
G01X149404Y143904D02*
Y146911D01*
G01X150464Y144347D02*
Y146468D01*
G01X149404Y146911D02*
X151093Y148600D01*
G01X150464Y146468D02*
X151536Y147540D01*
G01X151093Y148600D02*
X152332D01*
G01X151536Y147540D02*
X152775D01*
G01X151093Y148600D02*
X152332D01*
G01D02*
X153204Y149472D01*
G01X152775Y147540D02*
X154264Y149029D01*
G01X153204Y149472D02*
Y152747D01*
G01X154264Y149029D02*
Y152304D01*
G01X153204Y152747D02*
X251851Y251394D01*
G01X154264Y152304D02*
X252294Y250334D01*
G01X135986Y95220D02*
Y97570D01*
G01D02*
X138684Y100268D01*
G01X134926Y98013D02*
X137004Y100091D01*
G01X138064Y101720D02*
Y102680D01*
G01Y104920D02*
Y105680D01*
G01Y107920D02*
Y108680D01*
G01Y110920D02*
Y111680D01*
G01Y113920D02*
Y114680D01*
G01Y116920D02*
Y141497D01*
G01X137004Y100091D02*
Y141940D01*
G01X138064Y141497D02*
X139810Y143243D01*
G01D02*
X140905D01*
G01X137004Y141940D02*
X139367Y144303D01*
G01X139810Y143243D02*
X140905D01*
G01D02*
X143972Y146310D01*
G01X139367Y144303D02*
X140462D01*
G01X140905Y143243D02*
X143972Y146310D01*
G01X140462Y144303D02*
X142912Y146753D01*
G01X143972Y146310D02*
Y147405D01*
G01X142912Y146753D02*
Y147848D01*
G01X143972Y147405D02*
X250750Y254183D01*
G01X142912Y147848D02*
X250307Y255243D01*
G01X135986Y95220D02*
Y97570D01*
G01D02*
X138684Y100268D01*
G01X134926Y98013D02*
X137004Y100091D01*
G01X138064Y101720D02*
Y102680D01*
G01Y104920D02*
Y105680D01*
G01Y107920D02*
Y108680D01*
G01Y110920D02*
Y111680D01*
G01Y113920D02*
Y114680D01*
G01Y116920D02*
Y141497D01*
G01X137004Y100091D02*
Y141940D01*
G01X138064Y141497D02*
X139810Y143243D01*
G01D02*
X140905D01*
G01X137004Y141940D02*
X139367Y144303D01*
G01X139810Y143243D02*
X140905D01*
G01D02*
X143972Y146310D01*
G01X139367Y144303D02*
X140462D01*
G01X140905Y143243D02*
X143972Y146310D01*
G01X140462Y144303D02*
X142912Y146753D01*
G01X143972Y146310D02*
Y147405D01*
G01X142912Y146753D02*
Y147848D01*
G01X143972Y147405D02*
X250750Y254183D01*
G01X142912Y147848D02*
X250307Y255243D01*
G01X208092Y398500D02*
X155408Y451184D01*
G01X207032Y398060D02*
X154968Y450124D01*
G01X155408Y451184D02*
X151376D01*
G01X154968Y450124D02*
X150936D01*
G01X151376Y451184D02*
X147872Y454688D01*
G01X150936Y450124D02*
X146812Y454248D01*
G01X147872Y454688D02*
Y475960D01*
G01X146812Y454248D02*
Y475520D01*
G01X203832Y396959D02*
X153651Y447140D01*
G01X204892Y397399D02*
X154091Y448200D01*
G01X153651Y447140D02*
X149751D01*
G01X154091Y448200D02*
X150191D01*
G01X149751Y447140D02*
X140012Y456879D01*
G01X150191Y448200D02*
X141072Y457319D01*
G01X140012Y456879D02*
Y458623D01*
G01X141072Y457319D02*
Y458183D01*
G01X140012Y458623D02*
X141104Y459715D01*
G01X141072Y458183D02*
X141544Y458655D01*
G01X141104Y459715D02*
X142140D01*
G01X141544Y458655D02*
X142580D01*
G01X142140Y459715D02*
X142812Y460387D01*
G01X142602Y458676D02*
X143872Y459947D01*
G01X142812Y460387D02*
Y462383D01*
G01X143872Y459947D02*
Y462823D01*
G01X142812Y462383D02*
X142040Y463155D01*
G01X143872Y462823D02*
X142480Y464215D01*
G01X142040Y463155D02*
X140904D01*
G01X142480Y464215D02*
X141344D01*
G01X140904Y463155D02*
X139612Y464447D01*
G01X141344Y464215D02*
X140672Y464887D01*
G01X139612Y464447D02*
Y467223D01*
G01X207032Y398060D02*
X154968Y450124D01*
G01X208092Y398500D02*
X155408Y451184D01*
G01X154968Y450124D02*
X150936D01*
G01X155408Y451184D02*
X151376D01*
G01X150936Y450124D02*
X146812Y454248D01*
G01X151376Y451184D02*
X147872Y454688D01*
G01X146812Y454248D02*
Y475520D01*
G01X147872Y454688D02*
Y475960D01*
G01X204892Y397399D02*
X154091Y448200D01*
G01X203832Y396959D02*
X153651Y447140D01*
G01X154091Y448200D02*
X150191D01*
G01X153651Y447140D02*
X149751D01*
G01X150191Y448200D02*
X141072Y457319D01*
G01X149751Y447140D02*
X140012Y456879D01*
G01X141072Y457319D02*
Y458183D01*
G01X140012Y456879D02*
Y458623D01*
G01X141072Y458183D02*
X141544Y458655D01*
G01X140012Y458623D02*
X141104Y459715D01*
G01X141544Y458655D02*
X142580D01*
G01X141104Y459715D02*
X142140D01*
G01X142602Y458676D02*
X143872Y459947D01*
G01X142140Y459715D02*
X142812Y460387D01*
G01X143872Y459947D02*
Y462823D01*
G01X142812Y460387D02*
Y462383D01*
G01X143872Y462823D02*
X142480Y464215D01*
G01X142812Y462383D02*
X142040Y463155D01*
G01X142480Y464215D02*
X141344D01*
G01X142040Y463155D02*
X140904D01*
G01X141344Y464215D02*
X140672Y464887D01*
G01X140904Y463155D02*
X139612Y464447D01*
G01D02*
Y467223D01*
G01X208092Y398500D02*
X155408Y451184D01*
G01X207032Y398060D02*
X154968Y450124D01*
G01X155408Y451184D02*
X151376D01*
G01X154968Y450124D02*
X150936D01*
G01X151376Y451184D02*
X147872Y454688D01*
G01X150936Y450124D02*
X146812Y454248D01*
G01X147872Y454688D02*
Y475960D01*
G01X146812Y454248D02*
Y475520D01*
G01X203832Y396959D02*
X153651Y447140D01*
G01X204892Y397399D02*
X154091Y448200D01*
G01X153651Y447140D02*
X149751D01*
G01X154091Y448200D02*
X150191D01*
G01X149751Y447140D02*
X140012Y456879D01*
G01X150191Y448200D02*
X141072Y457319D01*
G01X140012Y456879D02*
Y458623D01*
G01X141072Y457319D02*
Y458183D01*
G01X140012Y458623D02*
X141104Y459715D01*
G01X141072Y458183D02*
X141544Y458655D01*
G01X141104Y459715D02*
X142140D01*
G01X141544Y458655D02*
X142580D01*
G01X142140Y459715D02*
X142812Y460387D01*
G01X142602Y458676D02*
X143872Y459947D01*
G01X142812Y460387D02*
Y462383D01*
G01X143872Y459947D02*
Y462823D01*
G01X142812Y462383D02*
X142040Y463155D01*
G01X143872Y462823D02*
X142480Y464215D01*
G01X142040Y463155D02*
X140904D01*
G01X142480Y464215D02*
X141344D01*
G01X140904Y463155D02*
X139612Y464447D01*
G01X141344Y464215D02*
X140672Y464887D01*
G01X139612Y464447D02*
Y467223D01*
G01X207032Y398060D02*
X154968Y450124D01*
G01X208092Y398500D02*
X155408Y451184D01*
G01X154968Y450124D02*
X150936D01*
G01X155408Y451184D02*
X151376D01*
G01X150936Y450124D02*
X146812Y454248D01*
G01X151376Y451184D02*
X147872Y454688D01*
G01X146812Y454248D02*
Y475520D01*
G01X147872Y454688D02*
Y475960D01*
G01X204892Y397399D02*
X154091Y448200D01*
G01X203832Y396959D02*
X153651Y447140D01*
G01X154091Y448200D02*
X150191D01*
G01X153651Y447140D02*
X149751D01*
G01X150191Y448200D02*
X141072Y457319D01*
G01X149751Y447140D02*
X140012Y456879D01*
G01X141072Y457319D02*
Y458183D01*
G01X140012Y456879D02*
Y458623D01*
G01X141072Y458183D02*
X141544Y458655D01*
G01X140012Y458623D02*
X141104Y459715D01*
G01X141544Y458655D02*
X142580D01*
G01X141104Y459715D02*
X142140D01*
G01X142602Y458676D02*
X143872Y459947D01*
G01X142140Y459715D02*
X142812Y460387D01*
G01X143872Y459947D02*
Y462823D01*
G01X142812Y460387D02*
Y462383D01*
G01X143872Y462823D02*
X142480Y464215D01*
G01X142812Y462383D02*
X142040Y463155D01*
G01X142480Y464215D02*
X141344D01*
G01X142040Y463155D02*
X140904D01*
G01X141344Y464215D02*
X140672Y464887D01*
G01X140904Y463155D02*
X139612Y464447D01*
G01D02*
Y467223D01*
G01X141176Y527000D02*
X140405Y526229D01*
G01D02*
Y525338D01*
G01Y521848D02*
Y520571D01*
G01X139345Y526670D02*
Y520130D01*
G01X140405Y520571D02*
X141076Y519900D01*
G01X139345Y520130D02*
X140175Y519300D01*
G01X147872Y475960D02*
X146380Y477452D01*
G01X146812Y475520D02*
X145940Y476392D01*
G01X146380Y477452D02*
X145244D01*
G01X145940Y476392D02*
X144801D01*
G01X145244Y477452D02*
X144372Y478324D01*
G01X144801Y476392D02*
X143312Y477881D01*
G01X144372Y478324D02*
Y480020D01*
G01X143312Y477881D02*
Y480463D01*
G01X144372Y480020D02*
X145244Y480892D01*
G01X143312Y480463D02*
X144801Y481952D01*
G01X145244Y480892D02*
X146383D01*
G01X144801Y481952D02*
X145940D01*
G01X146383Y480892D02*
X147872Y482381D01*
G01X145940Y481952D02*
X146812Y482824D01*
G01X147872Y482381D02*
Y484963D01*
G01X146812Y482824D02*
Y484520D01*
G01X147872Y484963D02*
X146383Y486452D01*
G01X146812Y484520D02*
X145940Y485392D01*
G01X146383Y486452D02*
X145044D01*
G01X145940Y485392D02*
X144601D01*
G01X145044Y486452D02*
X144172Y487324D01*
G01X144601Y485392D02*
X143112Y486881D01*
G01X144172Y487324D02*
Y489020D01*
G01X143112Y486881D02*
Y489463D01*
G01X144172Y489020D02*
X145044Y489892D01*
G01X143112Y489463D02*
X144601Y490952D01*
G01X145044Y489892D02*
X146383D01*
G01X144601Y490952D02*
X145940D01*
G01X146383Y489892D02*
X147872Y491381D01*
G01X145940Y490952D02*
X146812Y491824D01*
G01X147872Y491381D02*
Y493963D01*
G01X146812Y491824D02*
Y493520D01*
G01X147872Y493963D02*
X146383Y495452D01*
G01X146812Y493520D02*
X145940Y494392D01*
G01X146383Y495452D02*
X144844D01*
G01X145940Y494392D02*
X144401D01*
G01X144844Y495452D02*
X143972Y496324D01*
G01X144401Y494392D02*
X142912Y495881D01*
G01X143972Y496324D02*
Y498020D01*
G01X142912Y495881D02*
Y498463D01*
G01X143972Y498020D02*
X144844Y498892D01*
G01X142912Y498463D02*
X144401Y499952D01*
G01X144844Y498892D02*
X146015D01*
G01D02*
X147872Y500749D01*
G01X144401Y499952D02*
X145572D01*
G01X146015Y498892D02*
X147872Y500749D01*
G01X145572Y499952D02*
X146812Y501192D01*
G01X147872Y500749D02*
Y503192D01*
G01X146812Y501192D02*
Y502749D01*
G01X147872Y503192D02*
X144972Y506092D01*
G01X146812Y502749D02*
X143912Y505649D01*
G01X144972Y506092D02*
Y512720D01*
G01X143912Y505649D02*
Y507080D01*
G01X144972Y506092D02*
Y512720D01*
G01X143912Y509520D02*
Y512280D01*
G01X144972Y512720D02*
X143718Y513974D01*
G01X143912Y512280D02*
X143278Y512914D01*
G01X143718Y513974D02*
X143420D01*
G01X143278Y512914D02*
X141880D01*
G01X134792Y514400D02*
Y532411D01*
G01X135852Y520290D02*
Y521660D01*
G01X134792Y514400D02*
Y532411D01*
G01X135852Y525340D02*
Y526760D01*
G01X140672Y464887D02*
Y466783D01*
G01X139612Y467223D02*
X141104Y468715D01*
G01X140672Y466783D02*
X141544Y467655D01*
G01X141104Y468715D02*
X142435D01*
G01X141544Y467655D02*
X142875D01*
G01X141104Y468715D02*
X142435D01*
G01D02*
X143004Y469284D01*
G01X142875Y467655D02*
X144064Y468844D01*
G01X143004Y469284D02*
Y471286D01*
G01X144064Y468844D02*
Y471726D01*
G01X143004Y471286D02*
X142135Y472155D01*
G01D02*
X140604D01*
G01X144064Y471726D02*
X142575Y473215D01*
G01X142135Y472155D02*
X140604D01*
G01X142575Y473215D02*
X141044D01*
G01X140604Y472155D02*
X139012Y473747D01*
G01X141044Y473215D02*
X140072Y474187D01*
G01X139012Y473747D02*
Y506680D01*
G01Y509120D02*
Y511568D01*
G01X140072Y474187D02*
Y512008D01*
G01X139012Y511568D02*
X137761Y512819D01*
G01X140072Y512008D02*
X136780Y515300D01*
G01X141176Y527000D02*
X140405Y526229D01*
G01X139345Y526670D02*
Y520130D01*
G01X140405Y526229D02*
Y525338D01*
G01X139345Y526670D02*
Y520130D01*
G01X140405Y521848D02*
Y520571D01*
G01X139345Y520130D02*
X140175Y519300D01*
G01X140405Y520571D02*
X141076Y519900D01*
G01X146812Y475520D02*
X145940Y476392D01*
G01X147872Y475960D02*
X146380Y477452D01*
G01X145940Y476392D02*
X144801D01*
G01X146380Y477452D02*
X145244D01*
G01X144801Y476392D02*
X143312Y477881D01*
G01X145244Y477452D02*
X144372Y478324D01*
G01X143312Y477881D02*
Y480463D01*
G01X144372Y478324D02*
Y480020D01*
G01X143312Y480463D02*
X144801Y481952D01*
G01X144372Y480020D02*
X145244Y480892D01*
G01X144801Y481952D02*
X145940D01*
G01X145244Y480892D02*
X146383D01*
G01X145940Y481952D02*
X146812Y482824D01*
G01X146383Y480892D02*
X147872Y482381D01*
G01X146812Y482824D02*
Y484520D01*
G01X147872Y482381D02*
Y484963D01*
G01X146812Y484520D02*
X145940Y485392D01*
G01X147872Y484963D02*
X146383Y486452D01*
G01X145940Y485392D02*
X144601D01*
G01X146383Y486452D02*
X145044D01*
G01X144601Y485392D02*
X143112Y486881D01*
G01X145044Y486452D02*
X144172Y487324D01*
G01X143112Y486881D02*
Y489463D01*
G01X144172Y487324D02*
Y489020D01*
G01X143112Y489463D02*
X144601Y490952D01*
G01X144172Y489020D02*
X145044Y489892D01*
G01X144601Y490952D02*
X145940D01*
G01X145044Y489892D02*
X146383D01*
G01X145940Y490952D02*
X146812Y491824D01*
G01X146383Y489892D02*
X147872Y491381D01*
G01X146812Y491824D02*
Y493520D01*
G01X147872Y491381D02*
Y493963D01*
G01X146812Y493520D02*
X145940Y494392D01*
G01X147872Y493963D02*
X146383Y495452D01*
G01X145940Y494392D02*
X144401D01*
G01X146383Y495452D02*
X144844D01*
G01X144401Y494392D02*
X142912Y495881D01*
G01X144844Y495452D02*
X143972Y496324D01*
G01X142912Y495881D02*
Y498463D01*
G01X143972Y496324D02*
Y498020D01*
G01X142912Y498463D02*
X144401Y499952D01*
G01X143972Y498020D02*
X144844Y498892D01*
G01X144401Y499952D02*
X145572D01*
G01X144844Y498892D02*
X146015D01*
G01X144401Y499952D02*
X145572D01*
G01D02*
X146812Y501192D01*
G01X146015Y498892D02*
X147872Y500749D01*
G01X146812Y501192D02*
Y502749D01*
G01X147872Y500749D02*
Y503192D01*
G01X146812Y502749D02*
X143912Y505649D01*
G01X147872Y503192D02*
X144972Y506092D01*
G01X143912Y505649D02*
Y507080D01*
G01Y509520D02*
Y512280D01*
G01X144972Y506092D02*
Y512720D01*
G01X143912Y512280D02*
X143278Y512914D01*
G01X144972Y512720D02*
X143718Y513974D01*
G01X143278Y512914D02*
X141880D01*
G01X143718Y513974D02*
X143420D01*
G01X135852Y520290D02*
Y521660D01*
G01Y525340D02*
Y526760D01*
G01X134792Y514400D02*
Y532411D01*
G01X140672Y464887D02*
Y466783D01*
G01D02*
X141544Y467655D01*
G01X139612Y467223D02*
X141104Y468715D01*
G01X141544Y467655D02*
X142875D01*
G01D02*
X144064Y468844D01*
G01X141104Y468715D02*
X142435D01*
G01X142875Y467655D02*
X144064Y468844D01*
G01X142435Y468715D02*
X143004Y469284D01*
G01X144064Y468844D02*
Y471726D01*
G01X143004Y469284D02*
Y471286D01*
G01X144064Y471726D02*
X142575Y473215D01*
G01X143004Y471286D02*
X142135Y472155D01*
G01X144064Y471726D02*
X142575Y473215D01*
G01D02*
X141044D01*
G01X142135Y472155D02*
X140604D01*
G01X141044Y473215D02*
X140072Y474187D01*
G01X140604Y472155D02*
X139012Y473747D01*
G01X140072Y474187D02*
Y512008D01*
G01X139012Y473747D02*
Y506680D01*
G01X140072Y474187D02*
Y512008D01*
G01X139012Y509120D02*
Y511568D01*
G01X140072Y512008D02*
X136780Y515300D01*
G01X139012Y511568D02*
X137761Y512819D01*
G01X141176Y527000D02*
X140405Y526229D01*
G01D02*
Y525338D01*
G01Y521848D02*
Y520571D01*
G01X139345Y526670D02*
Y520130D01*
G01X140405Y520571D02*
X141076Y519900D01*
G01X139345Y520130D02*
X140175Y519300D01*
G01X147872Y475960D02*
X146380Y477452D01*
G01X146812Y475520D02*
X145940Y476392D01*
G01X146380Y477452D02*
X145244D01*
G01X145940Y476392D02*
X144801D01*
G01X145244Y477452D02*
X144372Y478324D01*
G01X144801Y476392D02*
X143312Y477881D01*
G01X144372Y478324D02*
Y480020D01*
G01X143312Y477881D02*
Y480463D01*
G01X144372Y480020D02*
X145244Y480892D01*
G01X143312Y480463D02*
X144801Y481952D01*
G01X145244Y480892D02*
X146383D01*
G01X144801Y481952D02*
X145940D01*
G01X146383Y480892D02*
X147872Y482381D01*
G01X145940Y481952D02*
X146812Y482824D01*
G01X147872Y482381D02*
Y484963D01*
G01X146812Y482824D02*
Y484520D01*
G01X147872Y484963D02*
X146383Y486452D01*
G01X146812Y484520D02*
X145940Y485392D01*
G01X146383Y486452D02*
X145044D01*
G01X145940Y485392D02*
X144601D01*
G01X145044Y486452D02*
X144172Y487324D01*
G01X144601Y485392D02*
X143112Y486881D01*
G01X144172Y487324D02*
Y489020D01*
G01X143112Y486881D02*
Y489463D01*
G01X144172Y489020D02*
X145044Y489892D01*
G01X143112Y489463D02*
X144601Y490952D01*
G01X145044Y489892D02*
X146383D01*
G01X144601Y490952D02*
X145940D01*
G01X146383Y489892D02*
X147872Y491381D01*
G01X145940Y490952D02*
X146812Y491824D01*
G01X147872Y491381D02*
Y493963D01*
G01X146812Y491824D02*
Y493520D01*
G01X147872Y493963D02*
X146383Y495452D01*
G01X146812Y493520D02*
X145940Y494392D01*
G01X146383Y495452D02*
X144844D01*
G01X145940Y494392D02*
X144401D01*
G01X144844Y495452D02*
X143972Y496324D01*
G01X144401Y494392D02*
X142912Y495881D01*
G01X143972Y496324D02*
Y498020D01*
G01X142912Y495881D02*
Y498463D01*
G01X143972Y498020D02*
X144844Y498892D01*
G01X142912Y498463D02*
X144401Y499952D01*
G01X144844Y498892D02*
X146015D01*
G01D02*
X147872Y500749D01*
G01X144401Y499952D02*
X145572D01*
G01X146015Y498892D02*
X147872Y500749D01*
G01X145572Y499952D02*
X146812Y501192D01*
G01X147872Y500749D02*
Y503192D01*
G01X146812Y501192D02*
Y502749D01*
G01X147872Y503192D02*
X144972Y506092D01*
G01X146812Y502749D02*
X143912Y505649D01*
G01X144972Y506092D02*
Y512720D01*
G01X143912Y505649D02*
Y507080D01*
G01X144972Y506092D02*
Y512720D01*
G01X143912Y509520D02*
Y512280D01*
G01X144972Y512720D02*
X143718Y513974D01*
G01X143912Y512280D02*
X143278Y512914D01*
G01X143718Y513974D02*
X143420D01*
G01X143278Y512914D02*
X141880D01*
G01X134792Y514400D02*
Y532411D01*
G01X135852Y520290D02*
Y521660D01*
G01X134792Y514400D02*
Y532411D01*
G01X135852Y525340D02*
Y526760D01*
G01X140672Y464887D02*
Y466783D01*
G01X139612Y467223D02*
X141104Y468715D01*
G01X140672Y466783D02*
X141544Y467655D01*
G01X141104Y468715D02*
X142435D01*
G01X141544Y467655D02*
X142875D01*
G01X141104Y468715D02*
X142435D01*
G01D02*
X143004Y469284D01*
G01X142875Y467655D02*
X144064Y468844D01*
G01X143004Y469284D02*
Y471286D01*
G01X144064Y468844D02*
Y471726D01*
G01X143004Y471286D02*
X142135Y472155D01*
G01D02*
X140604D01*
G01X144064Y471726D02*
X142575Y473215D01*
G01X142135Y472155D02*
X140604D01*
G01X142575Y473215D02*
X141044D01*
G01X140604Y472155D02*
X139012Y473747D01*
G01X141044Y473215D02*
X140072Y474187D01*
G01X139012Y473747D02*
Y506680D01*
G01Y509120D02*
Y511568D01*
G01X140072Y474187D02*
Y512008D01*
G01X139012Y511568D02*
X137761Y512819D01*
G01X140072Y512008D02*
X136780Y515300D01*
G01X141176Y527000D02*
X140405Y526229D01*
G01X139345Y526670D02*
Y520130D01*
G01X140405Y526229D02*
Y525338D01*
G01X139345Y526670D02*
Y520130D01*
G01X140405Y521848D02*
Y520571D01*
G01X139345Y520130D02*
X140175Y519300D01*
G01X140405Y520571D02*
X141076Y519900D01*
G01X146812Y475520D02*
X145940Y476392D01*
G01X147872Y475960D02*
X146380Y477452D01*
G01X145940Y476392D02*
X144801D01*
G01X146380Y477452D02*
X145244D01*
G01X144801Y476392D02*
X143312Y477881D01*
G01X145244Y477452D02*
X144372Y478324D01*
G01X143312Y477881D02*
Y480463D01*
G01X144372Y478324D02*
Y480020D01*
G01X143312Y480463D02*
X144801Y481952D01*
G01X144372Y480020D02*
X145244Y480892D01*
G01X144801Y481952D02*
X145940D01*
G01X145244Y480892D02*
X146383D01*
G01X145940Y481952D02*
X146812Y482824D01*
G01X146383Y480892D02*
X147872Y482381D01*
G01X146812Y482824D02*
Y484520D01*
G01X147872Y482381D02*
Y484963D01*
G01X146812Y484520D02*
X145940Y485392D01*
G01X147872Y484963D02*
X146383Y486452D01*
G01X145940Y485392D02*
X144601D01*
G01X146383Y486452D02*
X145044D01*
G01X144601Y485392D02*
X143112Y486881D01*
G01X145044Y486452D02*
X144172Y487324D01*
G01X143112Y486881D02*
Y489463D01*
G01X144172Y487324D02*
Y489020D01*
G01X143112Y489463D02*
X144601Y490952D01*
G01X144172Y489020D02*
X145044Y489892D01*
G01X144601Y490952D02*
X145940D01*
G01X145044Y489892D02*
X146383D01*
G01X145940Y490952D02*
X146812Y491824D01*
G01X146383Y489892D02*
X147872Y491381D01*
G01X146812Y491824D02*
Y493520D01*
G01X147872Y491381D02*
Y493963D01*
G01X146812Y493520D02*
X145940Y494392D01*
G01X147872Y493963D02*
X146383Y495452D01*
G01X145940Y494392D02*
X144401D01*
G01X146383Y495452D02*
X144844D01*
G01X144401Y494392D02*
X142912Y495881D01*
G01X144844Y495452D02*
X143972Y496324D01*
G01X142912Y495881D02*
Y498463D01*
G01X143972Y496324D02*
Y498020D01*
G01X142912Y498463D02*
X144401Y499952D01*
G01X143972Y498020D02*
X144844Y498892D01*
G01X144401Y499952D02*
X145572D01*
G01X144844Y498892D02*
X146015D01*
G01X144401Y499952D02*
X145572D01*
G01D02*
X146812Y501192D01*
G01X146015Y498892D02*
X147872Y500749D01*
G01X146812Y501192D02*
Y502749D01*
G01X147872Y500749D02*
Y503192D01*
G01X146812Y502749D02*
X143912Y505649D01*
G01X147872Y503192D02*
X144972Y506092D01*
G01X143912Y505649D02*
Y507080D01*
G01Y509520D02*
Y512280D01*
G01X144972Y506092D02*
Y512720D01*
G01X143912Y512280D02*
X143278Y512914D01*
G01X144972Y512720D02*
X143718Y513974D01*
G01X143278Y512914D02*
X141880D01*
G01X143718Y513974D02*
X143420D01*
G01X135852Y520290D02*
Y521660D01*
G01Y525340D02*
Y526760D01*
G01X134792Y514400D02*
Y532411D01*
G01X140672Y464887D02*
Y466783D01*
G01D02*
X141544Y467655D01*
G01X139612Y467223D02*
X141104Y468715D01*
G01X141544Y467655D02*
X142875D01*
G01D02*
X144064Y468844D01*
G01X141104Y468715D02*
X142435D01*
G01X142875Y467655D02*
X144064Y468844D01*
G01X142435Y468715D02*
X143004Y469284D01*
G01X144064Y468844D02*
Y471726D01*
G01X143004Y469284D02*
Y471286D01*
G01X144064Y471726D02*
X142575Y473215D01*
G01X143004Y471286D02*
X142135Y472155D01*
G01X144064Y471726D02*
X142575Y473215D01*
G01D02*
X141044D01*
G01X142135Y472155D02*
X140604D01*
G01X141044Y473215D02*
X140072Y474187D01*
G01X140604Y472155D02*
X139012Y473747D01*
G01X140072Y474187D02*
Y512008D01*
G01X139012Y473747D02*
Y506680D01*
G01X140072Y474187D02*
Y512008D01*
G01X139012Y509120D02*
Y511568D01*
G01X140072Y512008D02*
X136780Y515300D01*
G01X139012Y511568D02*
X137761Y512819D01*
G01X140175Y527500D02*
X139345Y526670D01*
G01X140175Y527500D02*
X139345Y526670D01*
G01X140175Y527500D02*
X139345Y526670D01*
G01X140175Y527500D02*
X139345Y526670D01*
G01X174690Y87300D02*
X175637Y86353D01*
G01X173591Y89900D02*
X176697Y86794D01*
G01X175637Y86353D02*
Y83820D01*
G01Y79680D02*
Y78720D01*
G01Y74380D02*
Y71091D01*
G01X176697Y86794D02*
Y70648D01*
G01X175637Y71091D02*
X174926Y70380D01*
G01X176697Y70648D02*
X175369Y69320D01*
G01X174926Y70380D02*
X174410D01*
G01X175369Y69320D02*
X174387D01*
G01X208564Y96096D02*
X210160Y94500D01*
G01X211501Y87300D02*
X212448Y86353D01*
G01X210402Y89900D02*
X213508Y86794D01*
G01X212448Y86353D02*
Y83820D01*
G01Y79680D02*
Y78720D01*
G01Y74380D02*
Y71091D01*
G01X213508Y86794D02*
Y70648D01*
G01X212448Y71091D02*
X211737Y70380D01*
G01X213508Y70648D02*
X212180Y69320D01*
G01X211737Y70380D02*
X211221D01*
G01X212180Y69320D02*
X211198D01*
G01X208564Y96096D02*
X210160Y94500D01*
G01X211501Y87300D02*
X212448Y86353D01*
G01X210402Y89900D02*
X213508Y86794D01*
G01X212448Y86353D02*
Y83820D01*
G01Y79680D02*
Y78720D01*
G01Y74380D02*
Y71091D01*
G01X213508Y86794D02*
Y70648D01*
G01X212448Y71091D02*
X211737Y70380D01*
G01X213508Y70648D02*
X212180Y69320D01*
G01X211737Y70380D02*
X211221D01*
G01X212180Y69320D02*
X211198D01*
G01X178691Y90114D02*
X181883Y86922D01*
G01X179789Y87515D02*
X180823Y86481D01*
G01X181883Y86922D02*
Y71532D01*
G01X180823Y86481D02*
Y83706D01*
G01X181883Y86922D02*
Y71532D01*
G01X180823Y79880D02*
Y78507D01*
G01X181883Y86922D02*
Y71532D01*
G01X180823Y74593D02*
Y71972D01*
G01X181883Y71532D02*
X178691Y68340D01*
G01X180823Y71972D02*
X179800Y70949D01*
G01X217328Y93332D02*
X213496Y97164D01*
G01X218694Y86922D02*
X215502Y90114D01*
G01Y87515D02*
X216600D01*
G01X218694Y86922D02*
X215502Y90114D01*
G01X216600Y87515D02*
X217634Y86481D01*
G01X218694Y71532D02*
Y86922D01*
G01X217634Y86481D02*
Y83706D01*
G01X218694Y71532D02*
Y86922D01*
G01X217634Y79880D02*
Y78507D01*
G01X218694Y71532D02*
Y86922D01*
G01X217634Y74593D02*
Y71972D01*
G01X215502Y68340D02*
X218694Y71532D01*
G01X217634Y71972D02*
X216611Y70949D01*
G01X217328Y93332D02*
X213496Y97164D01*
G01X218694Y86922D02*
X215502Y90114D01*
G01Y87515D02*
X216600D01*
G01X218694Y86922D02*
X215502Y90114D01*
G01X216600Y87515D02*
X217634Y86481D01*
G01X218694Y71532D02*
Y86922D01*
G01X217634Y86481D02*
Y83706D01*
G01X218694Y71532D02*
Y86922D01*
G01X217634Y79880D02*
Y78507D01*
G01X218694Y71532D02*
Y86922D01*
G01X217634Y74593D02*
Y71972D01*
G01X215502Y68340D02*
X218694Y71532D01*
G01X217634Y71972D02*
X216611Y70949D01*
G01X173591Y89900D02*
X176697Y86794D01*
G01X174690Y87300D02*
X175637Y86353D01*
G01X176697Y86794D02*
Y70648D01*
G01X175637Y86353D02*
Y83820D01*
G01X176697Y86794D02*
Y70648D01*
G01X175637Y79680D02*
Y78720D01*
G01X176697Y86794D02*
Y70648D01*
G01X175637Y74380D02*
Y71091D01*
G01X176697Y70648D02*
X175369Y69320D01*
G01X175637Y71091D02*
X174926Y70380D01*
G01X175369Y69320D02*
X174387D01*
G01X174926Y70380D02*
X174410D01*
G01X208564Y96096D02*
X210160Y94500D01*
G01X210402Y89900D02*
X213508Y86794D01*
G01X211501Y87300D02*
X212448Y86353D01*
G01X213508Y86794D02*
Y70648D01*
G01X212448Y86353D02*
Y83820D01*
G01X213508Y86794D02*
Y70648D01*
G01X212448Y79680D02*
Y78720D01*
G01X213508Y86794D02*
Y70648D01*
G01X212448Y74380D02*
Y71091D01*
G01X213508Y70648D02*
X212180Y69320D01*
G01X212448Y71091D02*
X211737Y70380D01*
G01X212180Y69320D02*
X211198D01*
G01X211737Y70380D02*
X211221D01*
G01X208564Y96096D02*
X210160Y94500D01*
G01X210402Y89900D02*
X213508Y86794D01*
G01X211501Y87300D02*
X212448Y86353D01*
G01X213508Y86794D02*
Y70648D01*
G01X212448Y86353D02*
Y83820D01*
G01X213508Y86794D02*
Y70648D01*
G01X212448Y79680D02*
Y78720D01*
G01X213508Y86794D02*
Y70648D01*
G01X212448Y74380D02*
Y71091D01*
G01X213508Y70648D02*
X212180Y69320D01*
G01X212448Y71091D02*
X211737Y70380D01*
G01X212180Y69320D02*
X211198D01*
G01X211737Y70380D02*
X211221D01*
G01X179789Y87515D02*
X180823Y86481D01*
G01X178691Y90114D02*
X181883Y86922D01*
G01X180823Y86481D02*
Y83706D01*
G01Y79880D02*
Y78507D01*
G01Y74593D02*
Y71972D01*
G01X181883Y86922D02*
Y71532D01*
G01X180823Y71972D02*
X179800Y70949D01*
G01X181883Y71532D02*
X178691Y68340D01*
G01X217634Y71972D02*
X216611Y70949D01*
G01X215502Y68340D02*
X218694Y71532D01*
G01X217634Y86481D02*
Y83706D01*
G01Y79880D02*
Y78507D01*
G01Y74593D02*
Y71972D01*
G01X218694Y71532D02*
Y86922D01*
G01X215502Y87515D02*
X216600D01*
G01D02*
X217634Y86481D01*
G01X218694Y86922D02*
X215502Y90114D01*
G01X217328Y93332D02*
X213496Y97164D01*
G01X217634Y71972D02*
X216611Y70949D01*
G01X215502Y68340D02*
X218694Y71532D01*
G01X217634Y86481D02*
Y83706D01*
G01Y79880D02*
Y78507D01*
G01Y74593D02*
Y71972D01*
G01X218694Y71532D02*
Y86922D01*
G01X215502Y87515D02*
X216600D01*
G01D02*
X217634Y86481D01*
G01X218694Y86922D02*
X215502Y90114D01*
G01X217328Y93332D02*
X213496Y97164D01*
G01X205532Y159553D02*
Y156007D01*
G01D02*
X206854Y154685D01*
G01X206592Y156447D02*
X207294Y155745D01*
G01X206854Y154685D02*
X209213D01*
G01X207294Y155745D02*
X209653D01*
G01X209213Y154685D02*
X210082Y153816D01*
G01X209653Y155745D02*
X211142Y154256D01*
G01X210082Y153816D02*
Y151244D01*
G01X211142Y154256D02*
Y150804D01*
G01X210082Y151244D02*
X209283Y150445D01*
G01X211142Y150804D02*
X209723Y149385D01*
G01X209283Y150445D02*
X207501D01*
G01D02*
X206104Y149048D01*
G01X209723Y149385D02*
X207944D01*
G01X207501Y150445D02*
X206104Y149048D01*
G01X207944Y149385D02*
X207164Y148605D01*
G01X206104Y149048D02*
Y130757D01*
G01X207164Y148605D02*
Y131200D01*
G01X206104Y130757D02*
X207504Y129357D01*
G01X207164Y131200D02*
X208564Y129800D01*
G01X207504Y129357D02*
Y95653D01*
G01X208564Y129800D02*
Y108264D01*
G01X207504Y129357D02*
Y95653D01*
G01X208564Y106024D02*
Y105264D01*
G01X207504Y129357D02*
Y95653D01*
G01X208564Y103024D02*
Y102264D01*
G01X207504Y129357D02*
Y95653D01*
G01X208564Y100024D02*
Y99264D01*
G01X207504Y129357D02*
Y95653D01*
G01X208564Y97024D02*
Y96096D01*
G01X207504Y95653D02*
X208428Y94729D01*
G01X205532Y159553D02*
Y156007D01*
G01D02*
X206854Y154685D01*
G01X206592Y156447D02*
X207294Y155745D01*
G01X206854Y154685D02*
X209213D01*
G01X207294Y155745D02*
X209653D01*
G01X209213Y154685D02*
X210082Y153816D01*
G01X209653Y155745D02*
X211142Y154256D01*
G01X210082Y153816D02*
Y151244D01*
G01X211142Y154256D02*
Y150804D01*
G01X210082Y151244D02*
X209283Y150445D01*
G01X211142Y150804D02*
X209723Y149385D01*
G01X209283Y150445D02*
X207501D01*
G01D02*
X206104Y149048D01*
G01X209723Y149385D02*
X207944D01*
G01X207501Y150445D02*
X206104Y149048D01*
G01X207944Y149385D02*
X207164Y148605D01*
G01X206104Y149048D02*
Y130757D01*
G01X207164Y148605D02*
Y131200D01*
G01X206104Y130757D02*
X207504Y129357D01*
G01X207164Y131200D02*
X208564Y129800D01*
G01X207504Y129357D02*
Y95653D01*
G01X208564Y129800D02*
Y108264D01*
G01X207504Y129357D02*
Y95653D01*
G01X208564Y106024D02*
Y105264D01*
G01X207504Y129357D02*
Y95653D01*
G01X208564Y103024D02*
Y102264D01*
G01X207504Y129357D02*
Y95653D01*
G01X208564Y100024D02*
Y99264D01*
G01X207504Y129357D02*
Y95653D01*
G01X208564Y97024D02*
Y96096D01*
G01X207504Y95653D02*
X208428Y94729D01*
G01X214264Y147321D02*
Y168138D01*
G01X213204Y168578D02*
Y147764D01*
G01X212775Y145832D02*
X214264Y147321D01*
G01X213204Y147764D02*
X212332Y146892D01*
G01X212136Y145832D02*
X212775D01*
G01X212332Y146892D02*
X211693D01*
G01X210964Y144660D02*
X212136Y145832D01*
G01X211693Y146892D02*
X209904Y145103D01*
G01X210964Y142464D02*
Y144660D01*
G01X209904Y145103D02*
Y142021D01*
G01X211836Y141592D02*
X210964Y142464D01*
G01X209904Y142021D02*
X211393Y140532D01*
G01X212775Y141592D02*
X211836D01*
G01X211393Y140532D02*
X212332D01*
G01X214264Y140103D02*
X212775Y141592D01*
G01X212332Y140532D02*
X213204Y139660D01*
G01X214264Y136721D02*
Y140103D01*
G01X213204Y139660D02*
Y137164D01*
G01X212775Y135232D02*
X214264Y136721D01*
G01X213204Y137164D02*
X212332Y136292D01*
G01X212232Y135232D02*
X212775D01*
G01X212332Y136292D02*
X211789D01*
G01X211264Y134264D02*
X212232Y135232D01*
G01X211789Y136292D02*
X210204Y134707D01*
G01X211264Y132764D02*
Y134264D01*
G01X210204Y134707D02*
Y132324D01*
G01X214264Y129764D02*
X211264Y132764D01*
G01X210204Y132324D02*
X213204Y129324D01*
G01X214264Y125960D02*
Y129764D01*
G01X213204Y129324D02*
Y126400D01*
G01X212052Y123748D02*
X214264Y125960D01*
G01X213204Y126400D02*
X210992Y124188D01*
G01X212052Y121552D02*
Y123748D01*
G01X210992Y124188D02*
Y121112D01*
G01X214264Y119340D02*
X212052Y121552D01*
G01X210992Y121112D02*
X213204Y118900D01*
G01X214264Y114572D02*
Y119340D01*
G01X213204Y118900D02*
Y115012D01*
G01X213496Y113804D02*
X214264Y114572D01*
G01X213204Y115012D02*
X212436Y114244D01*
G01X213496Y97164D02*
Y98092D01*
G01Y100332D02*
Y101092D01*
G01Y103332D02*
Y104092D01*
G01Y106332D02*
Y107092D01*
G01Y109332D02*
Y110180D01*
G01Y112420D02*
Y113804D01*
G01X212436Y114244D02*
Y96721D01*
G01D02*
X213778Y95379D01*
G01X214264Y147321D02*
Y168138D01*
G01X213204Y168578D02*
Y147764D01*
G01X212775Y145832D02*
X214264Y147321D01*
G01X213204Y147764D02*
X212332Y146892D01*
G01X212136Y145832D02*
X212775D01*
G01X212332Y146892D02*
X211693D01*
G01X210964Y144660D02*
X212136Y145832D01*
G01X211693Y146892D02*
X209904Y145103D01*
G01X210964Y142464D02*
Y144660D01*
G01X209904Y145103D02*
Y142021D01*
G01X211836Y141592D02*
X210964Y142464D01*
G01X209904Y142021D02*
X211393Y140532D01*
G01X212775Y141592D02*
X211836D01*
G01X211393Y140532D02*
X212332D01*
G01X214264Y140103D02*
X212775Y141592D01*
G01X212332Y140532D02*
X213204Y139660D01*
G01X214264Y136721D02*
Y140103D01*
G01X213204Y139660D02*
Y137164D01*
G01X212775Y135232D02*
X214264Y136721D01*
G01X213204Y137164D02*
X212332Y136292D01*
G01X212232Y135232D02*
X212775D01*
G01X212332Y136292D02*
X211789D01*
G01X211264Y134264D02*
X212232Y135232D01*
G01X211789Y136292D02*
X210204Y134707D01*
G01X211264Y132764D02*
Y134264D01*
G01X210204Y134707D02*
Y132324D01*
G01X214264Y129764D02*
X211264Y132764D01*
G01X210204Y132324D02*
X213204Y129324D01*
G01X214264Y125960D02*
Y129764D01*
G01X213204Y129324D02*
Y126400D01*
G01X212052Y123748D02*
X214264Y125960D01*
G01X213204Y126400D02*
X210992Y124188D01*
G01X212052Y121552D02*
Y123748D01*
G01X210992Y124188D02*
Y121112D01*
G01X214264Y119340D02*
X212052Y121552D01*
G01X210992Y121112D02*
X213204Y118900D01*
G01X214264Y114572D02*
Y119340D01*
G01X213204Y118900D02*
Y115012D01*
G01X213496Y113804D02*
X214264Y114572D01*
G01X213204Y115012D02*
X212436Y114244D01*
G01X213496Y97164D02*
Y98092D01*
G01Y100332D02*
Y101092D01*
G01Y103332D02*
Y104092D01*
G01Y106332D02*
Y107092D01*
G01Y109332D02*
Y110180D01*
G01Y112420D02*
Y113804D01*
G01X212436Y114244D02*
Y96721D01*
G01D02*
X213778Y95379D01*
G01X205532Y159553D02*
Y156007D01*
G01X206592Y156447D02*
X207294Y155745D01*
G01X205532Y156007D02*
X206854Y154685D01*
G01X207294Y155745D02*
X209653D01*
G01X206854Y154685D02*
X209213D01*
G01X209653Y155745D02*
X211142Y154256D01*
G01X209213Y154685D02*
X210082Y153816D01*
G01X211142Y154256D02*
Y150804D01*
G01X210082Y153816D02*
Y151244D01*
G01X211142Y150804D02*
X209723Y149385D01*
G01X210082Y151244D02*
X209283Y150445D01*
G01X209723Y149385D02*
X207944D01*
G01X209283Y150445D02*
X207501D01*
G01X209723Y149385D02*
X207944D01*
G01D02*
X207164Y148605D01*
G01X207501Y150445D02*
X206104Y149048D01*
G01X207164Y148605D02*
Y131200D01*
G01X206104Y149048D02*
Y130757D01*
G01X207164Y131200D02*
X208564Y129800D01*
G01X206104Y130757D02*
X207504Y129357D01*
G01X208564Y129800D02*
Y108264D01*
G01Y106024D02*
Y105264D01*
G01Y103024D02*
Y102264D01*
G01Y100024D02*
Y99264D01*
G01Y97024D02*
Y96096D01*
G01X207504Y129357D02*
Y95653D01*
G01D02*
X208428Y94729D01*
G01X205532Y159553D02*
Y156007D01*
G01X206592Y156447D02*
X207294Y155745D01*
G01X205532Y156007D02*
X206854Y154685D01*
G01X207294Y155745D02*
X209653D01*
G01X206854Y154685D02*
X209213D01*
G01X209653Y155745D02*
X211142Y154256D01*
G01X209213Y154685D02*
X210082Y153816D01*
G01X211142Y154256D02*
Y150804D01*
G01X210082Y153816D02*
Y151244D01*
G01X211142Y150804D02*
X209723Y149385D01*
G01X210082Y151244D02*
X209283Y150445D01*
G01X209723Y149385D02*
X207944D01*
G01X209283Y150445D02*
X207501D01*
G01X209723Y149385D02*
X207944D01*
G01D02*
X207164Y148605D01*
G01X207501Y150445D02*
X206104Y149048D01*
G01X207164Y148605D02*
Y131200D01*
G01X206104Y149048D02*
Y130757D01*
G01X207164Y131200D02*
X208564Y129800D01*
G01X206104Y130757D02*
X207504Y129357D01*
G01X208564Y129800D02*
Y108264D01*
G01Y106024D02*
Y105264D01*
G01Y103024D02*
Y102264D01*
G01Y100024D02*
Y99264D01*
G01Y97024D02*
Y96096D01*
G01X207504Y129357D02*
Y95653D01*
G01D02*
X208428Y94729D01*
G01X212436Y96721D02*
X213778Y95379D01*
G01X212436Y114244D02*
Y96721D01*
G01X213496Y97164D02*
Y98092D01*
G01X212436Y114244D02*
Y96721D01*
G01X213496Y100332D02*
Y101092D01*
G01X212436Y114244D02*
Y96721D01*
G01X213496Y103332D02*
Y104092D01*
G01X212436Y114244D02*
Y96721D01*
G01X213496Y106332D02*
Y107092D01*
G01X212436Y114244D02*
Y96721D01*
G01X213496Y109332D02*
Y110180D01*
G01X212436Y114244D02*
Y96721D01*
G01X213496Y112420D02*
Y113804D01*
G01X213204Y115012D02*
X212436Y114244D01*
G01X213496Y113804D02*
X214264Y114572D01*
G01X213204Y118900D02*
Y115012D01*
G01X214264Y114572D02*
Y119340D01*
G01X210992Y121112D02*
X213204Y118900D01*
G01X214264Y119340D02*
X212052Y121552D01*
G01X210992Y124188D02*
Y121112D01*
G01X212052Y121552D02*
Y123748D01*
G01X213204Y126400D02*
X210992Y124188D01*
G01X212052Y123748D02*
X214264Y125960D01*
G01X213204Y129324D02*
Y126400D01*
G01X214264Y125960D02*
Y129764D01*
G01X210204Y132324D02*
X213204Y129324D01*
G01X214264Y129764D02*
X211264Y132764D01*
G01X210204Y134707D02*
Y132324D01*
G01X211264Y132764D02*
Y134264D01*
G01X211789Y136292D02*
X210204Y134707D01*
G01X211264Y134264D02*
X212232Y135232D01*
G01X212332Y136292D02*
X211789D01*
G01X212232Y135232D02*
X212775D01*
G01X213204Y137164D02*
X212332Y136292D01*
G01X212775Y135232D02*
X214264Y136721D01*
G01X213204Y139660D02*
Y137164D01*
G01X214264Y136721D02*
Y140103D01*
G01X212332Y140532D02*
X213204Y139660D01*
G01X214264Y140103D02*
X212775Y141592D01*
G01X211393Y140532D02*
X212332D01*
G01X212775Y141592D02*
X211836D01*
G01X209904Y142021D02*
X211393Y140532D01*
G01X211836Y141592D02*
X210964Y142464D01*
G01X209904Y145103D02*
Y142021D01*
G01X210964Y142464D02*
Y144660D01*
G01X211693Y146892D02*
X209904Y145103D01*
G01X210964Y144660D02*
X212136Y145832D01*
G01X212332Y146892D02*
X211693D01*
G01X212136Y145832D02*
X212775D01*
G01X213204Y147764D02*
X212332Y146892D01*
G01X212775Y145832D02*
X214264Y147321D01*
G01X213204Y168578D02*
Y147764D01*
G01X214264Y147321D02*
Y168138D01*
G01X212436Y96721D02*
X213778Y95379D01*
G01X212436Y114244D02*
Y96721D01*
G01X213496Y97164D02*
Y98092D01*
G01X212436Y114244D02*
Y96721D01*
G01X213496Y100332D02*
Y101092D01*
G01X212436Y114244D02*
Y96721D01*
G01X213496Y103332D02*
Y104092D01*
G01X212436Y114244D02*
Y96721D01*
G01X213496Y106332D02*
Y107092D01*
G01X212436Y114244D02*
Y96721D01*
G01X213496Y109332D02*
Y110180D01*
G01X212436Y114244D02*
Y96721D01*
G01X213496Y112420D02*
Y113804D01*
G01X213204Y115012D02*
X212436Y114244D01*
G01X213496Y113804D02*
X214264Y114572D01*
G01X213204Y118900D02*
Y115012D01*
G01X214264Y114572D02*
Y119340D01*
G01X210992Y121112D02*
X213204Y118900D01*
G01X214264Y119340D02*
X212052Y121552D01*
G01X210992Y124188D02*
Y121112D01*
G01X212052Y121552D02*
Y123748D01*
G01X213204Y126400D02*
X210992Y124188D01*
G01X212052Y123748D02*
X214264Y125960D01*
G01X213204Y129324D02*
Y126400D01*
G01X214264Y125960D02*
Y129764D01*
G01X210204Y132324D02*
X213204Y129324D01*
G01X214264Y129764D02*
X211264Y132764D01*
G01X210204Y134707D02*
Y132324D01*
G01X211264Y132764D02*
Y134264D01*
G01X211789Y136292D02*
X210204Y134707D01*
G01X211264Y134264D02*
X212232Y135232D01*
G01X212332Y136292D02*
X211789D01*
G01X212232Y135232D02*
X212775D01*
G01X213204Y137164D02*
X212332Y136292D01*
G01X212775Y135232D02*
X214264Y136721D01*
G01X213204Y139660D02*
Y137164D01*
G01X214264Y136721D02*
Y140103D01*
G01X212332Y140532D02*
X213204Y139660D01*
G01X214264Y140103D02*
X212775Y141592D01*
G01X211393Y140532D02*
X212332D01*
G01X212775Y141592D02*
X211836D01*
G01X209904Y142021D02*
X211393Y140532D01*
G01X211836Y141592D02*
X210964Y142464D01*
G01X209904Y145103D02*
Y142021D01*
G01X210964Y142464D02*
Y144660D01*
G01X211693Y146892D02*
X209904Y145103D01*
G01X210964Y144660D02*
X212136Y145832D01*
G01X212332Y146892D02*
X211693D01*
G01X212136Y145832D02*
X212775D01*
G01X213204Y147764D02*
X212332Y146892D01*
G01X212775Y145832D02*
X214264Y147321D01*
G01X213204Y168578D02*
Y147764D01*
G01X214264Y147321D02*
Y168138D01*
G01X257618Y219775D02*
X209404Y171561D01*
G01X257618Y219775D02*
X209404Y171561D01*
G01X257618Y219775D02*
X209404Y171561D01*
G01X257618Y219775D02*
X209404Y171561D01*
G01X257618Y219775D02*
X209404Y171561D01*
G01X257618Y219775D02*
X209404Y171561D01*
G01X257618Y219775D02*
X209404Y171561D01*
G01X257618Y219775D02*
X209404Y171561D01*
G01X257618Y219775D02*
X209404Y171561D01*
G01X257618Y219775D02*
X209404Y171561D01*
G01X257618Y219775D02*
X209404Y171561D01*
G01X257618Y219775D02*
X209404Y171561D01*
G01X257618Y219775D02*
X209404Y171561D01*
G01X257618Y219775D02*
X209404Y171561D01*
G01X231445Y192102D02*
X230715Y191372D01*
G01X257618Y219775D02*
X209404Y171561D01*
G01X229370Y190027D02*
X210464Y171121D01*
G01X209404Y171561D02*
Y170012D01*
G01X210464Y171121D02*
Y169572D01*
G01X209404Y170012D02*
X207012Y167620D01*
G01X210464Y169572D02*
X208072Y167180D01*
G01X207012Y167620D02*
Y165880D01*
G01X208072Y167180D02*
Y166320D01*
G01X207012Y165880D02*
X209404Y163488D01*
G01X208072Y166320D02*
X210464Y163928D01*
G01X209404Y163488D02*
Y161917D01*
G01X210464Y163928D02*
Y161477D01*
G01X209404Y161917D02*
X208532Y161045D01*
G01X210464Y161477D02*
X208972Y159985D01*
G01X208532Y161045D02*
X207024D01*
G01X208972Y159985D02*
X207464D01*
G01X207024Y161045D02*
X205532Y159553D01*
G01X207464Y159985D02*
X206592Y159113D01*
G01D02*
Y156447D01*
G01X257618Y219775D02*
X209404Y171561D01*
G01X257618Y219775D02*
X209404Y171561D01*
G01X257618Y219775D02*
X209404Y171561D01*
G01X257618Y219775D02*
X209404Y171561D01*
G01X257618Y219775D02*
X209404Y171561D01*
G01X257618Y219775D02*
X209404Y171561D01*
G01X257618Y219775D02*
X209404Y171561D01*
G01X257618Y219775D02*
X209404Y171561D01*
G01X257618Y219775D02*
X209404Y171561D01*
G01X257618Y219775D02*
X209404Y171561D01*
G01X257618Y219775D02*
X209404Y171561D01*
G01X257618Y219775D02*
X209404Y171561D01*
G01X257618Y219775D02*
X209404Y171561D01*
G01X257618Y219775D02*
X209404Y171561D01*
G01X231445Y192102D02*
X230715Y191372D01*
G01X257618Y219775D02*
X209404Y171561D01*
G01X229370Y190027D02*
X210464Y171121D01*
G01X209404Y171561D02*
Y170012D01*
G01X210464Y171121D02*
Y169572D01*
G01X209404Y170012D02*
X207012Y167620D01*
G01X210464Y169572D02*
X208072Y167180D01*
G01X207012Y167620D02*
Y165880D01*
G01X208072Y167180D02*
Y166320D01*
G01X207012Y165880D02*
X209404Y163488D01*
G01X208072Y166320D02*
X210464Y163928D01*
G01X209404Y163488D02*
Y161917D01*
G01X210464Y163928D02*
Y161477D01*
G01X209404Y161917D02*
X208532Y161045D01*
G01X210464Y161477D02*
X208972Y159985D01*
G01X208532Y161045D02*
X207024D01*
G01X208972Y159985D02*
X207464D01*
G01X207024Y161045D02*
X205532Y159553D01*
G01X207464Y159985D02*
X206592Y159113D01*
G01D02*
Y156447D01*
G01X214264Y168138D02*
X250847Y204721D01*
G01X263022Y218396D02*
X213204Y168578D01*
G01X214264Y168138D02*
X250847Y204721D01*
G01X263022Y218396D02*
X213204Y168578D01*
G01X231445Y192102D02*
X230715Y191372D01*
G01X229370Y190027D02*
X210464Y171121D01*
G01X257618Y219775D02*
X209404Y171561D01*
G01X210464Y171121D02*
Y169572D01*
G01X209404Y171561D02*
Y170012D01*
G01X210464Y169572D02*
X208072Y167180D01*
G01X209404Y170012D02*
X207012Y167620D01*
G01X208072Y167180D02*
Y166320D01*
G01X207012Y167620D02*
Y165880D01*
G01X208072Y166320D02*
X210464Y163928D01*
G01X207012Y165880D02*
X209404Y163488D01*
G01X210464Y163928D02*
Y161477D01*
G01X209404Y163488D02*
Y161917D01*
G01X210464Y161477D02*
X208972Y159985D01*
G01X209404Y161917D02*
X208532Y161045D01*
G01X208972Y159985D02*
X207464D01*
G01X208532Y161045D02*
X207024D01*
G01X207464Y159985D02*
X206592Y159113D01*
G01X207024Y161045D02*
X205532Y159553D01*
G01X206592Y159113D02*
Y156447D01*
G01X231445Y192102D02*
X230715Y191372D01*
G01X229370Y190027D02*
X210464Y171121D01*
G01X257618Y219775D02*
X209404Y171561D01*
G01X210464Y171121D02*
Y169572D01*
G01X209404Y171561D02*
Y170012D01*
G01X210464Y169572D02*
X208072Y167180D01*
G01X209404Y170012D02*
X207012Y167620D01*
G01X208072Y167180D02*
Y166320D01*
G01X207012Y167620D02*
Y165880D01*
G01X208072Y166320D02*
X210464Y163928D01*
G01X207012Y165880D02*
X209404Y163488D01*
G01X210464Y163928D02*
Y161477D01*
G01X209404Y163488D02*
Y161917D01*
G01X210464Y161477D02*
X208972Y159985D01*
G01X209404Y161917D02*
X208532Y161045D01*
G01X208972Y159985D02*
X207464D01*
G01X208532Y161045D02*
X207024D01*
G01X207464Y159985D02*
X206592Y159113D01*
G01X207024Y161045D02*
X205532Y159553D01*
G01X206592Y159113D02*
Y156447D01*
G01X263022Y218396D02*
X213204Y168578D01*
G01X214264Y168138D02*
X250847Y204721D01*
G01X263022Y218396D02*
X213204Y168578D01*
G01X263022Y218396D02*
X213204Y168578D01*
G01X263022Y218396D02*
X213204Y168578D01*
G01X263022Y218396D02*
X213204Y168578D01*
G01X263022Y218396D02*
X213204Y168578D01*
G01X263022Y218396D02*
X213204Y168578D01*
G01X263022Y218396D02*
X213204Y168578D01*
G01X214264Y168138D02*
X250847Y204721D01*
G01X263022Y218396D02*
X213204Y168578D01*
G01X263022Y218396D02*
X213204Y168578D01*
G01X263022Y218396D02*
X213204Y168578D01*
G01X263022Y218396D02*
X213204Y168578D01*
G01X263022Y218396D02*
X213204Y168578D01*
G01X263022Y218396D02*
X213204Y168578D01*
G01X255441Y344877D02*
X208092Y392226D01*
G01X255001Y343817D02*
X207032Y391786D01*
G01X208092Y392226D02*
Y398500D01*
G01X207032Y391786D02*
Y398060D01*
G01X254555Y340096D02*
X203832Y390819D01*
G01X254995Y341156D02*
X204892Y391259D01*
G01X203832Y390819D02*
Y396959D01*
G01X204892Y391259D02*
Y397399D01*
G01X255001Y343817D02*
X207032Y391786D01*
G01X255441Y344877D02*
X208092Y392226D01*
G01X207032Y391786D02*
Y398060D01*
G01X208092Y392226D02*
Y398500D01*
G01X254995Y341156D02*
X204892Y391259D01*
G01X254555Y340096D02*
X203832Y390819D01*
G01X204892Y391259D02*
Y397399D01*
G01X203832Y390819D02*
Y396959D01*
G01X255441Y344877D02*
X208092Y392226D01*
G01X255001Y343817D02*
X207032Y391786D01*
G01X208092Y392226D02*
Y398500D01*
G01X207032Y391786D02*
Y398060D01*
G01X254555Y340096D02*
X203832Y390819D01*
G01X254995Y341156D02*
X204892Y391259D01*
G01X203832Y390819D02*
Y396959D01*
G01X204892Y391259D02*
Y397399D01*
G01X255001Y343817D02*
X207032Y391786D01*
G01X255441Y344877D02*
X208092Y392226D01*
G01X207032Y391786D02*
Y398060D01*
G01X208092Y392226D02*
Y398500D01*
G01X254995Y341156D02*
X204892Y391259D01*
G01X254555Y340096D02*
X203832Y390819D01*
G01X204892Y391259D02*
Y397399D01*
G01X203832Y390819D02*
Y396959D01*
G01X257581Y370801D02*
X226227Y402155D01*
G01X258331Y371551D02*
X227287Y402595D01*
G01X226227Y402155D02*
Y411633D01*
G01X227287Y402595D02*
Y412073D01*
G01X253805Y379826D02*
X229172Y404460D01*
G01X258331Y371551D02*
X227287Y402595D01*
G01X257581Y370801D02*
X226227Y402155D01*
G01X227287Y402595D02*
Y412073D01*
G01X226227Y402155D02*
Y411633D01*
G01X253805Y379826D02*
X229172Y404460D01*
G01X257581Y370801D02*
X226227Y402155D01*
G01X258331Y371551D02*
X227287Y402595D01*
G01X226227Y402155D02*
Y411633D01*
G01X227287Y402595D02*
Y412073D01*
G01X253805Y379826D02*
X229172Y404460D01*
G01X258331Y371551D02*
X227287Y402595D01*
G01X257581Y370801D02*
X226227Y402155D01*
G01X227287Y402595D02*
Y412073D01*
G01X226227Y402155D02*
Y411633D01*
G01X253805Y379826D02*
X229172Y404460D01*
G01X226227Y411633D02*
X203512Y434348D01*
G01X227287Y412073D02*
X204572Y434788D01*
G01X203512Y434348D02*
Y441385D01*
G01Y444015D02*
Y448291D01*
G01X204572Y434788D02*
Y447848D01*
G01X203512Y448291D02*
X206709Y451488D01*
G01X204572Y447848D02*
X207769Y451045D01*
G01X206709Y451488D02*
Y454156D01*
G01X207769Y451045D02*
Y454596D01*
G01X206709Y454156D02*
X205000Y455865D01*
G01X207769Y454596D02*
X206060Y456305D01*
G01X205000Y455865D02*
Y458581D01*
G01X206060Y456305D02*
Y458141D01*
G01X205000Y458581D02*
X206912Y460493D01*
G01X206060Y458141D02*
X207972Y460053D01*
G01X206912Y460493D02*
Y503362D01*
G01X207972Y460053D02*
Y502922D01*
G01X254556Y380578D02*
X230232Y404904D01*
G01D02*
Y414542D01*
G01X229172Y404460D02*
Y414102D01*
G01X230232Y414542D02*
X218172Y426602D01*
G01X229172Y414102D02*
X217112Y426162D01*
G01X218172Y426602D02*
Y432834D01*
G01X217112Y426162D02*
Y432394D01*
G01X218172Y432834D02*
X216680Y434326D01*
G01X217112Y432394D02*
X216240Y433266D01*
G01X216680Y434326D02*
X210229D01*
G01X216240Y433266D02*
X209789D01*
G01X210229Y434326D02*
X209360Y435195D01*
G01X209789Y433266D02*
X208300Y434755D01*
G01X209360Y435195D02*
Y436897D01*
G01X208300Y434755D02*
Y437337D01*
G01X209360Y436897D02*
X210229Y437766D01*
G01X208300Y437337D02*
X209789Y438826D01*
G01X210229Y437766D02*
X216680D01*
G01X209789Y438826D02*
X216240D01*
G01X216680Y437766D02*
X218172Y439258D01*
G01X216240Y438826D02*
X217112Y439698D01*
G01X218172Y439258D02*
Y441690D01*
G01X217112Y439698D02*
Y441247D01*
G01X218172Y441690D02*
X216682Y443180D01*
G01X217112Y441247D02*
X216239Y442120D01*
G01X216682Y443180D02*
X210208D01*
G01X216239Y442120D02*
X209768D01*
G01X210208Y443180D02*
X209172Y444216D01*
G01X209768Y442120D02*
X208112Y443776D01*
G01X209172Y444216D02*
Y446520D01*
G01X208112Y443776D02*
Y446960D01*
G01X209172Y446520D02*
X211872Y449220D01*
G01X208112Y446960D02*
X210812Y449660D01*
G01X211872Y449220D02*
Y500409D01*
G01X210812Y449660D02*
Y478157D01*
G01X211872Y449220D02*
Y500409D01*
G01Y449220D02*
Y500409D01*
G01Y449220D02*
Y500409D01*
G01Y449220D02*
Y500409D01*
G01Y449220D02*
Y500409D01*
G01Y449220D02*
Y500409D01*
G01Y449220D02*
Y500409D01*
G01X227287Y412073D02*
X204572Y434788D01*
G01X226227Y411633D02*
X203512Y434348D01*
G01X204572Y434788D02*
Y447848D01*
G01X203512Y434348D02*
Y441385D01*
G01X204572Y434788D02*
Y447848D01*
G01X203512Y444015D02*
Y448291D01*
G01X204572Y447848D02*
X207769Y451045D01*
G01X203512Y448291D02*
X206709Y451488D01*
G01X207769Y451045D02*
Y454596D01*
G01X206709Y451488D02*
Y454156D01*
G01X207769Y454596D02*
X206060Y456305D01*
G01X206709Y454156D02*
X205000Y455865D01*
G01X206060Y456305D02*
Y458141D01*
G01X205000Y455865D02*
Y458581D01*
G01X206060Y458141D02*
X207972Y460053D01*
G01X205000Y458581D02*
X206912Y460493D01*
G01X207972Y460053D02*
Y502922D01*
G01X206912Y460493D02*
Y503362D01*
G01X254556Y380578D02*
X230232Y404904D01*
G01X229172Y404460D02*
Y414102D01*
G01X230232Y404904D02*
Y414542D01*
G01X229172Y414102D02*
X217112Y426162D01*
G01X230232Y414542D02*
X218172Y426602D01*
G01X217112Y426162D02*
Y432394D01*
G01X218172Y426602D02*
Y432834D01*
G01X217112Y432394D02*
X216240Y433266D01*
G01X218172Y432834D02*
X216680Y434326D01*
G01X216240Y433266D02*
X209789D01*
G01X216680Y434326D02*
X210229D01*
G01X209789Y433266D02*
X208300Y434755D01*
G01X210229Y434326D02*
X209360Y435195D01*
G01X208300Y434755D02*
Y437337D01*
G01X209360Y435195D02*
Y436897D01*
G01X208300Y437337D02*
X209789Y438826D01*
G01X209360Y436897D02*
X210229Y437766D01*
G01X209789Y438826D02*
X216240D01*
G01X210229Y437766D02*
X216680D01*
G01X216240Y438826D02*
X217112Y439698D01*
G01X216680Y437766D02*
X218172Y439258D01*
G01X217112Y439698D02*
Y441247D01*
G01X218172Y439258D02*
Y441690D01*
G01X217112Y441247D02*
X216239Y442120D01*
G01X218172Y441690D02*
X216682Y443180D01*
G01X216239Y442120D02*
X209768D01*
G01X216682Y443180D02*
X210208D01*
G01X209768Y442120D02*
X208112Y443776D01*
G01X210208Y443180D02*
X209172Y444216D01*
G01X208112Y443776D02*
Y446960D01*
G01X209172Y444216D02*
Y446520D01*
G01X208112Y446960D02*
X210812Y449660D01*
G01X209172Y446520D02*
X211872Y449220D01*
G01X210812Y449660D02*
Y478157D01*
G01X211872Y449220D02*
Y500409D01*
G01X226227Y411633D02*
X203512Y434348D01*
G01X227287Y412073D02*
X204572Y434788D01*
G01X203512Y434348D02*
Y441385D01*
G01Y444015D02*
Y448291D01*
G01X204572Y434788D02*
Y447848D01*
G01X203512Y448291D02*
X206709Y451488D01*
G01X204572Y447848D02*
X207769Y451045D01*
G01X206709Y451488D02*
Y454156D01*
G01X207769Y451045D02*
Y454596D01*
G01X206709Y454156D02*
X205000Y455865D01*
G01X207769Y454596D02*
X206060Y456305D01*
G01X205000Y455865D02*
Y458581D01*
G01X206060Y456305D02*
Y458141D01*
G01X205000Y458581D02*
X206912Y460493D01*
G01X206060Y458141D02*
X207972Y460053D01*
G01X206912Y460493D02*
Y503362D01*
G01X207972Y460053D02*
Y502922D01*
G01X254556Y380578D02*
X230232Y404904D01*
G01D02*
Y414542D01*
G01X229172Y404460D02*
Y414102D01*
G01X230232Y414542D02*
X218172Y426602D01*
G01X229172Y414102D02*
X217112Y426162D01*
G01X218172Y426602D02*
Y432834D01*
G01X217112Y426162D02*
Y432394D01*
G01X218172Y432834D02*
X216680Y434326D01*
G01X217112Y432394D02*
X216240Y433266D01*
G01X216680Y434326D02*
X210229D01*
G01X216240Y433266D02*
X209789D01*
G01X210229Y434326D02*
X209360Y435195D01*
G01X209789Y433266D02*
X208300Y434755D01*
G01X209360Y435195D02*
Y436897D01*
G01X208300Y434755D02*
Y437337D01*
G01X209360Y436897D02*
X210229Y437766D01*
G01X208300Y437337D02*
X209789Y438826D01*
G01X210229Y437766D02*
X216680D01*
G01X209789Y438826D02*
X216240D01*
G01X216680Y437766D02*
X218172Y439258D01*
G01X216240Y438826D02*
X217112Y439698D01*
G01X218172Y439258D02*
Y441690D01*
G01X217112Y439698D02*
Y441247D01*
G01X218172Y441690D02*
X216682Y443180D01*
G01X217112Y441247D02*
X216239Y442120D01*
G01X216682Y443180D02*
X210208D01*
G01X216239Y442120D02*
X209768D01*
G01X210208Y443180D02*
X209172Y444216D01*
G01X209768Y442120D02*
X208112Y443776D01*
G01X209172Y444216D02*
Y446520D01*
G01X208112Y443776D02*
Y446960D01*
G01X209172Y446520D02*
X211872Y449220D01*
G01X208112Y446960D02*
X210812Y449660D01*
G01X211872Y449220D02*
Y500409D01*
G01X210812Y449660D02*
Y478157D01*
G01X211872Y449220D02*
Y500409D01*
G01Y449220D02*
Y500409D01*
G01Y449220D02*
Y500409D01*
G01Y449220D02*
Y500409D01*
G01Y449220D02*
Y500409D01*
G01Y449220D02*
Y500409D01*
G01Y449220D02*
Y500409D01*
G01X227287Y412073D02*
X204572Y434788D01*
G01X226227Y411633D02*
X203512Y434348D01*
G01X204572Y434788D02*
Y447848D01*
G01X203512Y434348D02*
Y441385D01*
G01X204572Y434788D02*
Y447848D01*
G01X203512Y444015D02*
Y448291D01*
G01X204572Y447848D02*
X207769Y451045D01*
G01X203512Y448291D02*
X206709Y451488D01*
G01X207769Y451045D02*
Y454596D01*
G01X206709Y451488D02*
Y454156D01*
G01X207769Y454596D02*
X206060Y456305D01*
G01X206709Y454156D02*
X205000Y455865D01*
G01X206060Y456305D02*
Y458141D01*
G01X205000Y455865D02*
Y458581D01*
G01X206060Y458141D02*
X207972Y460053D01*
G01X205000Y458581D02*
X206912Y460493D01*
G01X207972Y460053D02*
Y502922D01*
G01X206912Y460493D02*
Y503362D01*
G01X254556Y380578D02*
X230232Y404904D01*
G01X229172Y404460D02*
Y414102D01*
G01X230232Y404904D02*
Y414542D01*
G01X229172Y414102D02*
X217112Y426162D01*
G01X230232Y414542D02*
X218172Y426602D01*
G01X217112Y426162D02*
Y432394D01*
G01X218172Y426602D02*
Y432834D01*
G01X217112Y432394D02*
X216240Y433266D01*
G01X218172Y432834D02*
X216680Y434326D01*
G01X216240Y433266D02*
X209789D01*
G01X216680Y434326D02*
X210229D01*
G01X209789Y433266D02*
X208300Y434755D01*
G01X210229Y434326D02*
X209360Y435195D01*
G01X208300Y434755D02*
Y437337D01*
G01X209360Y435195D02*
Y436897D01*
G01X208300Y437337D02*
X209789Y438826D01*
G01X209360Y436897D02*
X210229Y437766D01*
G01X209789Y438826D02*
X216240D01*
G01X210229Y437766D02*
X216680D01*
G01X216240Y438826D02*
X217112Y439698D01*
G01X216680Y437766D02*
X218172Y439258D01*
G01X217112Y439698D02*
Y441247D01*
G01X218172Y439258D02*
Y441690D01*
G01X217112Y441247D02*
X216239Y442120D01*
G01X218172Y441690D02*
X216682Y443180D01*
G01X216239Y442120D02*
X209768D01*
G01X216682Y443180D02*
X210208D01*
G01X209768Y442120D02*
X208112Y443776D01*
G01X210208Y443180D02*
X209172Y444216D01*
G01X208112Y443776D02*
Y446960D01*
G01X209172Y444216D02*
Y446520D01*
G01X208112Y446960D02*
X210812Y449660D01*
G01X209172Y446520D02*
X211872Y449220D01*
G01X210812Y449660D02*
Y478157D01*
G01X211872Y449220D02*
Y500409D01*
G01X208414Y514400D02*
Y532411D01*
G01X209474Y520290D02*
Y521660D01*
G01X208414Y514400D02*
Y532411D01*
G01X209474Y525340D02*
Y526760D01*
G01X206912Y503362D02*
X212422Y508872D01*
G01X207972Y502922D02*
X208898Y503848D01*
G01X206912Y503362D02*
X212422Y508872D01*
G01X210483Y505433D02*
X211190Y506140D01*
G01X206912Y503362D02*
X212422Y508872D01*
G01X212775Y507725D02*
X213482Y508432D01*
G01X212422Y508872D02*
Y511780D01*
G01X213482Y508432D02*
Y512220D01*
G01X212422Y511780D02*
X211502Y512700D01*
G01X213482Y512220D02*
X210402Y515300D01*
G01X214698Y519900D02*
X214027Y520571D01*
G01X213797Y519300D02*
X212967Y520130D01*
G01X214027Y520571D02*
Y521848D01*
G01Y525338D02*
Y526229D01*
G01X212967Y520130D02*
Y526670D01*
G01X214027Y526229D02*
X214798Y527000D01*
G01X210812Y480053D02*
Y481212D01*
G01Y483452D02*
Y484452D01*
G01Y486692D02*
Y487692D01*
G01Y489932D02*
Y490932D01*
G01Y493172D02*
Y494172D01*
G01Y496412D02*
Y497412D01*
G01Y499652D02*
Y500852D01*
G01X211872Y500409D02*
X218582Y507119D01*
G01X210812Y500852D02*
X212569Y502609D01*
G01X211872Y500409D02*
X218582Y507119D01*
G01X213276Y504194D02*
X214154D01*
G01X211872Y500409D02*
X218582Y507119D01*
G01X214154Y504194D02*
X214890Y504930D01*
G01X211872Y500409D02*
X218582Y507119D01*
G01X215597Y506515D02*
X216475D01*
G01X211872Y500409D02*
X218582Y507119D01*
G01X216475Y506515D02*
X217522Y507562D01*
G01X218582Y507119D02*
Y512434D01*
G01X217522Y507562D02*
Y511994D01*
G01X218582Y512434D02*
X215502Y515514D01*
G01X217522Y511994D02*
X216602Y512914D01*
G01X209474Y520290D02*
Y521660D01*
G01Y525340D02*
Y526760D01*
G01X208414Y514400D02*
Y532411D01*
G01X207972Y502922D02*
X208898Y503848D01*
G01X210483Y505433D02*
X211190Y506140D01*
G01X212775Y507725D02*
X213482Y508432D01*
G01X206912Y503362D02*
X212422Y508872D01*
G01X213482Y508432D02*
Y512220D01*
G01X212422Y508872D02*
Y511780D01*
G01X213482Y512220D02*
X210402Y515300D01*
G01X212422Y511780D02*
X211502Y512700D01*
G01X213797Y519300D02*
X212967Y520130D01*
G01X214698Y519900D02*
X214027Y520571D01*
G01X212967Y520130D02*
Y526670D01*
G01X214027Y520571D02*
Y521848D01*
G01X212967Y520130D02*
Y526670D01*
G01X214027Y525338D02*
Y526229D01*
G01D02*
X214798Y527000D01*
G01X210812Y480053D02*
Y481212D01*
G01Y483452D02*
Y484452D01*
G01Y486692D02*
Y487692D01*
G01Y489932D02*
Y490932D01*
G01Y493172D02*
Y494172D01*
G01Y496412D02*
Y497412D01*
G01Y499652D02*
Y500852D01*
G01D02*
X212569Y502609D01*
G01X213276Y504194D02*
X214154D01*
G01D02*
X214890Y504930D01*
G01X215597Y506515D02*
X216475D01*
G01D02*
X217522Y507562D01*
G01X211872Y500409D02*
X218582Y507119D01*
G01X217522Y507562D02*
Y511994D01*
G01X218582Y507119D02*
Y512434D01*
G01X217522Y511994D02*
X216602Y512914D01*
G01X218582Y512434D02*
X215502Y515514D01*
G01X171603Y532411D02*
Y514400D01*
G01X172663Y526760D02*
Y525340D01*
G01X171603Y532411D02*
Y514400D01*
G01X172663Y521660D02*
Y520290D01*
G01X208414Y514400D02*
Y532411D01*
G01X209474Y520290D02*
Y521660D01*
G01X208414Y514400D02*
Y532411D01*
G01X209474Y525340D02*
Y526760D01*
G01X206912Y503362D02*
X212422Y508872D01*
G01X207972Y502922D02*
X208898Y503848D01*
G01X206912Y503362D02*
X212422Y508872D01*
G01X210483Y505433D02*
X211190Y506140D01*
G01X206912Y503362D02*
X212422Y508872D01*
G01X212775Y507725D02*
X213482Y508432D01*
G01X212422Y508872D02*
Y511780D01*
G01X213482Y508432D02*
Y512220D01*
G01X212422Y511780D02*
X211502Y512700D01*
G01X213482Y512220D02*
X210402Y515300D01*
G01X177987Y527000D02*
X177216Y526229D01*
G01D02*
Y525338D01*
G01Y521848D02*
Y520571D01*
G01X176156Y526670D02*
Y520130D01*
G01X177216Y520571D02*
X177887Y519900D01*
G01X176156Y520130D02*
X176986Y519300D01*
G01X214698Y519900D02*
X214027Y520571D01*
G01X213797Y519300D02*
X212967Y520130D01*
G01X214027Y520571D02*
Y521848D01*
G01Y525338D02*
Y526229D01*
G01X212967Y520130D02*
Y526670D01*
G01X214027Y526229D02*
X214798Y527000D01*
G01X210812Y480053D02*
Y481212D01*
G01Y483452D02*
Y484452D01*
G01Y486692D02*
Y487692D01*
G01Y489932D02*
Y490932D01*
G01Y493172D02*
Y494172D01*
G01Y496412D02*
Y497412D01*
G01Y499652D02*
Y500852D01*
G01X211872Y500409D02*
X218582Y507119D01*
G01X210812Y500852D02*
X212569Y502609D01*
G01X211872Y500409D02*
X218582Y507119D01*
G01X213276Y504194D02*
X214154D01*
G01X211872Y500409D02*
X218582Y507119D01*
G01X214154Y504194D02*
X214890Y504930D01*
G01X211872Y500409D02*
X218582Y507119D01*
G01X215597Y506515D02*
X216475D01*
G01X211872Y500409D02*
X218582Y507119D01*
G01X216475Y506515D02*
X217522Y507562D01*
G01X218582Y507119D02*
Y512434D01*
G01X217522Y507562D02*
Y511994D01*
G01X218582Y512434D02*
X215502Y515514D01*
G01X217522Y511994D02*
X216602Y512914D01*
G01X172663Y526760D02*
Y525340D01*
G01Y521660D02*
Y520290D01*
G01X171603Y532411D02*
Y514400D01*
G01X209474Y520290D02*
Y521660D01*
G01Y525340D02*
Y526760D01*
G01X208414Y514400D02*
Y532411D01*
G01X207972Y502922D02*
X208898Y503848D01*
G01X210483Y505433D02*
X211190Y506140D01*
G01X212775Y507725D02*
X213482Y508432D01*
G01X206912Y503362D02*
X212422Y508872D01*
G01X213482Y508432D02*
Y512220D01*
G01X212422Y508872D02*
Y511780D01*
G01X213482Y512220D02*
X210402Y515300D01*
G01X212422Y511780D02*
X211502Y512700D01*
G01X177987Y527000D02*
X177216Y526229D01*
G01X176156Y526670D02*
Y520130D01*
G01X177216Y526229D02*
Y525338D01*
G01X176156Y526670D02*
Y520130D01*
G01X177216Y521848D02*
Y520571D01*
G01X176156Y520130D02*
X176986Y519300D01*
G01X177216Y520571D02*
X177887Y519900D01*
G01X213797Y519300D02*
X212967Y520130D01*
G01X214698Y519900D02*
X214027Y520571D01*
G01X212967Y520130D02*
Y526670D01*
G01X214027Y520571D02*
Y521848D01*
G01X212967Y520130D02*
Y526670D01*
G01X214027Y525338D02*
Y526229D01*
G01D02*
X214798Y527000D01*
G01X210812Y480053D02*
Y481212D01*
G01Y483452D02*
Y484452D01*
G01Y486692D02*
Y487692D01*
G01Y489932D02*
Y490932D01*
G01Y493172D02*
Y494172D01*
G01Y496412D02*
Y497412D01*
G01Y499652D02*
Y500852D01*
G01D02*
X212569Y502609D01*
G01X213276Y504194D02*
X214154D01*
G01D02*
X214890Y504930D01*
G01X215597Y506515D02*
X216475D01*
G01D02*
X217522Y507562D01*
G01X211872Y500409D02*
X218582Y507119D01*
G01X217522Y507562D02*
Y511994D01*
G01X218582Y507119D02*
Y512434D01*
G01X217522Y511994D02*
X216602Y512914D01*
G01X218582Y512434D02*
X215502Y515514D01*
G01X212967Y526670D02*
X213797Y527500D01*
G01X212967Y526670D02*
X213797Y527500D01*
G01X176986D02*
X176156Y526670D01*
G01X212967D02*
X213797Y527500D01*
G01X176986D02*
X176156Y526670D01*
G01X212967D02*
X213797Y527500D01*
G01X248548Y70380D02*
X248032D01*
G01X248009Y69320D02*
X248991D01*
G01X249259Y71091D02*
X248548Y70380D01*
G01D02*
X248032D01*
G01X248991Y69320D02*
X250319Y70648D01*
G01X249259Y86353D02*
Y83820D01*
G01Y79680D02*
Y78720D01*
G01Y74380D02*
Y71091D01*
G01X250319Y70648D02*
Y86794D01*
G01X248312Y87300D02*
X249259Y86353D01*
G01X250319Y86794D02*
X247213Y89900D01*
G01X245359Y97331D02*
Y89154D01*
G01X248548Y70380D02*
X248032D01*
G01X248009Y69320D02*
X248991D01*
G01X249259Y71091D02*
X248548Y70380D01*
G01D02*
X248032D01*
G01X248991Y69320D02*
X250319Y70648D01*
G01X249259Y86353D02*
Y83820D01*
G01Y79680D02*
Y78720D01*
G01Y74380D02*
Y71091D01*
G01X250319Y70648D02*
Y86794D01*
G01X248312Y87300D02*
X249259Y86353D01*
G01X250319Y86794D02*
X247213Y89900D01*
G01X245359Y97331D02*
Y89154D01*
G01X285359Y70380D02*
X284843D01*
G01X284820Y69320D02*
X285802D01*
G01X286070Y71091D02*
X285359Y70380D01*
G01D02*
X284843D01*
G01X285802Y69320D02*
X287130Y70648D01*
G01X286070Y86353D02*
Y83820D01*
G01Y79680D02*
Y78720D01*
G01Y74380D02*
Y71091D01*
G01X287130Y70648D02*
Y86794D01*
G01X284024Y87300D02*
X285123D01*
G01D02*
X286070Y86353D01*
G01X287130Y86794D02*
X284024Y89900D01*
G01X282170Y98031D02*
Y89154D01*
G01X285359Y70380D02*
X284843D01*
G01X284820Y69320D02*
X285802D01*
G01X286070Y71091D02*
X285359Y70380D01*
G01D02*
X284843D01*
G01X285802Y69320D02*
X287130Y70648D01*
G01X286070Y86353D02*
Y83820D01*
G01Y79680D02*
Y78720D01*
G01Y74380D02*
Y71091D01*
G01X287130Y70648D02*
Y86794D01*
G01X284024Y87300D02*
X285123D01*
G01D02*
X286070Y86353D01*
G01X287130Y86794D02*
X284024Y89900D01*
G01X282170Y98031D02*
Y89154D01*
G01X255505Y86922D02*
X252313Y90114D01*
G01Y87515D02*
X253411D01*
G01X255505Y86922D02*
X252313Y90114D01*
G01X253411Y87515D02*
X254445Y86481D01*
G01X255505Y71532D02*
Y86922D01*
G01X254445Y86481D02*
Y83706D01*
G01X255505Y71532D02*
Y86922D01*
G01X254445Y79880D02*
Y78507D01*
G01X255505Y71532D02*
Y86922D01*
G01X254445Y74593D02*
Y71972D01*
G01X252313Y68340D02*
X255505Y71532D01*
G01X254445Y71972D02*
X253422Y70949D01*
G01X255505Y86922D02*
X252313Y90114D01*
G01Y87515D02*
X253411D01*
G01X255505Y86922D02*
X252313Y90114D01*
G01X253411Y87515D02*
X254445Y86481D01*
G01X255505Y71532D02*
Y86922D01*
G01X254445Y86481D02*
Y83706D01*
G01X255505Y71532D02*
Y86922D01*
G01X254445Y79880D02*
Y78507D01*
G01X255505Y71532D02*
Y86922D01*
G01X254445Y74593D02*
Y71972D01*
G01X252313Y68340D02*
X255505Y71532D01*
G01X254445Y71972D02*
X253422Y70949D01*
G01X287370Y97308D02*
Y89268D01*
G01X292316Y86922D02*
X289124Y90114D01*
G01Y87515D02*
X290222D01*
G01X292316Y86922D02*
X289124Y90114D01*
G01X290222Y87515D02*
X291256Y86481D01*
G01X292316Y71532D02*
Y86922D01*
G01X291256Y86481D02*
Y83706D01*
G01X292316Y71532D02*
Y86922D01*
G01X291256Y79880D02*
Y78507D01*
G01X292316Y71532D02*
Y86922D01*
G01X291256Y74593D02*
Y71972D01*
G01X289124Y68340D02*
X292316Y71532D01*
G01X291256Y71972D02*
X290233Y70949D01*
G01X287370Y97308D02*
Y89268D01*
G01X292316Y86922D02*
X289124Y90114D01*
G01Y87515D02*
X290222D01*
G01X292316Y86922D02*
X289124Y90114D01*
G01X290222Y87515D02*
X291256Y86481D01*
G01X292316Y71532D02*
Y86922D01*
G01X291256Y86481D02*
Y83706D01*
G01X292316Y71532D02*
Y86922D01*
G01X291256Y79880D02*
Y78507D01*
G01X292316Y71532D02*
Y86922D01*
G01X291256Y74593D02*
Y71972D01*
G01X289124Y68340D02*
X292316Y71532D01*
G01X291256Y71972D02*
X290233Y70949D01*
G01X245359Y97331D02*
Y89154D01*
G01X250319Y86794D02*
X247213Y89900D01*
G01X248312Y87300D02*
X249259Y86353D01*
G01X250319Y70648D02*
Y86794D01*
G01X249259Y86353D02*
Y83820D01*
G01X250319Y70648D02*
Y86794D01*
G01X249259Y79680D02*
Y78720D01*
G01X250319Y70648D02*
Y86794D01*
G01X249259Y74380D02*
Y71091D01*
G01X248991Y69320D02*
X250319Y70648D01*
G01X249259Y71091D02*
X248548Y70380D01*
G01X248009Y69320D02*
X248991D01*
G01D02*
X250319Y70648D01*
G01X248548Y70380D02*
X248032D01*
G01X245359Y97331D02*
Y89154D01*
G01X250319Y86794D02*
X247213Y89900D01*
G01X248312Y87300D02*
X249259Y86353D01*
G01X250319Y70648D02*
Y86794D01*
G01X249259Y86353D02*
Y83820D01*
G01X250319Y70648D02*
Y86794D01*
G01X249259Y79680D02*
Y78720D01*
G01X250319Y70648D02*
Y86794D01*
G01X249259Y74380D02*
Y71091D01*
G01X248991Y69320D02*
X250319Y70648D01*
G01X249259Y71091D02*
X248548Y70380D01*
G01X248009Y69320D02*
X248991D01*
G01D02*
X250319Y70648D01*
G01X248548Y70380D02*
X248032D01*
G01X282170Y98031D02*
Y89154D01*
G01X287130Y86794D02*
X284024Y89900D01*
G01Y87300D02*
X285123D01*
G01X287130Y86794D02*
X284024Y89900D01*
G01X285123Y87300D02*
X286070Y86353D01*
G01X287130Y70648D02*
Y86794D01*
G01X286070Y86353D02*
Y83820D01*
G01X287130Y70648D02*
Y86794D01*
G01X286070Y79680D02*
Y78720D01*
G01X287130Y70648D02*
Y86794D01*
G01X286070Y74380D02*
Y71091D01*
G01X285802Y69320D02*
X287130Y70648D01*
G01X286070Y71091D02*
X285359Y70380D01*
G01X284820Y69320D02*
X285802D01*
G01D02*
X287130Y70648D01*
G01X285359Y70380D02*
X284843D01*
G01X282170Y98031D02*
Y89154D01*
G01X287130Y86794D02*
X284024Y89900D01*
G01Y87300D02*
X285123D01*
G01X287130Y86794D02*
X284024Y89900D01*
G01X285123Y87300D02*
X286070Y86353D01*
G01X287130Y70648D02*
Y86794D01*
G01X286070Y86353D02*
Y83820D01*
G01X287130Y70648D02*
Y86794D01*
G01X286070Y79680D02*
Y78720D01*
G01X287130Y70648D02*
Y86794D01*
G01X286070Y74380D02*
Y71091D01*
G01X285802Y69320D02*
X287130Y70648D01*
G01X286070Y71091D02*
X285359Y70380D01*
G01X284820Y69320D02*
X285802D01*
G01D02*
X287130Y70648D01*
G01X285359Y70380D02*
X284843D01*
G01X254445Y71972D02*
X253422Y70949D01*
G01X252313Y68340D02*
X255505Y71532D01*
G01X254445Y86481D02*
Y83706D01*
G01Y79880D02*
Y78507D01*
G01Y74593D02*
Y71972D01*
G01X255505Y71532D02*
Y86922D01*
G01X252313Y87515D02*
X253411D01*
G01D02*
X254445Y86481D01*
G01X255505Y86922D02*
X252313Y90114D01*
G01X254445Y71972D02*
X253422Y70949D01*
G01X252313Y68340D02*
X255505Y71532D01*
G01X254445Y86481D02*
Y83706D01*
G01Y79880D02*
Y78507D01*
G01Y74593D02*
Y71972D01*
G01X255505Y71532D02*
Y86922D01*
G01X252313Y87515D02*
X253411D01*
G01D02*
X254445Y86481D01*
G01X255505Y86922D02*
X252313Y90114D01*
G01X291256Y71972D02*
X290233Y70949D01*
G01X289124Y68340D02*
X292316Y71532D01*
G01X291256Y86481D02*
Y83706D01*
G01Y79880D02*
Y78507D01*
G01Y74593D02*
Y71972D01*
G01X292316Y71532D02*
Y86922D01*
G01X289124Y87515D02*
X290222D01*
G01D02*
X291256Y86481D01*
G01X292316Y86922D02*
X289124Y90114D01*
G01X287370Y97308D02*
Y89268D01*
G01X291256Y71972D02*
X290233Y70949D01*
G01X289124Y68340D02*
X292316Y71532D01*
G01X291256Y86481D02*
Y83706D01*
G01Y79880D02*
Y78507D01*
G01Y74593D02*
Y71972D01*
G01X292316Y71532D02*
Y86922D01*
G01X289124Y87515D02*
X290222D01*
G01D02*
X291256Y86481D01*
G01X292316Y86922D02*
X289124Y90114D01*
G01X287370Y97308D02*
Y89268D01*
G01X246419Y95220D02*
Y96888D01*
G01X249186Y101158D02*
X245359Y97331D01*
G01X246419Y96888D02*
X250246Y100715D01*
G01X249186Y133065D02*
Y101158D01*
G01X250246Y100715D02*
Y115630D01*
G01X249186Y133065D02*
Y101158D01*
G01X250246Y118420D02*
Y119180D01*
G01X249186Y133065D02*
Y101158D01*
G01X250246Y121420D02*
Y122180D01*
G01X249186Y133065D02*
Y101158D01*
G01X250246Y124420D02*
Y125180D01*
G01X249186Y133065D02*
Y101158D01*
G01X250246Y127420D02*
Y132622D01*
G01X249504Y133383D02*
X249186Y133065D01*
G01X250246Y132622D02*
X250564Y132940D01*
G01X249504Y143876D02*
Y133383D01*
G01X250564Y132940D02*
Y144319D01*
G01X248732Y144648D02*
X249504Y143876D01*
G01X250564Y144319D02*
X249175Y145708D01*
G01X247793Y144648D02*
X248732D01*
G01X249175Y145708D02*
X248236D01*
G01X246304Y146137D02*
X247793Y144648D01*
G01X248236Y145708D02*
X247364Y146580D01*
G01X246304Y149519D02*
Y146137D01*
G01X247364Y146580D02*
Y149076D01*
G01X247793Y151008D02*
X246304Y149519D01*
G01X247364Y149076D02*
X248236Y149948D01*
G01X249632Y151008D02*
X247793D01*
G01X248236Y149948D02*
X250075D01*
G01X250504Y151880D02*
X249632Y151008D01*
G01X250075Y149948D02*
X251564Y151437D01*
G01X250504Y154376D02*
Y151880D01*
G01X251564Y151437D02*
Y154819D01*
G01X249632Y155248D02*
X250504Y154376D01*
G01X251564Y154819D02*
X250075Y156308D01*
G01X247793Y155248D02*
X249632D01*
G01X246304Y156737D02*
X247793Y155248D01*
G01X248236Y156308D02*
X247364Y157180D01*
G01X246419Y95220D02*
Y96888D01*
G01X249186Y101158D02*
X245359Y97331D01*
G01X246419Y96888D02*
X250246Y100715D01*
G01X249186Y133065D02*
Y101158D01*
G01X250246Y100715D02*
Y115630D01*
G01X249186Y133065D02*
Y101158D01*
G01X250246Y118420D02*
Y119180D01*
G01X249186Y133065D02*
Y101158D01*
G01X250246Y121420D02*
Y122180D01*
G01X249186Y133065D02*
Y101158D01*
G01X250246Y124420D02*
Y125180D01*
G01X249186Y133065D02*
Y101158D01*
G01X250246Y127420D02*
Y132622D01*
G01X249504Y133383D02*
X249186Y133065D01*
G01X250246Y132622D02*
X250564Y132940D01*
G01X249504Y143876D02*
Y133383D01*
G01X250564Y132940D02*
Y144319D01*
G01X248732Y144648D02*
X249504Y143876D01*
G01X250564Y144319D02*
X249175Y145708D01*
G01X247793Y144648D02*
X248732D01*
G01X249175Y145708D02*
X248236D01*
G01X246304Y146137D02*
X247793Y144648D01*
G01X248236Y145708D02*
X247364Y146580D01*
G01X246304Y149519D02*
Y146137D01*
G01X247364Y146580D02*
Y149076D01*
G01X247793Y151008D02*
X246304Y149519D01*
G01X247364Y149076D02*
X248236Y149948D01*
G01X249632Y151008D02*
X247793D01*
G01X248236Y149948D02*
X250075D01*
G01X250504Y151880D02*
X249632Y151008D01*
G01X250075Y149948D02*
X251564Y151437D01*
G01X250504Y154376D02*
Y151880D01*
G01X251564Y151437D02*
Y154819D01*
G01X249632Y155248D02*
X250504Y154376D01*
G01X251564Y154819D02*
X250075Y156308D01*
G01X247793Y155248D02*
X249632D01*
G01X246304Y156737D02*
X247793Y155248D01*
G01X248236Y156308D02*
X247364Y157180D01*
G01X283230Y95000D02*
Y97588D01*
G01X285986Y101847D02*
X282170Y98031D01*
G01X283230Y97588D02*
X287046Y101404D01*
G01X285986Y113926D02*
Y101847D01*
G01X287046Y101404D02*
Y102236D01*
G01X285986Y113926D02*
Y101847D01*
G01X287046Y104476D02*
Y113483D01*
G01X286904Y114844D02*
X285986Y113926D01*
G01X287046Y113483D02*
X287964Y114401D01*
G01X286904Y133307D02*
Y114844D01*
G01X287964Y114401D02*
Y115401D01*
G01X286904Y133307D02*
Y114844D01*
G01X287964Y117401D02*
Y118401D01*
G01X286904Y133307D02*
Y114844D01*
G01X287964Y120401D02*
Y121401D01*
G01X286904Y133307D02*
Y114844D01*
G01X287964Y123401D02*
Y128404D01*
G01X286904Y133307D02*
Y114844D01*
G01X287964Y131034D02*
Y132864D01*
G01X288433Y134836D02*
X286904Y133307D01*
G01X287964Y132864D02*
X288876Y133776D01*
G01X290293Y134836D02*
X288433D01*
G01X288876Y133776D02*
X290736D01*
G01X291104Y135647D02*
X290293Y134836D01*
G01X290736Y133776D02*
X292164Y135204D01*
G01X291104Y137986D02*
Y135647D01*
G01X292164Y135204D02*
Y138429D01*
G01X290232Y138858D02*
X291104Y137986D01*
G01X292164Y138429D02*
X290675Y139918D01*
G01X288396Y138858D02*
X290232D01*
G01X290675Y139918D02*
X288836D01*
G01X286632Y140622D02*
X288396Y138858D01*
G01X288836Y139918D02*
X287692Y141062D01*
G01X286632Y143454D02*
Y140622D01*
G01X287692Y141062D02*
Y143014D01*
G01X288396Y145218D02*
X286632Y143454D01*
G01X287692Y143014D02*
X288836Y144158D01*
G01X290235Y145218D02*
X288396D01*
G01X288836Y144158D02*
X290675D01*
G01X291104Y146087D02*
X290235Y145218D01*
G01X290675Y144158D02*
X292164Y145647D01*
G01X291104Y148586D02*
Y146087D01*
G01X292164Y145647D02*
Y149029D01*
G01X290232Y149458D02*
X291104Y148586D01*
G01X292164Y149029D02*
X290675Y150518D01*
G01X289566Y149458D02*
X290232D01*
G01X290675Y150518D02*
X290006D01*
G01X288292Y150732D02*
X289566Y149458D01*
G01X290006Y150518D02*
X289352Y151172D01*
G01X288292Y159934D02*
Y150732D01*
G01X289352Y151172D02*
Y153834D01*
G01X288292Y159934D02*
Y150732D01*
G01X283230Y95000D02*
Y97588D01*
G01X285986Y101847D02*
X282170Y98031D01*
G01X283230Y97588D02*
X287046Y101404D01*
G01X285986Y113926D02*
Y101847D01*
G01X287046Y101404D02*
Y102236D01*
G01X285986Y113926D02*
Y101847D01*
G01X287046Y104476D02*
Y113483D01*
G01X286904Y114844D02*
X285986Y113926D01*
G01X287046Y113483D02*
X287964Y114401D01*
G01X286904Y133307D02*
Y114844D01*
G01X287964Y114401D02*
Y115401D01*
G01X286904Y133307D02*
Y114844D01*
G01X287964Y117401D02*
Y118401D01*
G01X286904Y133307D02*
Y114844D01*
G01X287964Y120401D02*
Y121401D01*
G01X286904Y133307D02*
Y114844D01*
G01X287964Y123401D02*
Y128404D01*
G01X286904Y133307D02*
Y114844D01*
G01X287964Y131034D02*
Y132864D01*
G01X288433Y134836D02*
X286904Y133307D01*
G01X287964Y132864D02*
X288876Y133776D01*
G01X290293Y134836D02*
X288433D01*
G01X288876Y133776D02*
X290736D01*
G01X291104Y135647D02*
X290293Y134836D01*
G01X290736Y133776D02*
X292164Y135204D01*
G01X291104Y137986D02*
Y135647D01*
G01X292164Y135204D02*
Y138429D01*
G01X290232Y138858D02*
X291104Y137986D01*
G01X292164Y138429D02*
X290675Y139918D01*
G01X288396Y138858D02*
X290232D01*
G01X290675Y139918D02*
X288836D01*
G01X286632Y140622D02*
X288396Y138858D01*
G01X288836Y139918D02*
X287692Y141062D01*
G01X286632Y143454D02*
Y140622D01*
G01X287692Y141062D02*
Y143014D01*
G01X288396Y145218D02*
X286632Y143454D01*
G01X287692Y143014D02*
X288836Y144158D01*
G01X290235Y145218D02*
X288396D01*
G01X288836Y144158D02*
X290675D01*
G01X291104Y146087D02*
X290235Y145218D01*
G01X290675Y144158D02*
X292164Y145647D01*
G01X291104Y148586D02*
Y146087D01*
G01X292164Y145647D02*
Y149029D01*
G01X290232Y149458D02*
X291104Y148586D01*
G01X292164Y149029D02*
X290675Y150518D01*
G01X289566Y149458D02*
X290232D01*
G01X290675Y150518D02*
X290006D01*
G01X288292Y150732D02*
X289566Y149458D01*
G01X290006Y150518D02*
X289352Y151172D01*
G01X288292Y159934D02*
Y150732D01*
G01X289352Y151172D02*
Y153834D01*
G01X288292Y159934D02*
Y150732D01*
G01X255446Y99715D02*
Y113280D01*
G01Y115520D02*
Y116280D01*
G01Y118520D02*
Y119280D01*
G01Y121520D02*
Y122280D01*
G01Y124520D02*
Y125280D01*
G01Y127520D02*
Y161428D01*
G01X254386Y161868D02*
Y100158D01*
G01X252119Y96388D02*
X253093Y97362D01*
G01X254677Y98946D02*
X255446Y99715D01*
G01X254386Y100158D02*
X251059Y96831D01*
G01X252119Y95520D02*
Y96388D01*
G01X251059Y96831D02*
Y94567D01*
G01X255446Y99715D02*
Y113280D01*
G01Y115520D02*
Y116280D01*
G01Y118520D02*
Y119280D01*
G01Y121520D02*
Y122280D01*
G01Y124520D02*
Y125280D01*
G01Y127520D02*
Y161428D01*
G01X254386Y161868D02*
Y100158D01*
G01X252119Y96388D02*
X253093Y97362D01*
G01X254677Y98946D02*
X255446Y99715D01*
G01X254386Y100158D02*
X251059Y96831D01*
G01X252119Y95520D02*
Y96388D01*
G01X251059Y96831D02*
Y94567D01*
G01X292564Y130065D02*
X295964Y133465D01*
G01X294904Y133908D02*
X291504Y130508D01*
G01X292564Y113304D02*
Y130065D01*
G01X291504Y130508D02*
Y113747D01*
G01X292204Y112944D02*
X292564Y113304D01*
G01X291504Y113747D02*
X291144Y113387D01*
G01X292204Y100642D02*
Y103480D01*
G01Y105720D02*
Y112944D01*
G01X291144Y113387D02*
Y101085D01*
G01X289185Y97623D02*
X290061D01*
G01X290769Y99207D02*
X292204Y100642D01*
G01X291144Y101085D02*
X288435Y98376D01*
G01X288430Y96868D02*
X289185Y97623D01*
G01D02*
X290061D01*
G01X288435Y98373D02*
X287370Y97308D01*
G01X288430Y95362D02*
Y96868D01*
G01X292564Y130065D02*
X295964Y133465D01*
G01X294904Y133908D02*
X291504Y130508D01*
G01X292564Y113304D02*
Y130065D01*
G01X291504Y130508D02*
Y113747D01*
G01X292204Y112944D02*
X292564Y113304D01*
G01X291504Y113747D02*
X291144Y113387D01*
G01X292204Y100642D02*
Y103480D01*
G01Y105720D02*
Y112944D01*
G01X291144Y113387D02*
Y101085D01*
G01X289185Y97623D02*
X290061D01*
G01X290769Y99207D02*
X292204Y100642D01*
G01X291144Y101085D02*
X288435Y98376D01*
G01X288430Y96868D02*
X289185Y97623D01*
G01D02*
X290061D01*
G01X288435Y98373D02*
X287370Y97308D01*
G01X288430Y95362D02*
Y96868D01*
G01X248236Y156308D02*
X247364Y157180D01*
G01X246304Y156737D02*
X247793Y155248D01*
G01D02*
X249632D01*
G01X251564Y154819D02*
X250075Y156308D01*
G01X249632Y155248D02*
X250504Y154376D01*
G01X251564Y151437D02*
Y154819D01*
G01X250504Y154376D02*
Y151880D01*
G01X250075Y149948D02*
X251564Y151437D01*
G01X250504Y151880D02*
X249632Y151008D01*
G01X248236Y149948D02*
X250075D01*
G01X249632Y151008D02*
X247793D01*
G01X247364Y149076D02*
X248236Y149948D01*
G01X247793Y151008D02*
X246304Y149519D01*
G01X247364Y146580D02*
Y149076D01*
G01X246304Y149519D02*
Y146137D01*
G01X248236Y145708D02*
X247364Y146580D01*
G01X246304Y146137D02*
X247793Y144648D01*
G01X249175Y145708D02*
X248236D01*
G01X247793Y144648D02*
X248732D01*
G01X250564Y144319D02*
X249175Y145708D01*
G01X248732Y144648D02*
X249504Y143876D01*
G01X250564Y132940D02*
Y144319D01*
G01X249504Y143876D02*
Y133383D01*
G01X250246Y132622D02*
X250564Y132940D01*
G01X249504Y133383D02*
X249186Y133065D01*
G01X250246Y100715D02*
Y115630D01*
G01Y118420D02*
Y119180D01*
G01Y121420D02*
Y122180D01*
G01Y124420D02*
Y125180D01*
G01Y127420D02*
Y132622D01*
G01X249186Y133065D02*
Y101158D01*
G01X246419Y96888D02*
X250246Y100715D01*
G01X249186Y101158D02*
X245359Y97331D01*
G01X246419Y95220D02*
Y96888D01*
G01X248236Y156308D02*
X247364Y157180D01*
G01X246304Y156737D02*
X247793Y155248D01*
G01D02*
X249632D01*
G01X251564Y154819D02*
X250075Y156308D01*
G01X249632Y155248D02*
X250504Y154376D01*
G01X251564Y151437D02*
Y154819D01*
G01X250504Y154376D02*
Y151880D01*
G01X250075Y149948D02*
X251564Y151437D01*
G01X250504Y151880D02*
X249632Y151008D01*
G01X248236Y149948D02*
X250075D01*
G01X249632Y151008D02*
X247793D01*
G01X247364Y149076D02*
X248236Y149948D01*
G01X247793Y151008D02*
X246304Y149519D01*
G01X247364Y146580D02*
Y149076D01*
G01X246304Y149519D02*
Y146137D01*
G01X248236Y145708D02*
X247364Y146580D01*
G01X246304Y146137D02*
X247793Y144648D01*
G01X249175Y145708D02*
X248236D01*
G01X247793Y144648D02*
X248732D01*
G01X250564Y144319D02*
X249175Y145708D01*
G01X248732Y144648D02*
X249504Y143876D01*
G01X250564Y132940D02*
Y144319D01*
G01X249504Y143876D02*
Y133383D01*
G01X250246Y132622D02*
X250564Y132940D01*
G01X249504Y133383D02*
X249186Y133065D01*
G01X250246Y100715D02*
Y115630D01*
G01Y118420D02*
Y119180D01*
G01Y121420D02*
Y122180D01*
G01Y124420D02*
Y125180D01*
G01Y127420D02*
Y132622D01*
G01X249186Y133065D02*
Y101158D01*
G01X246419Y96888D02*
X250246Y100715D01*
G01X249186Y101158D02*
X245359Y97331D01*
G01X246419Y95220D02*
Y96888D01*
G01X289352Y151172D02*
Y153834D01*
G01X288292Y159934D02*
Y150732D01*
G01X290006Y150518D02*
X289352Y151172D01*
G01X288292Y150732D02*
X289566Y149458D01*
G01X290675Y150518D02*
X290006D01*
G01X289566Y149458D02*
X290232D01*
G01X292164Y149029D02*
X290675Y150518D01*
G01X290232Y149458D02*
X291104Y148586D01*
G01X292164Y145647D02*
Y149029D01*
G01X291104Y148586D02*
Y146087D01*
G01X290675Y144158D02*
X292164Y145647D01*
G01X291104Y146087D02*
X290235Y145218D01*
G01X288836Y144158D02*
X290675D01*
G01X290235Y145218D02*
X288396D01*
G01X287692Y143014D02*
X288836Y144158D01*
G01X288396Y145218D02*
X286632Y143454D01*
G01X287692Y141062D02*
Y143014D01*
G01X286632Y143454D02*
Y140622D01*
G01X288836Y139918D02*
X287692Y141062D01*
G01X286632Y140622D02*
X288396Y138858D01*
G01X290675Y139918D02*
X288836D01*
G01X288396Y138858D02*
X290232D01*
G01X292164Y138429D02*
X290675Y139918D01*
G01X290232Y138858D02*
X291104Y137986D01*
G01X292164Y135204D02*
Y138429D01*
G01X291104Y137986D02*
Y135647D01*
G01X290736Y133776D02*
X292164Y135204D01*
G01X291104Y135647D02*
X290293Y134836D01*
G01X288876Y133776D02*
X290736D01*
G01X290293Y134836D02*
X288433D01*
G01X287964Y132864D02*
X288876Y133776D01*
G01X288433Y134836D02*
X286904Y133307D01*
G01X287964Y114401D02*
Y115401D01*
G01Y117401D02*
Y118401D01*
G01Y120401D02*
Y121401D01*
G01Y123401D02*
Y128404D01*
G01Y131034D02*
Y132864D01*
G01X286904Y133307D02*
Y114844D01*
G01X287046Y113483D02*
X287964Y114401D01*
G01X286904Y114844D02*
X285986Y113926D01*
G01X287046Y101404D02*
Y102236D01*
G01Y104476D02*
Y113483D01*
G01X285986Y113926D02*
Y101847D01*
G01X283230Y97588D02*
X287046Y101404D01*
G01X285986Y101847D02*
X282170Y98031D01*
G01X283230Y95000D02*
Y97588D01*
G01X289352Y151172D02*
Y153834D01*
G01X288292Y159934D02*
Y150732D01*
G01X290006Y150518D02*
X289352Y151172D01*
G01X288292Y150732D02*
X289566Y149458D01*
G01X290675Y150518D02*
X290006D01*
G01X289566Y149458D02*
X290232D01*
G01X292164Y149029D02*
X290675Y150518D01*
G01X290232Y149458D02*
X291104Y148586D01*
G01X292164Y145647D02*
Y149029D01*
G01X291104Y148586D02*
Y146087D01*
G01X290675Y144158D02*
X292164Y145647D01*
G01X291104Y146087D02*
X290235Y145218D01*
G01X288836Y144158D02*
X290675D01*
G01X290235Y145218D02*
X288396D01*
G01X287692Y143014D02*
X288836Y144158D01*
G01X288396Y145218D02*
X286632Y143454D01*
G01X287692Y141062D02*
Y143014D01*
G01X286632Y143454D02*
Y140622D01*
G01X288836Y139918D02*
X287692Y141062D01*
G01X286632Y140622D02*
X288396Y138858D01*
G01X290675Y139918D02*
X288836D01*
G01X288396Y138858D02*
X290232D01*
G01X292164Y138429D02*
X290675Y139918D01*
G01X290232Y138858D02*
X291104Y137986D01*
G01X292164Y135204D02*
Y138429D01*
G01X291104Y137986D02*
Y135647D01*
G01X290736Y133776D02*
X292164Y135204D01*
G01X291104Y135647D02*
X290293Y134836D01*
G01X288876Y133776D02*
X290736D01*
G01X290293Y134836D02*
X288433D01*
G01X287964Y132864D02*
X288876Y133776D01*
G01X288433Y134836D02*
X286904Y133307D01*
G01X287964Y114401D02*
Y115401D01*
G01Y117401D02*
Y118401D01*
G01Y120401D02*
Y121401D01*
G01Y123401D02*
Y128404D01*
G01Y131034D02*
Y132864D01*
G01X286904Y133307D02*
Y114844D01*
G01X287046Y113483D02*
X287964Y114401D01*
G01X286904Y114844D02*
X285986Y113926D01*
G01X287046Y101404D02*
Y102236D01*
G01Y104476D02*
Y113483D01*
G01X285986Y113926D02*
Y101847D01*
G01X283230Y97588D02*
X287046Y101404D01*
G01X285986Y101847D02*
X282170Y98031D01*
G01X283230Y95000D02*
Y97588D01*
G01X251059Y96831D02*
Y94567D01*
G01X252119Y95520D02*
Y96388D01*
G01X254386Y100158D02*
X251059Y96831D01*
G01X252119Y96388D02*
X253093Y97362D01*
G01X254386Y100158D02*
X251059Y96831D01*
G01X254677Y98946D02*
X255446Y99715D01*
G01X254386Y161868D02*
Y100158D01*
G01X255446Y99715D02*
Y113280D01*
G01X254386Y161868D02*
Y100158D01*
G01X255446Y115520D02*
Y116280D01*
G01X254386Y161868D02*
Y100158D01*
G01X255446Y118520D02*
Y119280D01*
G01X254386Y161868D02*
Y100158D01*
G01X255446Y121520D02*
Y122280D01*
G01X254386Y161868D02*
Y100158D01*
G01X255446Y124520D02*
Y125280D01*
G01X254386Y161868D02*
Y100158D01*
G01X255446Y127520D02*
Y161428D01*
G01X251059Y96831D02*
Y94567D01*
G01X252119Y95520D02*
Y96388D01*
G01X254386Y100158D02*
X251059Y96831D01*
G01X252119Y96388D02*
X253093Y97362D01*
G01X254386Y100158D02*
X251059Y96831D01*
G01X254677Y98946D02*
X255446Y99715D01*
G01X254386Y161868D02*
Y100158D01*
G01X255446Y99715D02*
Y113280D01*
G01X254386Y161868D02*
Y100158D01*
G01X255446Y115520D02*
Y116280D01*
G01X254386Y161868D02*
Y100158D01*
G01X255446Y118520D02*
Y119280D01*
G01X254386Y161868D02*
Y100158D01*
G01X255446Y121520D02*
Y122280D01*
G01X254386Y161868D02*
Y100158D01*
G01X255446Y124520D02*
Y125280D01*
G01X254386Y161868D02*
Y100158D01*
G01X255446Y127520D02*
Y161428D01*
G01X288430Y95362D02*
Y96868D01*
G01X288435Y98373D02*
X287370Y97308D01*
G01X288430Y96868D02*
X289185Y97623D01*
G01X291144Y101085D02*
X288435Y98376D01*
G01Y98373D02*
X287370Y97308D01*
G01X289185Y97623D02*
X290061D01*
G01X291144Y101085D02*
X288435Y98376D01*
G01X290769Y99207D02*
X292204Y100642D01*
G01X291144Y113387D02*
Y101085D01*
G01X292204Y100642D02*
Y103480D01*
G01X291144Y113387D02*
Y101085D01*
G01X292204Y105720D02*
Y112944D01*
G01X291504Y113747D02*
X291144Y113387D01*
G01X292204Y112944D02*
X292564Y113304D01*
G01X291504Y130508D02*
Y113747D01*
G01X292564Y113304D02*
Y130065D01*
G01X294904Y133908D02*
X291504Y130508D01*
G01X292564Y130065D02*
X295964Y133465D01*
G01X288430Y95362D02*
Y96868D01*
G01X288435Y98373D02*
X287370Y97308D01*
G01X288430Y96868D02*
X289185Y97623D01*
G01X291144Y101085D02*
X288435Y98376D01*
G01Y98373D02*
X287370Y97308D01*
G01X289185Y97623D02*
X290061D01*
G01X291144Y101085D02*
X288435Y98376D01*
G01X290769Y99207D02*
X292204Y100642D01*
G01X291144Y113387D02*
Y101085D01*
G01X292204Y100642D02*
Y103480D01*
G01X291144Y113387D02*
Y101085D01*
G01X292204Y105720D02*
Y112944D01*
G01X291504Y113747D02*
X291144Y113387D01*
G01X292204Y112944D02*
X292564Y113304D01*
G01X291504Y130508D02*
Y113747D01*
G01X292564Y113304D02*
Y130065D01*
G01X294904Y133908D02*
X291504Y130508D01*
G01X292564Y130065D02*
X295964Y133465D01*
G01X256388Y217045D02*
X255752Y216409D01*
G01X254408Y215065D02*
X253715Y214372D01*
G01X252370Y213027D02*
X251734Y212391D01*
G01X250390Y211047D02*
X249754Y210411D01*
G01X248410Y209067D02*
X247640Y208297D01*
G01X246295Y206952D02*
X245440Y206097D01*
G01X244095Y204752D02*
X243265Y203922D01*
G01X241920Y202577D02*
X240840Y201497D01*
G01X239495Y200152D02*
X238840Y199497D01*
G01X237495Y198152D02*
X236815Y197472D01*
G01X235470Y196127D02*
X234834Y195491D01*
G01X233490Y194147D02*
X232790Y193447D01*
G01X256388Y217045D02*
X255752Y216409D01*
G01X254408Y215065D02*
X253715Y214372D01*
G01X252370Y213027D02*
X251734Y212391D01*
G01X250390Y211047D02*
X249754Y210411D01*
G01X248410Y209067D02*
X247640Y208297D01*
G01X246295Y206952D02*
X245440Y206097D01*
G01X244095Y204752D02*
X243265Y203922D01*
G01X241920Y202577D02*
X240840Y201497D01*
G01X239495Y200152D02*
X238840Y199497D01*
G01X237495Y198152D02*
X236815Y197472D01*
G01X235470Y196127D02*
X234834Y195491D01*
G01X233490Y194147D02*
X232790Y193447D01*
G01X263462Y217336D02*
X265461D01*
G01X252191Y206065D02*
X252827Y206701D01*
G01X254171Y208045D02*
X254807Y208681D01*
G01X256151Y210025D02*
X256787Y210661D01*
G01X258131Y212005D02*
X259307Y213181D01*
G01X260651Y214525D02*
X261287Y215161D01*
G01X262631Y216505D02*
X263462Y217336D01*
G01D02*
X265461D01*
G01X252191Y206065D02*
X252827Y206701D01*
G01X254171Y208045D02*
X254807Y208681D01*
G01X256151Y210025D02*
X256787Y210661D01*
G01X258131Y212005D02*
X259307Y213181D01*
G01X260651Y214525D02*
X261287Y215161D01*
G01X262631Y216505D02*
X263462Y217336D01*
G01X256388Y217045D02*
X255752Y216409D01*
G01X254408Y215065D02*
X253715Y214372D01*
G01X252370Y213027D02*
X251734Y212391D01*
G01X250390Y211047D02*
X249754Y210411D01*
G01X248410Y209067D02*
X247640Y208297D01*
G01X246295Y206952D02*
X245440Y206097D01*
G01X244095Y204752D02*
X243265Y203922D01*
G01X241920Y202577D02*
X240840Y201497D01*
G01X239495Y200152D02*
X238840Y199497D01*
G01X237495Y198152D02*
X236815Y197472D01*
G01X235470Y196127D02*
X234834Y195491D01*
G01X233490Y194147D02*
X232790Y193447D01*
G01X256388Y217045D02*
X255752Y216409D01*
G01X254408Y215065D02*
X253715Y214372D01*
G01X252370Y213027D02*
X251734Y212391D01*
G01X250390Y211047D02*
X249754Y210411D01*
G01X248410Y209067D02*
X247640Y208297D01*
G01X246295Y206952D02*
X245440Y206097D01*
G01X244095Y204752D02*
X243265Y203922D01*
G01X241920Y202577D02*
X240840Y201497D01*
G01X239495Y200152D02*
X238840Y199497D01*
G01X237495Y198152D02*
X236815Y197472D01*
G01X235470Y196127D02*
X234834Y195491D01*
G01X233490Y194147D02*
X232790Y193447D01*
G01X252191Y206065D02*
X252827Y206701D01*
G01X254171Y208045D02*
X254807Y208681D01*
G01X256151Y210025D02*
X256787Y210661D01*
G01X258131Y212005D02*
X259307Y213181D01*
G01X260651Y214525D02*
X261287Y215161D01*
G01X262631Y216505D02*
X263462Y217336D01*
G01D02*
X265461D01*
G01X252191Y206065D02*
X252827Y206701D01*
G01X254171Y208045D02*
X254807Y208681D01*
G01X256151Y210025D02*
X256787Y210661D01*
G01X258131Y212005D02*
X259307Y213181D01*
G01X260651Y214525D02*
X261287Y215161D01*
G01X262631Y216505D02*
X263462Y217336D01*
G01D02*
X265461D01*
G01X250075Y156308D02*
X248236D01*
G01X246304Y160119D02*
Y156737D01*
G01X247364Y157180D02*
Y159676D01*
G01X247793Y161608D02*
X246304Y160119D01*
G01X247364Y159676D02*
X248236Y160548D01*
G01X249635Y161608D02*
X247793D01*
G01X248236Y160548D02*
X250075D01*
G01X250504Y162477D02*
X249635Y161608D01*
G01X250075Y160548D02*
X251564Y162037D01*
G01X250504Y165112D02*
Y162477D01*
G01X251564Y162037D02*
Y164672D01*
G01X279992Y194600D02*
X250504Y165112D01*
G01X251564Y164672D02*
X262270Y175378D01*
G01X279992Y194600D02*
X250504Y165112D01*
G01X263614Y176722D02*
X264370Y177478D01*
G01X279992Y194600D02*
X250504Y165112D01*
G01X265714Y178822D02*
X266390Y179498D01*
G01X279992Y194600D02*
X250504Y165112D01*
G01X267734Y180842D02*
X268370Y181478D01*
G01X279992Y194600D02*
X250504Y165112D01*
G01X269714Y182822D02*
X270385Y183493D01*
G01X279992Y194600D02*
X250504Y165112D01*
G01X271729Y184837D02*
X272365Y185473D01*
G01X279992Y194600D02*
X250504Y165112D01*
G01X273709Y186817D02*
X274345Y187453D01*
G01X279992Y194600D02*
X250504Y165112D01*
G01X275689Y188797D02*
X276445Y189553D01*
G01X279992Y194600D02*
X250504Y165112D01*
G01X277789Y190897D02*
X278868Y191976D01*
G01X279992Y194600D02*
X250504Y165112D01*
G01X280212Y193320D02*
X280848Y193956D01*
G01X250075Y156308D02*
X248236D01*
G01X246304Y160119D02*
Y156737D01*
G01X247364Y157180D02*
Y159676D01*
G01X247793Y161608D02*
X246304Y160119D01*
G01X247364Y159676D02*
X248236Y160548D01*
G01X249635Y161608D02*
X247793D01*
G01X248236Y160548D02*
X250075D01*
G01X250504Y162477D02*
X249635Y161608D01*
G01X250075Y160548D02*
X251564Y162037D01*
G01X250504Y165112D02*
Y162477D01*
G01X251564Y162037D02*
Y164672D01*
G01X279992Y194600D02*
X250504Y165112D01*
G01X251564Y164672D02*
X262270Y175378D01*
G01X279992Y194600D02*
X250504Y165112D01*
G01X263614Y176722D02*
X264370Y177478D01*
G01X279992Y194600D02*
X250504Y165112D01*
G01X265714Y178822D02*
X266390Y179498D01*
G01X279992Y194600D02*
X250504Y165112D01*
G01X267734Y180842D02*
X268370Y181478D01*
G01X279992Y194600D02*
X250504Y165112D01*
G01X269714Y182822D02*
X270385Y183493D01*
G01X279992Y194600D02*
X250504Y165112D01*
G01X271729Y184837D02*
X272365Y185473D01*
G01X279992Y194600D02*
X250504Y165112D01*
G01X273709Y186817D02*
X274345Y187453D01*
G01X279992Y194600D02*
X250504Y165112D01*
G01X275689Y188797D02*
X276445Y189553D01*
G01X279992Y194600D02*
X250504Y165112D01*
G01X277789Y190897D02*
X278868Y191976D01*
G01X279992Y194600D02*
X250504Y165112D01*
G01X280212Y193320D02*
X280848Y193956D01*
G01X289352Y156464D02*
Y159494D01*
G01X314532Y186174D02*
X288292Y159934D01*
G01X289352Y159494D02*
X293514Y163656D01*
G01X314532Y186174D02*
X288292Y159934D01*
G01X314532Y186174D02*
X288292Y159934D01*
G01X314532Y186174D02*
X288292Y159934D01*
G01X314532Y186174D02*
X288292Y159934D01*
G01X314532Y186174D02*
X288292Y159934D01*
G01X314532Y186174D02*
X288292Y159934D01*
G01X314532Y186174D02*
X288292Y159934D01*
G01X289352Y156464D02*
Y159494D01*
G01X314532Y186174D02*
X288292Y159934D01*
G01X289352Y159494D02*
X293514Y163656D01*
G01X314532Y186174D02*
X288292Y159934D01*
G01X314532Y186174D02*
X288292Y159934D01*
G01X314532Y186174D02*
X288292Y159934D01*
G01X314532Y186174D02*
X288292Y159934D01*
G01X314532Y186174D02*
X288292Y159934D01*
G01X314532Y186174D02*
X288292Y159934D01*
G01X314532Y186174D02*
X288292Y159934D01*
G01X286875Y192857D02*
Y194683D01*
G01X285815D02*
Y193297D01*
G01X255446Y161428D02*
X286875Y192857D01*
G01X285815Y193297D02*
X254386Y161868D01*
G01X286875Y192857D02*
Y194683D01*
G01X285815D02*
Y193297D01*
G01X255446Y161428D02*
X286875Y192857D01*
G01X285815Y193297D02*
X254386Y161868D01*
G01X251564Y164672D02*
X262270Y175378D01*
G01X263614Y176722D02*
X264370Y177478D01*
G01X265714Y178822D02*
X266390Y179498D01*
G01X267734Y180842D02*
X268370Y181478D01*
G01X269714Y182822D02*
X270385Y183493D01*
G01X271729Y184837D02*
X272365Y185473D01*
G01X273709Y186817D02*
X274345Y187453D01*
G01X275689Y188797D02*
X276445Y189553D01*
G01X277789Y190897D02*
X278868Y191976D01*
G01X280212Y193320D02*
X280848Y193956D01*
G01X279992Y194600D02*
X250504Y165112D01*
G01X251564Y162037D02*
Y164672D01*
G01X250504Y165112D02*
Y162477D01*
G01X250075Y160548D02*
X251564Y162037D01*
G01X250504Y162477D02*
X249635Y161608D01*
G01X248236Y160548D02*
X250075D01*
G01X249635Y161608D02*
X247793D01*
G01X247364Y159676D02*
X248236Y160548D01*
G01X247793Y161608D02*
X246304Y160119D01*
G01X247364Y157180D02*
Y159676D01*
G01X246304Y160119D02*
Y156737D01*
G01X250075Y156308D02*
X248236D01*
G01X251564Y164672D02*
X262270Y175378D01*
G01X263614Y176722D02*
X264370Y177478D01*
G01X265714Y178822D02*
X266390Y179498D01*
G01X267734Y180842D02*
X268370Y181478D01*
G01X269714Y182822D02*
X270385Y183493D01*
G01X271729Y184837D02*
X272365Y185473D01*
G01X273709Y186817D02*
X274345Y187453D01*
G01X275689Y188797D02*
X276445Y189553D01*
G01X277789Y190897D02*
X278868Y191976D01*
G01X280212Y193320D02*
X280848Y193956D01*
G01X279992Y194600D02*
X250504Y165112D01*
G01X251564Y162037D02*
Y164672D01*
G01X250504Y165112D02*
Y162477D01*
G01X250075Y160548D02*
X251564Y162037D01*
G01X250504Y162477D02*
X249635Y161608D01*
G01X248236Y160548D02*
X250075D01*
G01X249635Y161608D02*
X247793D01*
G01X247364Y159676D02*
X248236Y160548D01*
G01X247793Y161608D02*
X246304Y160119D01*
G01X247364Y157180D02*
Y159676D01*
G01X246304Y160119D02*
Y156737D01*
G01X250075Y156308D02*
X248236D01*
G01X289352Y159494D02*
X293514Y163656D01*
G01X314532Y186174D02*
X288292Y159934D01*
G01X289352Y156464D02*
Y159494D01*
G01D02*
X293514Y163656D01*
G01X314532Y186174D02*
X288292Y159934D01*
G01X289352Y156464D02*
Y159494D01*
G01X285815Y193297D02*
X254386Y161868D01*
G01X255446Y161428D02*
X286875Y192857D01*
G01X285815Y194683D02*
Y193297D01*
G01X286875Y192857D02*
Y194683D01*
G01X285815Y193297D02*
X254386Y161868D01*
G01X255446Y161428D02*
X286875Y192857D01*
G01X285815Y194683D02*
Y193297D01*
G01X286875Y192857D02*
Y194683D01*
G01X252294Y250334D02*
X259846D01*
G01X251851Y251394D02*
X259846D01*
G01X252294Y250334D02*
X259846D01*
G01X251851Y251394D02*
X259846D01*
G01X250307Y255243D02*
X259496D01*
G01X250750Y254183D02*
X259376D01*
G01X250307Y255243D02*
X259496D01*
G01X250750Y254183D02*
X259376D01*
G01X251851Y251394D02*
X259846D01*
G01X252294Y250334D02*
X259846D01*
G01X251851Y251394D02*
X259846D01*
G01X252294Y250334D02*
X259846D01*
G01X250750Y254183D02*
X259376D01*
G01X250307Y255243D02*
X259496D01*
G01X250750Y254183D02*
X259376D01*
G01X250307Y255243D02*
X259496D01*
G01X258368Y219025D02*
X257732Y218389D01*
G01X258368Y219025D02*
X257732Y218389D01*
G01X265461Y218396D02*
X263022D01*
G01X265461D02*
X263022D01*
G01X258368Y219025D02*
X257732Y218389D01*
G01X258368Y219025D02*
X257732Y218389D01*
G01X265461Y218396D02*
X263022D01*
G01X265461D02*
X263022D01*
G01X258847Y340096D02*
X254555D01*
G01X259012Y341156D02*
X254995D01*
G01X259012D02*
X254995D01*
G01X258847Y340096D02*
X254555D01*
G01X258847D02*
X254555D01*
G01X259012Y341156D02*
X254995D01*
G01X259012D02*
X254995D01*
G01X258847Y340096D02*
X254555D01*
G01X258654Y344877D02*
X255441D01*
G01X258654Y343817D02*
X255001D01*
G01X258654D02*
X255001D01*
G01X258654Y344877D02*
X255441D01*
G01X258654D02*
X255441D01*
G01X258654Y343817D02*
X255001D01*
G01X258654D02*
X255001D01*
G01X258654Y344877D02*
X255441D01*
G01X249148Y438013D02*
Y503652D01*
G01X250208Y512305D02*
Y438453D01*
G01X258051Y429110D02*
X249148Y438013D01*
G01X250208Y438453D02*
X259111Y429550D01*
G01X258051Y415708D02*
Y429110D01*
G01X259111Y429550D02*
Y416148D01*
G01X268869Y404890D02*
X258051Y415708D01*
G01X259111Y416148D02*
X261800Y413459D01*
G01X268869Y404890D02*
X258051Y415708D01*
G01X261800Y413459D02*
X269619Y405641D01*
G01X267347Y413165D02*
X263702Y416810D01*
G01X266596Y412416D02*
X262642Y416370D01*
G01X263702Y416810D02*
Y430459D01*
G01X262642Y416370D02*
Y430019D01*
G01X263702Y430459D02*
X255234Y438927D01*
G01X262642Y430019D02*
X254174Y438487D01*
G01X255234Y438927D02*
Y441411D01*
G01X254174Y438487D02*
Y441851D01*
G01X255234Y441411D02*
X257572Y443749D01*
G01X254174Y441851D02*
X256512Y444189D01*
G01X257572Y443749D02*
Y445692D01*
G01X256512Y444189D02*
Y445252D01*
G01X257572Y445692D02*
X254664Y448600D01*
G01X256512Y445252D02*
X253604Y448160D01*
G01X254664Y448600D02*
Y449305D01*
G01X253604Y448160D02*
Y449745D01*
G01X254664Y449305D02*
X257472Y452113D01*
G01X253604Y449745D02*
X256412Y452553D01*
G01X257472Y452113D02*
Y454692D01*
G01X256412Y452553D02*
Y454249D01*
G01X257472Y454692D02*
X255983Y456181D01*
G01X256412Y454249D02*
X255540Y455121D01*
G01X255983Y456181D02*
X254167D01*
G01X255540Y455121D02*
X253727D01*
G01X255983Y456181D02*
X254167D01*
G01D02*
X253484Y456864D01*
G01X253727Y455121D02*
X252424Y456424D01*
G01X253484Y456864D02*
Y458566D01*
G01X252424Y456424D02*
Y459006D01*
G01X253484Y458566D02*
X254539Y459621D01*
G01X252424Y459006D02*
X254099Y460681D01*
G01X254539Y459621D02*
X256159D01*
G01X254099Y460681D02*
X255719D01*
G01X256159Y459621D02*
X257572Y461034D01*
G01X255719Y460681D02*
X256512Y461474D01*
G01X257572Y461034D02*
Y466385D01*
G01X256512Y461474D02*
Y462593D01*
G01X257572Y461034D02*
Y466385D01*
G01X259111Y416148D02*
X261800Y413459D01*
G01D02*
X269619Y405641D01*
G01X268869Y404890D02*
X258051Y415708D01*
G01X259111Y429550D02*
Y416148D01*
G01X258051Y415708D02*
Y429110D01*
G01X250208Y438453D02*
X259111Y429550D01*
G01X258051Y429110D02*
X249148Y438013D01*
G01X250208Y512305D02*
Y438453D01*
G01X249148Y438013D02*
Y503652D01*
G01X250208Y512305D02*
Y438453D01*
G01Y512305D02*
Y438453D01*
G01X266596Y412416D02*
X262642Y416370D01*
G01X267347Y413165D02*
X263702Y416810D01*
G01X262642Y416370D02*
Y430019D01*
G01X263702Y416810D02*
Y430459D01*
G01X262642Y430019D02*
X254174Y438487D01*
G01X263702Y430459D02*
X255234Y438927D01*
G01X254174Y438487D02*
Y441851D01*
G01X255234Y438927D02*
Y441411D01*
G01X254174Y441851D02*
X256512Y444189D01*
G01X255234Y441411D02*
X257572Y443749D01*
G01X256512Y444189D02*
Y445252D01*
G01X257572Y443749D02*
Y445692D01*
G01X256512Y445252D02*
X253604Y448160D01*
G01X257572Y445692D02*
X254664Y448600D01*
G01X253604Y448160D02*
Y449745D01*
G01X254664Y448600D02*
Y449305D01*
G01X253604Y449745D02*
X256412Y452553D01*
G01X254664Y449305D02*
X257472Y452113D01*
G01X256412Y452553D02*
Y454249D01*
G01X257472Y452113D02*
Y454692D01*
G01X256412Y454249D02*
X255540Y455121D01*
G01X257472Y454692D02*
X255983Y456181D01*
G01X255540Y455121D02*
X253727D01*
G01D02*
X252424Y456424D01*
G01X255983Y456181D02*
X254167D01*
G01X253727Y455121D02*
X252424Y456424D01*
G01X254167Y456181D02*
X253484Y456864D01*
G01X252424Y456424D02*
Y459006D01*
G01X253484Y456864D02*
Y458566D01*
G01X252424Y459006D02*
X254099Y460681D01*
G01X253484Y458566D02*
X254539Y459621D01*
G01X254099Y460681D02*
X255719D01*
G01X254539Y459621D02*
X256159D01*
G01X255719Y460681D02*
X256512Y461474D01*
G01X256159Y459621D02*
X257572Y461034D01*
G01X256512Y461474D02*
Y462593D01*
G01X257572Y461034D02*
Y466385D01*
G01X318263Y410996D02*
X292312Y436947D01*
G01D02*
Y479709D01*
G01X249148Y438013D02*
Y503652D01*
G01X250208Y512305D02*
Y438453D01*
G01X258051Y429110D02*
X249148Y438013D01*
G01X250208Y438453D02*
X259111Y429550D01*
G01X258051Y415708D02*
Y429110D01*
G01X259111Y429550D02*
Y416148D01*
G01X268869Y404890D02*
X258051Y415708D01*
G01X259111Y416148D02*
X261800Y413459D01*
G01X268869Y404890D02*
X258051Y415708D01*
G01X261800Y413459D02*
X269619Y405641D01*
G01X292312Y436947D02*
Y479709D01*
G01X318263Y410996D02*
X292312Y436947D01*
G01D02*
Y479709D01*
G01X318263Y410996D02*
X292312Y436947D01*
G01X267347Y413165D02*
X263702Y416810D01*
G01X266596Y412416D02*
X262642Y416370D01*
G01X263702Y416810D02*
Y430459D01*
G01X262642Y416370D02*
Y430019D01*
G01X263702Y430459D02*
X255234Y438927D01*
G01X262642Y430019D02*
X254174Y438487D01*
G01X255234Y438927D02*
Y441411D01*
G01X254174Y438487D02*
Y441851D01*
G01X255234Y441411D02*
X257572Y443749D01*
G01X254174Y441851D02*
X256512Y444189D01*
G01X257572Y443749D02*
Y445692D01*
G01X256512Y444189D02*
Y445252D01*
G01X257572Y445692D02*
X254664Y448600D01*
G01X256512Y445252D02*
X253604Y448160D01*
G01X254664Y448600D02*
Y449305D01*
G01X253604Y448160D02*
Y449745D01*
G01X254664Y449305D02*
X257472Y452113D01*
G01X253604Y449745D02*
X256412Y452553D01*
G01X257472Y452113D02*
Y454692D01*
G01X256412Y452553D02*
Y454249D01*
G01X257472Y454692D02*
X255983Y456181D01*
G01X256412Y454249D02*
X255540Y455121D01*
G01X255983Y456181D02*
X254167D01*
G01X255540Y455121D02*
X253727D01*
G01X255983Y456181D02*
X254167D01*
G01D02*
X253484Y456864D01*
G01X253727Y455121D02*
X252424Y456424D01*
G01X253484Y456864D02*
Y458566D01*
G01X252424Y456424D02*
Y459006D01*
G01X253484Y458566D02*
X254539Y459621D01*
G01X252424Y459006D02*
X254099Y460681D01*
G01X254539Y459621D02*
X256159D01*
G01X254099Y460681D02*
X255719D01*
G01X256159Y459621D02*
X257572Y461034D01*
G01X255719Y460681D02*
X256512Y461474D01*
G01X257572Y461034D02*
Y466385D01*
G01X256512Y461474D02*
Y462593D01*
G01X257572Y461034D02*
Y466385D01*
G01X259111Y416148D02*
X261800Y413459D01*
G01D02*
X269619Y405641D01*
G01X268869Y404890D02*
X258051Y415708D01*
G01X259111Y429550D02*
Y416148D01*
G01X258051Y415708D02*
Y429110D01*
G01X250208Y438453D02*
X259111Y429550D01*
G01X258051Y429110D02*
X249148Y438013D01*
G01X250208Y512305D02*
Y438453D01*
G01X249148Y438013D02*
Y503652D01*
G01X250208Y512305D02*
Y438453D01*
G01Y512305D02*
Y438453D01*
G01X318263Y410996D02*
X292312Y436947D01*
G01D02*
Y479709D01*
G01X266596Y412416D02*
X262642Y416370D01*
G01X267347Y413165D02*
X263702Y416810D01*
G01X262642Y416370D02*
Y430019D01*
G01X263702Y416810D02*
Y430459D01*
G01X262642Y430019D02*
X254174Y438487D01*
G01X263702Y430459D02*
X255234Y438927D01*
G01X254174Y438487D02*
Y441851D01*
G01X255234Y438927D02*
Y441411D01*
G01X254174Y441851D02*
X256512Y444189D01*
G01X255234Y441411D02*
X257572Y443749D01*
G01X256512Y444189D02*
Y445252D01*
G01X257572Y443749D02*
Y445692D01*
G01X256512Y445252D02*
X253604Y448160D01*
G01X257572Y445692D02*
X254664Y448600D01*
G01X253604Y448160D02*
Y449745D01*
G01X254664Y448600D02*
Y449305D01*
G01X253604Y449745D02*
X256412Y452553D01*
G01X254664Y449305D02*
X257472Y452113D01*
G01X256412Y452553D02*
Y454249D01*
G01X257472Y452113D02*
Y454692D01*
G01X256412Y454249D02*
X255540Y455121D01*
G01X257472Y454692D02*
X255983Y456181D01*
G01X255540Y455121D02*
X253727D01*
G01D02*
X252424Y456424D01*
G01X255983Y456181D02*
X254167D01*
G01X253727Y455121D02*
X252424Y456424D01*
G01X254167Y456181D02*
X253484Y456864D01*
G01X252424Y456424D02*
Y459006D01*
G01X253484Y456864D02*
Y458566D01*
G01X252424Y459006D02*
X254099Y460681D01*
G01X253484Y458566D02*
X254539Y459621D01*
G01X254099Y460681D02*
X255719D01*
G01X254539Y459621D02*
X256159D01*
G01X255719Y460681D02*
X256512Y461474D01*
G01X256159Y459621D02*
X257572Y461034D01*
G01X256512Y461474D02*
Y462593D01*
G01X257572Y461034D02*
Y466385D01*
G01X245225Y514400D02*
Y532411D01*
G01X246285Y526760D02*
Y525340D01*
G01X245225Y514400D02*
Y532411D01*
G01X246285Y521660D02*
Y520290D01*
G01X249148Y505706D02*
Y506799D01*
G01Y509039D02*
Y511744D01*
G01X251509Y519900D02*
X250838Y520571D01*
G01X250608Y519300D02*
X249778Y520130D01*
G01X250838Y520571D02*
Y521848D01*
G01Y525338D02*
Y526229D01*
G01X249778Y520130D02*
Y526670D01*
G01X250838Y526229D02*
X251609Y527000D01*
G01X256512Y464833D02*
Y465945D01*
G01X257572Y466385D02*
X255693Y468264D01*
G01X256512Y465945D02*
X254633Y467824D01*
G01X255693Y468264D02*
Y512134D01*
G01X254633Y467824D02*
Y469246D01*
G01X255693Y468264D02*
Y512134D01*
G01X254633Y471486D02*
Y472486D01*
G01X255693Y468264D02*
Y512134D01*
G01X254633Y474726D02*
Y475726D01*
G01X255693Y468264D02*
Y512134D01*
G01X254633Y477966D02*
Y478966D01*
G01X255693Y468264D02*
Y512134D01*
G01X254633Y481206D02*
Y482206D01*
G01X255693Y468264D02*
Y512134D01*
G01X254633Y484446D02*
Y485446D01*
G01X255693Y468264D02*
Y512134D01*
G01X254633Y487686D02*
Y488686D01*
G01X255693Y468264D02*
Y512134D01*
G01X254633Y490926D02*
Y491939D01*
G01X255693Y468264D02*
Y512134D01*
G01X254633Y494153D02*
Y495312D01*
G01X255693Y468264D02*
Y512134D01*
G01X254633Y497524D02*
Y498406D01*
G01X255693Y468264D02*
Y512134D01*
G01X254633Y500646D02*
Y501646D01*
G01X255693Y468264D02*
Y512134D01*
G01X254633Y503886D02*
Y504886D01*
G01X255693Y468264D02*
Y512134D01*
G01X254633Y507126D02*
Y508126D01*
G01X255693Y468264D02*
Y512134D01*
G01X254633Y510366D02*
Y511694D01*
G01X255693Y512134D02*
X252313Y515514D01*
G01X254633Y511694D02*
X253413Y512914D01*
G01X246285Y526760D02*
Y525340D01*
G01Y521660D02*
Y520290D01*
G01X245225Y514400D02*
Y532411D01*
G01X249148Y505706D02*
Y506799D01*
G01Y509039D02*
Y511744D01*
G01X250608Y519300D02*
X249778Y520130D01*
G01X251509Y519900D02*
X250838Y520571D01*
G01X249778Y520130D02*
Y526670D01*
G01X250838Y520571D02*
Y521848D01*
G01X249778Y520130D02*
Y526670D01*
G01X250838Y525338D02*
Y526229D01*
G01D02*
X251609Y527000D01*
G01X256512Y464833D02*
Y465945D01*
G01D02*
X254633Y467824D01*
G01X257572Y466385D02*
X255693Y468264D01*
G01X254633Y467824D02*
Y469246D01*
G01Y471486D02*
Y472486D01*
G01Y474726D02*
Y475726D01*
G01Y477966D02*
Y478966D01*
G01Y481206D02*
Y482206D01*
G01Y484446D02*
Y485446D01*
G01Y487686D02*
Y488686D01*
G01Y490926D02*
Y491939D01*
G01Y494153D02*
Y495312D01*
G01Y497524D02*
Y498406D01*
G01Y500646D02*
Y501646D01*
G01Y503886D02*
Y504886D01*
G01Y507126D02*
Y508126D01*
G01Y510366D02*
Y511694D01*
G01X255693Y468264D02*
Y512134D01*
G01X254633Y511694D02*
X253413Y512914D01*
G01X255693Y512134D02*
X252313Y515514D01*
G01X283096Y526760D02*
Y525340D01*
G01Y521660D02*
Y520290D01*
G01X282036Y514400D02*
Y532411D01*
G01X287104Y486420D02*
X293372Y480152D01*
G01X292312Y479709D02*
X286044Y485977D01*
G01X287104Y512249D02*
Y486420D01*
G01X286044Y485977D02*
Y503144D01*
G01X287104Y512249D02*
Y486420D01*
G01X286044Y505484D02*
Y506484D01*
G01X287104Y512249D02*
Y486420D01*
G01X286044Y508824D02*
Y511808D01*
G01X284053Y515300D02*
X287104Y512249D01*
G01X286044Y511808D02*
X285152Y512700D01*
G01X245225Y514400D02*
Y532411D01*
G01X246285Y526760D02*
Y525340D01*
G01X245225Y514400D02*
Y532411D01*
G01X246285Y521660D02*
Y520290D01*
G01X249148Y505706D02*
Y506799D01*
G01Y509039D02*
Y511744D01*
G01X286044Y511808D02*
X285152Y512700D01*
G01X284053Y515300D02*
X287104Y512249D01*
G01X286044Y485977D02*
Y503144D01*
G01Y505484D02*
Y506484D01*
G01Y508824D02*
Y511808D01*
G01X287104Y512249D02*
Y486420D01*
G01X292312Y479709D02*
X286044Y485977D01*
G01X287104Y486420D02*
X293372Y480152D01*
G01X282036Y514400D02*
Y532411D01*
G01X283096Y526760D02*
Y525340D01*
G01X282036Y514400D02*
Y532411D01*
G01X283096Y521660D02*
Y520290D01*
G01X286044Y511808D02*
X285152Y512700D01*
G01X284053Y515300D02*
X287104Y512249D01*
G01X286044Y485977D02*
Y503144D01*
G01Y505484D02*
Y506484D01*
G01Y508824D02*
Y511808D01*
G01X287104Y512249D02*
Y486420D01*
G01X292312Y479709D02*
X286044Y485977D01*
G01X287104Y486420D02*
X293372Y480152D01*
G01X282036Y514400D02*
Y532411D01*
G01X283096Y526760D02*
Y525340D01*
G01X282036Y514400D02*
Y532411D01*
G01X283096Y521660D02*
Y520290D01*
G01X251509Y519900D02*
X250838Y520571D01*
G01X250608Y519300D02*
X249778Y520130D01*
G01X250838Y520571D02*
Y521848D01*
G01Y525338D02*
Y526229D01*
G01X249778Y520130D02*
Y526670D01*
G01X250838Y526229D02*
X251609Y527000D01*
G01X256512Y464833D02*
Y465945D01*
G01X257572Y466385D02*
X255693Y468264D01*
G01X256512Y465945D02*
X254633Y467824D01*
G01X255693Y468264D02*
Y512134D01*
G01X254633Y467824D02*
Y469246D01*
G01X255693Y468264D02*
Y512134D01*
G01X254633Y471486D02*
Y472486D01*
G01X255693Y468264D02*
Y512134D01*
G01X254633Y474726D02*
Y475726D01*
G01X255693Y468264D02*
Y512134D01*
G01X254633Y477966D02*
Y478966D01*
G01X255693Y468264D02*
Y512134D01*
G01X254633Y481206D02*
Y482206D01*
G01X255693Y468264D02*
Y512134D01*
G01X254633Y484446D02*
Y485446D01*
G01X255693Y468264D02*
Y512134D01*
G01X254633Y487686D02*
Y488686D01*
G01X255693Y468264D02*
Y512134D01*
G01X254633Y490926D02*
Y491939D01*
G01X255693Y468264D02*
Y512134D01*
G01X254633Y494153D02*
Y495312D01*
G01X255693Y468264D02*
Y512134D01*
G01X254633Y497524D02*
Y498406D01*
G01X255693Y468264D02*
Y512134D01*
G01X254633Y500646D02*
Y501646D01*
G01X255693Y468264D02*
Y512134D01*
G01X254633Y503886D02*
Y504886D01*
G01X255693Y468264D02*
Y512134D01*
G01X254633Y507126D02*
Y508126D01*
G01X255693Y468264D02*
Y512134D01*
G01X254633Y510366D02*
Y511694D01*
G01X255693Y512134D02*
X252313Y515514D01*
G01X254633Y511694D02*
X253413Y512914D01*
G01X288320Y519900D02*
X287649Y520571D01*
G01X287419Y519300D02*
X286589Y520130D01*
G01X287649Y520571D02*
Y521848D01*
G01Y525338D02*
Y526229D01*
G01X286589Y520130D02*
Y526670D01*
G01X287649Y526229D02*
X288420Y527000D01*
G01X297984Y481637D02*
X292504Y487117D01*
G01X297984Y481637D02*
X292504Y487117D01*
G01X297984Y481637D02*
X292504Y487117D01*
G01X292151Y485970D02*
X291444Y486677D01*
G01X292504Y487117D02*
Y512134D01*
G01X291444Y486677D02*
Y488287D01*
G01X292504Y487117D02*
Y512134D01*
G01X291444Y490527D02*
Y491633D01*
G01X292504Y487117D02*
Y512134D01*
G01X291444Y493715D02*
Y494885D01*
G01X292504Y487117D02*
Y512134D01*
G01X291444Y496915D02*
Y498100D01*
G01X292504Y487117D02*
Y512134D01*
G01X291444Y500154D02*
Y501247D01*
G01X292504Y487117D02*
Y512134D01*
G01X291444Y503487D02*
Y504487D01*
G01X292504Y487117D02*
Y512134D01*
G01X291444Y506727D02*
Y507727D01*
G01X292504Y487117D02*
Y512134D01*
G01X291444Y509967D02*
Y511694D01*
G01X292504Y512134D02*
X289124Y515514D01*
G01X291444Y511694D02*
X290224Y512914D01*
G01X288320Y519900D02*
X287649Y520571D01*
G01X287419Y519300D02*
X286589Y520130D01*
G01X287649Y520571D02*
Y521848D01*
G01Y525338D02*
Y526229D01*
G01X286589Y520130D02*
Y526670D01*
G01X287649Y526229D02*
X288420Y527000D01*
G01X297984Y481637D02*
X292504Y487117D01*
G01X297984Y481637D02*
X292504Y487117D01*
G01X297984Y481637D02*
X292504Y487117D01*
G01X292151Y485970D02*
X291444Y486677D01*
G01X292504Y487117D02*
Y512134D01*
G01X291444Y486677D02*
Y488287D01*
G01X292504Y487117D02*
Y512134D01*
G01X291444Y490527D02*
Y491633D01*
G01X292504Y487117D02*
Y512134D01*
G01X291444Y493715D02*
Y494885D01*
G01X292504Y487117D02*
Y512134D01*
G01X291444Y496915D02*
Y498100D01*
G01X292504Y487117D02*
Y512134D01*
G01X291444Y500154D02*
Y501247D01*
G01X292504Y487117D02*
Y512134D01*
G01X291444Y503487D02*
Y504487D01*
G01X292504Y487117D02*
Y512134D01*
G01X291444Y506727D02*
Y507727D01*
G01X292504Y487117D02*
Y512134D01*
G01X291444Y509967D02*
Y511694D01*
G01X292504Y512134D02*
X289124Y515514D01*
G01X291444Y511694D02*
X290224Y512914D01*
G01X246285Y526760D02*
Y525340D01*
G01Y521660D02*
Y520290D01*
G01X245225Y514400D02*
Y532411D01*
G01X249148Y505706D02*
Y506799D01*
G01Y509039D02*
Y511744D01*
G01X283096Y526760D02*
Y525340D01*
G01Y521660D02*
Y520290D01*
G01X282036Y514400D02*
Y532411D01*
G01X287104Y486420D02*
X293372Y480152D01*
G01X292312Y479709D02*
X286044Y485977D01*
G01X287104Y512249D02*
Y486420D01*
G01X286044Y485977D02*
Y503144D01*
G01X287104Y512249D02*
Y486420D01*
G01X286044Y505484D02*
Y506484D01*
G01X287104Y512249D02*
Y486420D01*
G01X286044Y508824D02*
Y511808D01*
G01X284053Y515300D02*
X287104Y512249D01*
G01X286044Y511808D02*
X285152Y512700D01*
G01X250608Y519300D02*
X249778Y520130D01*
G01X251509Y519900D02*
X250838Y520571D01*
G01X249778Y520130D02*
Y526670D01*
G01X250838Y520571D02*
Y521848D01*
G01X249778Y520130D02*
Y526670D01*
G01X250838Y525338D02*
Y526229D01*
G01D02*
X251609Y527000D01*
G01X256512Y464833D02*
Y465945D01*
G01D02*
X254633Y467824D01*
G01X257572Y466385D02*
X255693Y468264D01*
G01X254633Y467824D02*
Y469246D01*
G01Y471486D02*
Y472486D01*
G01Y474726D02*
Y475726D01*
G01Y477966D02*
Y478966D01*
G01Y481206D02*
Y482206D01*
G01Y484446D02*
Y485446D01*
G01Y487686D02*
Y488686D01*
G01Y490926D02*
Y491939D01*
G01Y494153D02*
Y495312D01*
G01Y497524D02*
Y498406D01*
G01Y500646D02*
Y501646D01*
G01Y503886D02*
Y504886D01*
G01Y507126D02*
Y508126D01*
G01Y510366D02*
Y511694D01*
G01X255693Y468264D02*
Y512134D01*
G01X254633Y511694D02*
X253413Y512914D01*
G01X255693Y512134D02*
X252313Y515514D01*
G01X287419Y519300D02*
X286589Y520130D01*
G01X288320Y519900D02*
X287649Y520571D01*
G01X286589Y520130D02*
Y526670D01*
G01X287649Y520571D02*
Y521848D01*
G01X286589Y520130D02*
Y526670D01*
G01X287649Y525338D02*
Y526229D01*
G01D02*
X288420Y527000D01*
G01X292151Y485970D02*
X291444Y486677D01*
G01X297984Y481637D02*
X292504Y487117D01*
G01X291444Y486677D02*
Y488287D01*
G01Y490527D02*
Y491633D01*
G01Y493715D02*
Y494885D01*
G01Y496915D02*
Y498100D01*
G01Y500154D02*
Y501247D01*
G01Y503487D02*
Y504487D01*
G01Y506727D02*
Y507727D01*
G01Y509967D02*
Y511694D01*
G01X292504Y487117D02*
Y512134D01*
G01X291444Y511694D02*
X290224Y512914D01*
G01X292504Y512134D02*
X289124Y515514D01*
G01X287419Y519300D02*
X286589Y520130D01*
G01X288320Y519900D02*
X287649Y520571D01*
G01X286589Y520130D02*
Y526670D01*
G01X287649Y520571D02*
Y521848D01*
G01X286589Y520130D02*
Y526670D01*
G01X287649Y525338D02*
Y526229D01*
G01D02*
X288420Y527000D01*
G01X292151Y485970D02*
X291444Y486677D01*
G01X297984Y481637D02*
X292504Y487117D01*
G01X291444Y486677D02*
Y488287D01*
G01Y490527D02*
Y491633D01*
G01Y493715D02*
Y494885D01*
G01Y496915D02*
Y498100D01*
G01Y500154D02*
Y501247D01*
G01Y503487D02*
Y504487D01*
G01Y506727D02*
Y507727D01*
G01Y509967D02*
Y511694D01*
G01X292504Y487117D02*
Y512134D01*
G01X291444Y511694D02*
X290224Y512914D01*
G01X292504Y512134D02*
X289124Y515514D01*
G01X249778Y526670D02*
X250608Y527500D01*
G01X249778Y526670D02*
X250608Y527500D01*
G01X249778Y526670D02*
X250608Y527500D01*
G01X286589Y526670D02*
X287419Y527500D01*
G01X286589Y526670D02*
X287419Y527500D01*
G01X249778Y526670D02*
X250608Y527500D01*
G01X286589Y526670D02*
X287419Y527500D01*
G01X286589Y526670D02*
X287419Y527500D01*
G01X295964Y133465D02*
Y161372D01*
G01X294904Y161812D02*
Y133908D01*
G01X295964Y133465D02*
Y161372D01*
G01X294904Y161812D02*
Y133908D01*
G01Y161812D02*
Y133908D01*
G01X295964Y133465D02*
Y161372D01*
G01X294904Y161812D02*
Y133908D01*
G01X295964Y133465D02*
Y161372D01*
G01X295374Y165516D02*
X296668Y166810D01*
G01X298528Y168670D02*
X299822Y169964D01*
G01X301682Y171824D02*
X302976Y173118D01*
G01X304836Y174978D02*
X306130Y176272D01*
G01X307990Y178132D02*
X309284Y179426D01*
G01X311144Y181286D02*
X312438Y182580D01*
G01X314298Y184440D02*
X315592Y185734D01*
G01X314532Y188900D02*
Y186174D01*
G01X315592Y185734D02*
Y188900D01*
G01X295374Y165516D02*
X296668Y166810D01*
G01X298528Y168670D02*
X299822Y169964D01*
G01X301682Y171824D02*
X302976Y173118D01*
G01X304836Y174978D02*
X306130Y176272D01*
G01X307990Y178132D02*
X309284Y179426D01*
G01X311144Y181286D02*
X312438Y182580D01*
G01X314298Y184440D02*
X315592Y185734D01*
G01X314532Y188900D02*
Y186174D01*
G01X315592Y185734D02*
Y188900D01*
G01X321192Y190563D02*
Y192965D01*
G01X320132Y192943D02*
Y190774D01*
G01X318390Y183798D02*
X321192Y190563D01*
G01X320132Y190774D02*
X317491Y184399D01*
G01X295964Y161372D02*
X303546Y168954D01*
G01X305406Y170814D02*
X306700Y172108D01*
G01X308560Y173968D02*
X309854Y175262D01*
G01X311714Y177122D02*
X318390Y183798D01*
G01X317491Y184399D02*
X294904Y161812D01*
G01X321192Y190563D02*
Y192965D01*
G01X320132Y192943D02*
Y190774D01*
G01X318390Y183798D02*
X321192Y190563D01*
G01X320132Y190774D02*
X317491Y184399D01*
G01X295964Y161372D02*
X303546Y168954D01*
G01X305406Y170814D02*
X306700Y172108D01*
G01X308560Y173968D02*
X309854Y175262D01*
G01X311714Y177122D02*
X318390Y183798D01*
G01X317491Y184399D02*
X294904Y161812D01*
G01X315592Y185734D02*
Y188900D01*
G01X314532D02*
Y186174D01*
G01X295374Y165516D02*
X296668Y166810D01*
G01X298528Y168670D02*
X299822Y169964D01*
G01X301682Y171824D02*
X302976Y173118D01*
G01X304836Y174978D02*
X306130Y176272D01*
G01X307990Y178132D02*
X309284Y179426D01*
G01X311144Y181286D02*
X312438Y182580D01*
G01X314298Y184440D02*
X315592Y185734D01*
G01D02*
Y188900D01*
G01X314532D02*
Y186174D01*
G01X295374Y165516D02*
X296668Y166810D01*
G01X298528Y168670D02*
X299822Y169964D01*
G01X301682Y171824D02*
X302976Y173118D01*
G01X304836Y174978D02*
X306130Y176272D01*
G01X307990Y178132D02*
X309284Y179426D01*
G01X311144Y181286D02*
X312438Y182580D01*
G01X314298Y184440D02*
X315592Y185734D01*
G01X317491Y184399D02*
X294904Y161812D01*
G01X295964Y161372D02*
X303546Y168954D01*
G01X317491Y184399D02*
X294904Y161812D01*
G01X305406Y170814D02*
X306700Y172108D01*
G01X317491Y184399D02*
X294904Y161812D01*
G01X308560Y173968D02*
X309854Y175262D01*
G01X317491Y184399D02*
X294904Y161812D01*
G01X311714Y177122D02*
X318390Y183798D01*
G01X320132Y190774D02*
X317491Y184399D01*
G01X318390Y183798D02*
X321192Y190563D01*
G01X320132Y192943D02*
Y190774D01*
G01X321192Y190563D02*
Y192965D01*
G01X317491Y184399D02*
X294904Y161812D01*
G01X295964Y161372D02*
X303546Y168954D01*
G01X317491Y184399D02*
X294904Y161812D01*
G01X305406Y170814D02*
X306700Y172108D01*
G01X317491Y184399D02*
X294904Y161812D01*
G01X308560Y173968D02*
X309854Y175262D01*
G01X317491Y184399D02*
X294904Y161812D01*
G01X311714Y177122D02*
X318390Y183798D01*
G01X320132Y190774D02*
X317491Y184399D01*
G01X318390Y183798D02*
X321192Y190563D01*
G01X320132Y192943D02*
Y190774D01*
G01X321192Y190563D02*
Y192965D01*
G01X319323Y411439D02*
Y404437D01*
G01X318263D02*
Y410996D01*
G01X293372Y437390D02*
X319323Y411439D01*
G01X293372Y480152D02*
Y437390D01*
G01Y480152D02*
Y437390D01*
G01D02*
X319323Y411439D01*
G01X318263Y404437D02*
Y410996D01*
G01X319323Y411439D02*
Y404437D01*
G01X293372Y480152D02*
Y437390D01*
G01D02*
X319323Y411439D01*
G01X318263Y404437D02*
Y410996D01*
G01X319323Y411439D02*
Y404437D01*
G01X323286Y407587D02*
Y412875D01*
G01X322226Y407587D02*
Y412435D01*
G01X323286Y412875D02*
X304300Y431861D01*
G01X322226Y412435D02*
X303242Y431419D01*
G01X304300Y431861D02*
Y435304D01*
G01X303240Y431419D02*
Y434864D01*
G01X304300Y435304D02*
X302811Y436793D01*
G01X303240Y434864D02*
X302371Y435733D01*
G01X302811Y436793D02*
X300192D01*
G01X302371Y435733D02*
X299752D01*
G01X300192Y436793D02*
X299323Y437662D01*
G01X299752Y435733D02*
X298263Y437222D01*
G01X299323Y437662D02*
Y439361D01*
G01X298263Y437222D02*
Y439801D01*
G01X299323Y439361D02*
X300195Y440233D01*
G01X298263Y439801D02*
X299755Y441293D01*
G01X300195Y440233D02*
X301980D01*
G01X299755Y441293D02*
X301540D01*
G01X301980Y440233D02*
X303472Y441725D01*
G01X301540Y441293D02*
X302412Y442165D01*
G01X303472Y441725D02*
Y444318D01*
G01X302412Y442165D02*
Y443878D01*
G01X303472Y444318D02*
X302010Y445780D01*
G01X302412Y443878D02*
X301570Y444720D01*
G01X302010Y445780D02*
X298644D01*
G01X301570Y444720D02*
X298204D01*
G01X298644Y445780D02*
X297984Y446440D01*
G01X298204Y444720D02*
X296924Y446000D01*
G01X297984Y446440D02*
Y481637D01*
G01X296924Y446000D02*
Y468237D01*
G01X297984Y446440D02*
Y481637D01*
G01Y446440D02*
Y481637D01*
G01Y446440D02*
Y481637D01*
G01Y446440D02*
Y481637D01*
G01X323286Y407587D02*
Y412875D01*
G01X322226Y407587D02*
Y412435D01*
G01X323286Y412875D02*
X304300Y431861D01*
G01X322226Y412435D02*
X303242Y431419D01*
G01X304300Y431861D02*
Y435304D01*
G01X303240Y431419D02*
Y434864D01*
G01X304300Y435304D02*
X302811Y436793D01*
G01X303240Y434864D02*
X302371Y435733D01*
G01X302811Y436793D02*
X300192D01*
G01X302371Y435733D02*
X299752D01*
G01X300192Y436793D02*
X299323Y437662D01*
G01X299752Y435733D02*
X298263Y437222D01*
G01X299323Y437662D02*
Y439361D01*
G01X298263Y437222D02*
Y439801D01*
G01X299323Y439361D02*
X300195Y440233D01*
G01X298263Y439801D02*
X299755Y441293D01*
G01X300195Y440233D02*
X301980D01*
G01X299755Y441293D02*
X301540D01*
G01X301980Y440233D02*
X303472Y441725D01*
G01X301540Y441293D02*
X302412Y442165D01*
G01X303472Y441725D02*
Y444318D01*
G01X302412Y442165D02*
Y443878D01*
G01X303472Y444318D02*
X302010Y445780D01*
G01X302412Y443878D02*
X301570Y444720D01*
G01X302010Y445780D02*
X298644D01*
G01X301570Y444720D02*
X298204D01*
G01X298644Y445780D02*
X297984Y446440D01*
G01X298204Y444720D02*
X296924Y446000D01*
G01X297984Y446440D02*
Y481637D01*
G01X296924Y446000D02*
Y468237D01*
G01X297984Y446440D02*
Y481637D01*
G01Y446440D02*
Y481637D01*
G01Y446440D02*
Y481637D01*
G01Y446440D02*
Y481637D01*
G01X319323Y411439D02*
Y404437D01*
G01X318263D02*
Y410996D01*
G01X293372Y437390D02*
X319323Y411439D01*
G01X293372Y480152D02*
Y437390D01*
G01X322226Y407587D02*
Y412435D01*
G01X323286Y407587D02*
Y412875D01*
G01X322226Y412435D02*
X303242Y431419D01*
G01X323286Y412875D02*
X304300Y431861D01*
G01X303240Y431419D02*
Y434864D01*
G01X304300Y431861D02*
Y435304D01*
G01X303240Y434864D02*
X302371Y435733D01*
G01X304300Y435304D02*
X302811Y436793D01*
G01X302371Y435733D02*
X299752D01*
G01X302811Y436793D02*
X300192D01*
G01X299752Y435733D02*
X298263Y437222D01*
G01X300192Y436793D02*
X299323Y437662D01*
G01X298263Y437222D02*
Y439801D01*
G01X299323Y437662D02*
Y439361D01*
G01X298263Y439801D02*
X299755Y441293D01*
G01X299323Y439361D02*
X300195Y440233D01*
G01X299755Y441293D02*
X301540D01*
G01X300195Y440233D02*
X301980D01*
G01X301540Y441293D02*
X302412Y442165D01*
G01X301980Y440233D02*
X303472Y441725D01*
G01X302412Y442165D02*
Y443878D01*
G01X303472Y441725D02*
Y444318D01*
G01X302412Y443878D02*
X301570Y444720D01*
G01X303472Y444318D02*
X302010Y445780D01*
G01X301570Y444720D02*
X298204D01*
G01X302010Y445780D02*
X298644D01*
G01X298204Y444720D02*
X296924Y446000D01*
G01X298644Y445780D02*
X297984Y446440D01*
G01X296924Y446000D02*
Y468237D01*
G01X297984Y446440D02*
Y481637D01*
G01X322226Y407587D02*
Y412435D01*
G01X323286Y407587D02*
Y412875D01*
G01X322226Y412435D02*
X303242Y431419D01*
G01X323286Y412875D02*
X304300Y431861D01*
G01X303240Y431419D02*
Y434864D01*
G01X304300Y431861D02*
Y435304D01*
G01X303240Y434864D02*
X302371Y435733D01*
G01X304300Y435304D02*
X302811Y436793D01*
G01X302371Y435733D02*
X299752D01*
G01X302811Y436793D02*
X300192D01*
G01X299752Y435733D02*
X298263Y437222D01*
G01X300192Y436793D02*
X299323Y437662D01*
G01X298263Y437222D02*
Y439801D01*
G01X299323Y437662D02*
Y439361D01*
G01X298263Y439801D02*
X299755Y441293D01*
G01X299323Y439361D02*
X300195Y440233D01*
G01X299755Y441293D02*
X301540D01*
G01X300195Y440233D02*
X301980D01*
G01X301540Y441293D02*
X302412Y442165D01*
G01X301980Y440233D02*
X303472Y441725D01*
G01X302412Y442165D02*
Y443878D01*
G01X303472Y441725D02*
Y444318D01*
G01X302412Y443878D02*
X301570Y444720D01*
G01X303472Y444318D02*
X302010Y445780D01*
G01X301570Y444720D02*
X298204D01*
G01X302010Y445780D02*
X298644D01*
G01X298204Y444720D02*
X296924Y446000D01*
G01X298644Y445780D02*
X297984Y446440D01*
G01X296924Y446000D02*
Y468237D01*
G01X297984Y446440D02*
Y481637D01*
G01X296924Y470477D02*
Y471477D01*
G01Y473717D02*
Y474717D01*
G01Y476957D02*
Y477957D01*
G01Y480197D02*
Y481197D01*
G01D02*
X296028Y482093D01*
G01X294443Y483678D02*
X293736Y484385D01*
G01X296924Y470477D02*
Y471477D01*
G01Y473717D02*
Y474717D01*
G01Y476957D02*
Y477957D01*
G01Y480197D02*
Y481197D01*
G01D02*
X296028Y482093D01*
G01X294443Y483678D02*
X293736Y484385D01*
G01X296924Y470477D02*
Y471477D01*
G01Y473717D02*
Y474717D01*
G01Y476957D02*
Y477957D01*
G01Y480197D02*
Y481197D01*
G01D02*
X296028Y482093D01*
G01X294443Y483678D02*
X293736Y484385D01*
G01X296924Y470477D02*
Y471477D01*
G01Y473717D02*
Y474717D01*
G01Y476957D02*
Y477957D01*
G01Y480197D02*
Y481197D01*
G01D02*
X296028Y482093D01*
G01X294443Y483678D02*
X293736Y484385D01*
G01X382792Y39260D02*
Y7541D01*
G01X383852Y38820D02*
Y7101D01*
G01X382792Y7541D02*
X379751Y4500D01*
G01X383852Y7101D02*
X380191Y3440D01*
G01X379751Y4500D02*
X375792D01*
G01X380191Y3440D02*
X376232D01*
G01X375792Y4500D02*
X373292Y2000D01*
G01X376232Y3440D02*
X374352Y1560D01*
G01X373292Y2000D02*
Y-2407D01*
G01X374352Y1560D02*
Y-2847D01*
G01X373292Y-2407D02*
X370094Y-5605D01*
G01X374352Y-2847D02*
X370534Y-6665D01*
G01X370094Y-5605D02*
X363805D01*
G01X370534Y-6665D02*
X364245D01*
G01X363805Y-5605D02*
X362286Y-7124D01*
G01X364245Y-6665D02*
X363346Y-7564D01*
G01X362286Y-7124D02*
Y-8718D01*
G01X363346Y-7564D02*
Y-8567D01*
G01X373812Y41520D02*
Y24336D01*
G01X374872Y41080D02*
Y23896D01*
G01X373812Y24336D02*
X370356Y20880D01*
G01X374872Y23896D02*
X370796Y19820D01*
G01X370356Y20880D02*
X364610D01*
G01X370796Y19820D02*
X365050D01*
G01X364610Y20880D02*
X363295Y19565D01*
G01X365050Y19820D02*
X364355Y19125D01*
G01X363295Y19565D02*
Y17647D01*
G01X364355Y19125D02*
Y17998D01*
G01X377786Y41394D02*
Y11341D01*
G01X378846Y40954D02*
Y10901D01*
G01X377786Y11341D02*
X376354Y9909D01*
G01X378846Y10901D02*
X376794Y8849D01*
G01X376354Y9909D02*
X374886D01*
G01D02*
X370254Y5277D01*
G01X376794Y8849D02*
X375326D01*
G01X374886Y9909D02*
X370254Y5277D01*
G01X375326Y8849D02*
X371314Y4837D01*
G01X370254Y5277D02*
Y1664D01*
G01X371314Y4837D02*
Y1224D01*
G01X370254Y1664D02*
X369642Y1052D01*
G01X371314Y1224D02*
X370082Y-8D01*
G01X369642Y1052D02*
X368198D01*
G01X370082Y-8D02*
X367758D01*
G01X368198Y1052D02*
X367585Y1665D01*
G01X367758Y-8D02*
X366525Y1225D01*
G01X367585Y1665D02*
Y5793D01*
G01X366525Y1225D02*
Y5353D01*
G01X367585Y5793D02*
X366189Y7189D01*
G01X366525Y5353D02*
X365749Y6129D01*
G01X366189Y7189D02*
X358259D01*
G01X365749Y6129D02*
X358699D01*
G01X358259Y7189D02*
X356986Y5916D01*
G01X358699Y6129D02*
X358046Y5476D01*
G01X356986Y5916D02*
Y3137D01*
G01X358046Y5476D02*
Y3577D01*
G01X356986Y3137D02*
X358196Y1927D01*
G01X358046Y3577D02*
X358636Y2987D01*
G01X358196Y1927D02*
X361590D01*
G01X358636Y2987D02*
X362030D01*
G01X361590Y1927D02*
X362286Y1231D01*
G01X362030Y2987D02*
X363346Y1671D01*
G01X362286Y1231D02*
Y-790D01*
G01X363346Y1671D02*
Y-639D01*
G01X370312Y43320D02*
Y26807D01*
G01X371372Y42880D02*
Y26367D01*
G01X370312Y26807D02*
X368885Y25380D01*
G01X371372Y26367D02*
X369325Y24320D01*
G01X368885Y25380D02*
X363734D01*
G01X369325Y24320D02*
X364174D01*
G01X363734Y25380D02*
X359897Y21543D01*
G01X364174Y24320D02*
X360957Y21103D01*
G01X359897Y21543D02*
Y15083D01*
G01X360957Y21103D02*
Y15523D01*
G01X359897Y15083D02*
X362286Y12694D01*
G01X360957Y15523D02*
X363346Y13134D01*
G01X362286Y12694D02*
Y10182D01*
G01X363346Y13134D02*
Y10333D01*
G01X383852Y38820D02*
Y7101D01*
G01X382792Y39260D02*
Y7541D01*
G01X383852Y7101D02*
X380191Y3440D01*
G01X382792Y7541D02*
X379751Y4500D01*
G01X380191Y3440D02*
X376232D01*
G01X379751Y4500D02*
X375792D01*
G01X376232Y3440D02*
X374352Y1560D01*
G01X375792Y4500D02*
X373292Y2000D01*
G01X374352Y1560D02*
Y-2847D01*
G01X373292Y2000D02*
Y-2407D01*
G01X374352Y-2847D02*
X370534Y-6665D01*
G01X373292Y-2407D02*
X370094Y-5605D01*
G01X370534Y-6665D02*
X364245D01*
G01X370094Y-5605D02*
X363805D01*
G01X364245Y-6665D02*
X363346Y-7564D01*
G01X363805Y-5605D02*
X362286Y-7124D01*
G01X363346Y-7564D02*
Y-8567D01*
G01X362286Y-7124D02*
Y-8718D01*
G01X374872Y41080D02*
Y23896D01*
G01X373812Y41520D02*
Y24336D01*
G01X374872Y23896D02*
X370796Y19820D01*
G01X373812Y24336D02*
X370356Y20880D01*
G01X370796Y19820D02*
X365050D01*
G01X370356Y20880D02*
X364610D01*
G01X365050Y19820D02*
X364355Y19125D01*
G01X364610Y20880D02*
X363295Y19565D01*
G01X364355Y19125D02*
Y17998D01*
G01X363295Y19565D02*
Y17647D01*
G01X378846Y40954D02*
Y10901D01*
G01X377786Y41394D02*
Y11341D01*
G01X378846Y10901D02*
X376794Y8849D01*
G01X377786Y11341D02*
X376354Y9909D01*
G01X376794Y8849D02*
X375326D01*
G01X376354Y9909D02*
X374886D01*
G01X376794Y8849D02*
X375326D01*
G01D02*
X371314Y4837D01*
G01X374886Y9909D02*
X370254Y5277D01*
G01X371314Y4837D02*
Y1224D01*
G01X370254Y5277D02*
Y1664D01*
G01X371314Y1224D02*
X370082Y-8D01*
G01X370254Y1664D02*
X369642Y1052D01*
G01X370082Y-8D02*
X367758D01*
G01X369642Y1052D02*
X368198D01*
G01X367758Y-8D02*
X366525Y1225D01*
G01X368198Y1052D02*
X367585Y1665D01*
G01X366525Y1225D02*
Y5353D01*
G01X367585Y1665D02*
Y5793D01*
G01X366525Y5353D02*
X365749Y6129D01*
G01X367585Y5793D02*
X366189Y7189D01*
G01X365749Y6129D02*
X358699D01*
G01X366189Y7189D02*
X358259D01*
G01X358699Y6129D02*
X358046Y5476D01*
G01X358259Y7189D02*
X356986Y5916D01*
G01X358046Y5476D02*
Y3577D01*
G01X356986Y5916D02*
Y3137D01*
G01X358046Y3577D02*
X358636Y2987D01*
G01X356986Y3137D02*
X358196Y1927D01*
G01X358636Y2987D02*
X362030D01*
G01X358196Y1927D02*
X361590D01*
G01X362030Y2987D02*
X363346Y1671D01*
G01X361590Y1927D02*
X362286Y1231D01*
G01X363346Y1671D02*
Y-639D01*
G01X362286Y1231D02*
Y-790D01*
G01X371372Y42880D02*
Y26367D01*
G01X370312Y43320D02*
Y26807D01*
G01X371372Y26367D02*
X369325Y24320D01*
G01X370312Y26807D02*
X368885Y25380D01*
G01X369325Y24320D02*
X364174D01*
G01X368885Y25380D02*
X363734D01*
G01X364174Y24320D02*
X360957Y21103D01*
G01X363734Y25380D02*
X359897Y21543D01*
G01X360957Y21103D02*
Y15523D01*
G01X359897Y21543D02*
Y15083D01*
G01X360957Y15523D02*
X363346Y13134D01*
G01X359897Y15083D02*
X362286Y12694D01*
G01X363346Y13134D02*
Y10333D01*
G01X362286Y12694D02*
Y10182D01*
G01X381512Y104160D02*
Y80280D01*
G01X382572Y104600D02*
Y80720D01*
G01X381512Y80280D02*
X382732Y79060D01*
G01X382572Y80720D02*
X383792Y79500D01*
G01X382732Y79060D02*
Y46060D01*
G01X383792Y79500D02*
Y46500D01*
G01X382732Y46060D02*
X383992Y44800D01*
G01X383792Y46500D02*
X385052Y45240D01*
G01X383992Y44800D02*
Y40460D01*
G01X385052Y45240D02*
Y40020D01*
G01X383992Y40460D02*
X382792Y39260D01*
G01X385052Y40020D02*
X383852Y38820D01*
G01X370718Y188688D02*
Y84617D01*
G01X371778Y188688D02*
Y84177D01*
G01X370718Y84617D02*
X370108Y84007D01*
G01X371778Y84177D02*
X370548Y82947D01*
G01X370108Y84007D02*
X366962D01*
G01X370548Y82947D02*
X367402D01*
G01X366962Y84007D02*
X365761Y82806D01*
G01X367402Y82947D02*
X366821Y82366D01*
G01X365761Y82806D02*
Y80536D01*
G01X366821Y82366D02*
Y80976D01*
G01X365761Y80536D02*
X367020Y79277D01*
G01X366821Y80976D02*
X367460Y80337D01*
G01X367020Y79277D02*
X370108D01*
G01X367460Y80337D02*
X370548D01*
G01X370108Y79277D02*
X370718Y78667D01*
G01X370548Y80337D02*
X371778Y79107D01*
G01X370718Y78667D02*
Y61774D01*
G01X371778Y79107D02*
Y62214D01*
G01X370718Y61774D02*
X373812Y58680D01*
G01X371778Y62214D02*
X374872Y59120D01*
G01X373812Y58680D02*
Y54130D01*
G01X374872Y59120D02*
Y54570D01*
G01X373812Y54130D02*
X376032Y51910D01*
G01X374872Y54570D02*
X377092Y52350D01*
G01X376032Y51910D02*
Y43740D01*
G01X377092Y52350D02*
Y43300D01*
G01X376032Y43740D02*
X373812Y41520D01*
G01X377092Y43300D02*
X374872Y41080D01*
G01X377786Y102183D02*
Y55206D01*
G01X378846Y102623D02*
Y55646D01*
G01X377786Y55206D02*
X378832Y54160D01*
G01X378846Y55646D02*
X379892Y54600D01*
G01X378832Y54160D02*
Y42440D01*
G01X379892Y54600D02*
Y42000D01*
G01X378832Y42440D02*
X377786Y41394D01*
G01X379892Y42000D02*
X378846Y40954D01*
G01X359670Y95307D02*
Y85693D01*
G01X360730Y94867D02*
Y86133D01*
G01X359670Y85693D02*
X361332Y84031D01*
G01X360730Y86133D02*
X362392Y84471D01*
G01X361332Y84031D02*
Y71660D01*
G01X362392Y84471D02*
Y72100D01*
G01X361332Y71660D02*
X363992Y69000D01*
G01X362392Y72100D02*
X365052Y69440D01*
G01X363992Y69000D02*
Y62400D01*
G01X365052Y69440D02*
Y62840D01*
G01X363992Y62400D02*
X370312Y56080D01*
G01X365052Y62840D02*
X371372Y56520D01*
G01X370312Y56080D02*
Y53330D01*
G01X371372Y56520D02*
Y53770D01*
G01X370312Y53330D02*
X372932Y50710D01*
G01X371372Y53770D02*
X373992Y51150D01*
G01X372932Y50710D02*
Y45940D01*
G01X373992Y51150D02*
Y45500D01*
G01X372932Y45940D02*
X370312Y43320D01*
G01X373992Y45500D02*
X371372Y42880D01*
G01X382572Y104600D02*
Y80720D01*
G01X381512Y104160D02*
Y80280D01*
G01X382572Y80720D02*
X383792Y79500D01*
G01X381512Y80280D02*
X382732Y79060D01*
G01X383792Y79500D02*
Y46500D01*
G01X382732Y79060D02*
Y46060D01*
G01X383792Y46500D02*
X385052Y45240D01*
G01X382732Y46060D02*
X383992Y44800D01*
G01X385052Y45240D02*
Y40020D01*
G01X383992Y44800D02*
Y40460D01*
G01X385052Y40020D02*
X383852Y38820D01*
G01X383992Y40460D02*
X382792Y39260D01*
G01X371778Y188688D02*
Y84177D01*
G01X370718Y188688D02*
Y84617D01*
G01X371778Y84177D02*
X370548Y82947D01*
G01X370718Y84617D02*
X370108Y84007D01*
G01X370548Y82947D02*
X367402D01*
G01X370108Y84007D02*
X366962D01*
G01X367402Y82947D02*
X366821Y82366D01*
G01X366962Y84007D02*
X365761Y82806D01*
G01X366821Y82366D02*
Y80976D01*
G01X365761Y82806D02*
Y80536D01*
G01X366821Y80976D02*
X367460Y80337D01*
G01X365761Y80536D02*
X367020Y79277D01*
G01X367460Y80337D02*
X370548D01*
G01X367020Y79277D02*
X370108D01*
G01X370548Y80337D02*
X371778Y79107D01*
G01X370108Y79277D02*
X370718Y78667D01*
G01X371778Y79107D02*
Y62214D01*
G01X370718Y78667D02*
Y61774D01*
G01X371778Y62214D02*
X374872Y59120D01*
G01X370718Y61774D02*
X373812Y58680D01*
G01X374872Y59120D02*
Y54570D01*
G01X373812Y58680D02*
Y54130D01*
G01X374872Y54570D02*
X377092Y52350D01*
G01X373812Y54130D02*
X376032Y51910D01*
G01X377092Y52350D02*
Y43300D01*
G01X376032Y51910D02*
Y43740D01*
G01X377092Y43300D02*
X374872Y41080D01*
G01X376032Y43740D02*
X373812Y41520D01*
G01X378846Y102623D02*
Y55646D01*
G01X377786Y102183D02*
Y55206D01*
G01X378846Y55646D02*
X379892Y54600D01*
G01X377786Y55206D02*
X378832Y54160D01*
G01X379892Y54600D02*
Y42000D01*
G01X378832Y54160D02*
Y42440D01*
G01X379892Y42000D02*
X378846Y40954D01*
G01X378832Y42440D02*
X377786Y41394D01*
G01X360730Y94867D02*
Y86133D01*
G01X359670Y95307D02*
Y85693D01*
G01X360730Y86133D02*
X362392Y84471D01*
G01X359670Y85693D02*
X361332Y84031D01*
G01X362392Y84471D02*
Y72100D01*
G01X361332Y84031D02*
Y71660D01*
G01X362392Y72100D02*
X365052Y69440D01*
G01X361332Y71660D02*
X363992Y69000D01*
G01X365052Y69440D02*
Y62840D01*
G01X363992Y69000D02*
Y62400D01*
G01X365052Y62840D02*
X371372Y56520D01*
G01X363992Y62400D02*
X370312Y56080D01*
G01X371372Y56520D02*
Y53770D01*
G01X370312Y56080D02*
Y53330D01*
G01X371372Y53770D02*
X373992Y51150D01*
G01X370312Y53330D02*
X372932Y50710D01*
G01X373992Y51150D02*
Y45500D01*
G01X372932Y50710D02*
Y45940D01*
G01X373992Y45500D02*
X371372Y42880D01*
G01X372932Y45940D02*
X370312Y43320D01*
G01X377368Y189302D02*
Y108304D01*
G01X378428Y189302D02*
Y108744D01*
G01X377368Y108304D02*
X381512Y104160D01*
G01X378428Y108744D02*
X382572Y104600D01*
G01X374068Y189367D02*
Y105901D01*
G01X375128Y189209D02*
Y106341D01*
G01X374068Y105901D02*
X377786Y102183D01*
G01X375128Y106341D02*
X378846Y102623D01*
G01X367418Y196219D02*
Y103055D01*
G01X368478Y196219D02*
Y102615D01*
G01X367418Y103055D02*
X359670Y95307D01*
G01X368478Y102615D02*
X360730Y94867D01*
G01X378428Y189302D02*
Y108744D01*
G01X377368Y189302D02*
Y108304D01*
G01X378428Y108744D02*
X382572Y104600D01*
G01X377368Y108304D02*
X381512Y104160D01*
G01X375128Y189209D02*
Y106341D01*
G01X374068Y189367D02*
Y105901D01*
G01X375128Y106341D02*
X378846Y102623D01*
G01X374068Y105901D02*
X377786Y102183D01*
G01X368478Y196219D02*
Y102615D01*
G01X367418Y196219D02*
Y103055D01*
G01X368478Y102615D02*
X360730Y94867D01*
G01X367418Y103055D02*
X359670Y95307D01*
G01X372472Y401501D02*
Y404948D01*
G01X371412Y401381D02*
Y405391D01*
G01X365776Y401397D02*
Y407652D01*
G01X364716Y401277D02*
Y408095D01*
G01X375872Y401579D02*
Y403648D01*
G01X374812Y401699D02*
Y404091D01*
G01X369147Y401923D02*
Y406326D01*
G01X368087Y406766D02*
Y401923D01*
G01X371412Y401381D02*
Y405391D01*
G01X372472Y401501D02*
Y404948D01*
G01X364716Y401277D02*
Y408095D01*
G01X365776Y401397D02*
Y407652D01*
G01X374812Y401699D02*
Y404091D01*
G01X375872Y401579D02*
Y403648D01*
G01X368087Y406766D02*
Y401923D01*
G01X369147D02*
Y406326D01*
G01X372472Y404948D02*
X373572Y406048D01*
G01X371412Y405391D02*
X372512Y406491D01*
G01X373572Y406048D02*
Y495808D01*
G01X372512Y406491D02*
Y496248D01*
G01X365776Y407652D02*
X366972Y408848D01*
G01X364716Y408095D02*
X365912Y409291D01*
G01X366972Y408848D02*
Y499048D01*
G01X365912Y409291D02*
Y499488D01*
G01X375872Y403648D02*
X377072Y404848D01*
G01X374812Y404091D02*
X376012Y405291D01*
G01X377072Y404848D02*
Y494448D01*
G01X376012Y405291D02*
Y494888D01*
G01X370272Y407449D02*
Y497551D01*
G01X369212Y497991D02*
Y407891D01*
G01X369147Y406326D02*
X370269Y407448D01*
G01X369212Y407891D02*
X368087Y406766D01*
G01X371412Y405391D02*
X372512Y406491D01*
G01X372472Y404948D02*
X373572Y406048D01*
G01X372512Y406491D02*
Y496248D01*
G01X373572Y406048D02*
Y495808D01*
G01X364716Y408095D02*
X365912Y409291D01*
G01X365776Y407652D02*
X366972Y408848D01*
G01X365912Y409291D02*
Y499488D01*
G01X366972Y408848D02*
Y499048D01*
G01X374812Y404091D02*
X376012Y405291D01*
G01X375872Y403648D02*
X377072Y404848D01*
G01X376012Y405291D02*
Y494888D01*
G01X377072Y404848D02*
Y494448D01*
G01X369212Y407891D02*
X368087Y406766D01*
G01X369147Y406326D02*
X370269Y407448D01*
G01X369212Y497991D02*
Y407891D01*
G01X370272Y407449D02*
Y497551D01*
G01X373572Y495808D02*
X377760Y499996D01*
G01X372512Y496248D02*
X376700Y500436D01*
G01X377760Y499996D02*
Y510444D01*
G01X376700Y500436D02*
Y510884D01*
G01X377760Y510444D02*
X379659Y512343D01*
G01X376700Y510884D02*
X378599Y512783D01*
G01X379659Y512343D02*
Y595903D01*
G01X378599Y512783D02*
Y520701D01*
G01X379659Y512343D02*
Y595903D01*
G01X378599Y523427D02*
Y525257D01*
G01X379659Y512343D02*
Y595903D01*
G01Y512343D02*
Y595903D01*
G01Y512343D02*
Y595903D01*
G01Y512343D02*
Y595903D01*
G01Y512343D02*
Y595903D01*
G01Y512343D02*
Y595903D01*
G01X366972Y499048D02*
X369792Y501868D01*
G01X365912Y499488D02*
X368732Y502308D01*
G01X369792Y501868D02*
Y511377D01*
G01Y513889D02*
Y515808D01*
G01Y518534D02*
Y520364D01*
G01Y523090D02*
Y524920D01*
G01X368732Y502308D02*
Y525360D01*
G01X369792Y524920D02*
X371072Y526200D01*
G01X368732Y525360D02*
X370012Y526640D01*
G01X371072Y526200D02*
Y530236D01*
G01X377072Y494448D02*
X381665Y499041D01*
G01X376012Y494888D02*
X380605Y499481D01*
G01X381665Y499041D02*
Y508653D01*
G01X380605Y499481D02*
Y509093D01*
G01X381665Y508653D02*
X383133Y510121D01*
G01X380605Y509093D02*
X382073Y510561D01*
G01X383133Y510121D02*
Y553539D01*
G01X382073Y510561D02*
Y533775D01*
G01X383133Y510121D02*
Y553539D01*
G01Y510121D02*
Y553539D01*
G01Y510121D02*
Y553539D01*
G01Y510121D02*
Y553539D01*
G01X374845Y524573D02*
Y547252D01*
G01Y524573D02*
Y547252D01*
G01X373785Y526843D02*
Y525013D01*
G01X373392Y523120D02*
X374845Y524573D01*
G01X373785Y525013D02*
X372332Y523560D01*
G01X373392Y500671D02*
Y523120D01*
G01X372332Y523560D02*
Y510223D01*
G01X373392Y500671D02*
Y523120D01*
G01X372332Y507497D02*
Y505667D01*
G01X373392Y500671D02*
Y523120D01*
G01X372332Y502941D02*
Y501111D01*
G01X370272Y497551D02*
X373392Y500671D01*
G01X372332Y501111D02*
X369212Y497991D01*
G01X372512Y496248D02*
X376700Y500436D01*
G01X373572Y495808D02*
X377760Y499996D01*
G01X376700Y500436D02*
Y510884D01*
G01X377760Y499996D02*
Y510444D01*
G01X376700Y510884D02*
X378599Y512783D01*
G01X377760Y510444D02*
X379659Y512343D01*
G01X378599Y512783D02*
Y520701D01*
G01Y523427D02*
Y525257D01*
G01X379659Y512343D02*
Y595903D01*
G01X365912Y499488D02*
X368732Y502308D01*
G01X366972Y499048D02*
X369792Y501868D01*
G01X368732Y502308D02*
Y525360D01*
G01X369792Y501868D02*
Y511377D01*
G01X368732Y502308D02*
Y525360D01*
G01X369792Y513889D02*
Y515808D01*
G01X368732Y502308D02*
Y525360D01*
G01X369792Y518534D02*
Y520364D01*
G01X368732Y502308D02*
Y525360D01*
G01X369792Y523090D02*
Y524920D01*
G01X368732Y525360D02*
X370012Y526640D01*
G01X369792Y524920D02*
X371072Y526200D01*
G01D02*
Y530236D01*
G01X376012Y494888D02*
X380605Y499481D01*
G01X377072Y494448D02*
X381665Y499041D01*
G01X380605Y499481D02*
Y509093D01*
G01X381665Y499041D02*
Y508653D01*
G01X380605Y509093D02*
X382073Y510561D01*
G01X381665Y508653D02*
X383133Y510121D01*
G01X382073Y510561D02*
Y533775D01*
G01X383133Y510121D02*
Y553539D01*
G01X372332Y501111D02*
X369212Y497991D01*
G01X370272Y497551D02*
X373392Y500671D01*
G01X372332Y523560D02*
Y510223D01*
G01Y507497D02*
Y505667D01*
G01Y502941D02*
Y501111D01*
G01X373392Y500671D02*
Y523120D01*
G01X373785Y525013D02*
X372332Y523560D01*
G01X373392Y523120D02*
X374845Y524573D01*
G01X373785Y526843D02*
Y525013D01*
G01X374845Y524573D02*
Y547252D01*
G01X378599Y527983D02*
Y529813D01*
G01Y532539D02*
Y534369D01*
G01Y537095D02*
Y572588D01*
G01Y575314D02*
Y586351D01*
G01X371072Y532962D02*
Y534792D01*
G01Y537518D02*
Y539348D01*
G01Y542074D02*
Y543904D01*
G01Y546630D02*
Y548460D01*
G01X370012Y526640D02*
Y548900D01*
G01X371072Y548460D02*
X372992Y550380D01*
G01X370012Y548900D02*
X371932Y550820D01*
G01X372992Y550380D02*
Y558300D01*
G01X371932Y550820D02*
Y557860D01*
G01X372992Y558300D02*
X371072Y560220D01*
G01X371932Y557860D02*
X370012Y559780D01*
G01X371072Y560220D02*
Y564199D01*
G01Y566925D02*
Y568809D01*
G01Y571427D02*
Y575053D01*
G01X370012Y559780D02*
Y574613D01*
G01X371072Y575053D02*
X368668Y577457D01*
G01X366936Y579189D02*
X364953Y581172D01*
G01X370012Y574613D02*
X364513Y580112D01*
G01X364953Y581172D02*
X361462D01*
G01X364513Y580112D02*
X361022D01*
G01X361462Y581172D02*
X359813Y582821D01*
G01X361022Y580112D02*
X358753Y582381D01*
G01X359813Y582821D02*
Y596658D01*
G01X358753Y582381D02*
Y597098D01*
G01X382073Y536501D02*
Y538331D01*
G01Y541057D02*
Y542887D01*
G01Y545613D02*
Y547443D01*
G01Y550169D02*
Y553099D01*
G01X383133Y553539D02*
X382692Y553980D01*
G01X382073Y553099D02*
X381632Y553540D01*
G01X382692Y553980D02*
Y559600D01*
G01X381632Y553540D02*
Y560040D01*
G01X382692Y559600D02*
X383025Y559933D01*
G01X381632Y560040D02*
X381965Y560373D01*
G01X383025Y559933D02*
Y607229D01*
G01X381965Y560373D02*
Y597677D01*
G01X383025Y559933D02*
Y607229D01*
G01Y559933D02*
Y607229D01*
G01X362310Y588618D02*
Y586506D01*
G01X363370Y586609D02*
Y588178D01*
G01D02*
X364592Y589400D01*
G01X375092Y587869D02*
X372501Y590460D01*
G01X372061Y589400D02*
X374032Y587429D01*
G01X375092Y572800D02*
Y587869D01*
G01X374032Y587429D02*
Y585129D01*
G01X375092Y572800D02*
Y587869D01*
G01X374032Y582403D02*
Y580573D01*
G01X375092Y572800D02*
Y587869D01*
G01X374032Y577847D02*
Y572360D01*
G01X376792Y571100D02*
X375092Y572800D01*
G01X374032Y572360D02*
X375732Y570660D01*
G01X376792Y549199D02*
Y571100D01*
G01X375732Y570660D02*
Y568830D01*
G01X376792Y549199D02*
Y571100D01*
G01X375732Y566104D02*
Y561273D01*
G01X376792Y549199D02*
Y571100D01*
G01X375732Y558547D02*
Y556717D01*
G01X376792Y549199D02*
Y571100D01*
G01X375732Y553991D02*
Y549639D01*
G01X374845Y547252D02*
X376792Y549199D01*
G01X375732Y549639D02*
X373785Y547692D01*
G01D02*
Y529569D01*
G01X378599Y527983D02*
Y529813D01*
G01Y532539D02*
Y534369D01*
G01Y537095D02*
Y572588D01*
G01Y575314D02*
Y586351D01*
G01X370012Y526640D02*
Y548900D01*
G01Y526640D02*
Y548900D01*
G01X371072Y532962D02*
Y534792D01*
G01X370012Y526640D02*
Y548900D01*
G01X371072Y537518D02*
Y539348D01*
G01X370012Y526640D02*
Y548900D01*
G01X371072Y542074D02*
Y543904D01*
G01X370012Y526640D02*
Y548900D01*
G01X371072Y546630D02*
Y548460D01*
G01X370012Y548900D02*
X371932Y550820D01*
G01X371072Y548460D02*
X372992Y550380D01*
G01X371932Y550820D02*
Y557860D01*
G01X372992Y550380D02*
Y558300D01*
G01X371932Y557860D02*
X370012Y559780D01*
G01X372992Y558300D02*
X371072Y560220D01*
G01X370012Y559780D02*
Y574613D01*
G01X371072Y560220D02*
Y564199D01*
G01X370012Y559780D02*
Y574613D01*
G01X371072Y566925D02*
Y568809D01*
G01X370012Y559780D02*
Y574613D01*
G01X371072Y571427D02*
Y575053D01*
G01X370012Y574613D02*
X364513Y580112D01*
G01X371072Y575053D02*
X368668Y577457D01*
G01X370012Y574613D02*
X364513Y580112D01*
G01X366936Y579189D02*
X364953Y581172D01*
G01X364513Y580112D02*
X361022D01*
G01X364953Y581172D02*
X361462D01*
G01X361022Y580112D02*
X358753Y582381D01*
G01X361462Y581172D02*
X359813Y582821D01*
G01X358753Y582381D02*
Y597098D01*
G01X359813Y582821D02*
Y596658D01*
G01X382073Y536501D02*
Y538331D01*
G01Y541057D02*
Y542887D01*
G01Y545613D02*
Y547443D01*
G01Y550169D02*
Y553099D01*
G01D02*
X381632Y553540D01*
G01X383133Y553539D02*
X382692Y553980D01*
G01X381632Y553540D02*
Y560040D01*
G01X382692Y553980D02*
Y559600D01*
G01X381632Y560040D02*
X381965Y560373D01*
G01X382692Y559600D02*
X383025Y559933D01*
G01X381965Y560373D02*
Y597677D01*
G01X383025Y559933D02*
Y607229D01*
G01X373785Y547692D02*
Y529569D01*
G01X375732Y549639D02*
X373785Y547692D01*
G01X374845Y547252D02*
X376792Y549199D01*
G01X375732Y570660D02*
Y568830D01*
G01Y566104D02*
Y561273D01*
G01Y558547D02*
Y556717D01*
G01Y553991D02*
Y549639D01*
G01X376792Y549199D02*
Y571100D01*
G01X374032Y572360D02*
X375732Y570660D01*
G01X376792Y571100D02*
X375092Y572800D01*
G01X374032Y587429D02*
Y585129D01*
G01Y582403D02*
Y580573D01*
G01Y577847D02*
Y572360D01*
G01X375092Y572800D02*
Y587869D01*
G01X372061Y589400D02*
X374032Y587429D01*
G01X375092Y587869D02*
X372501Y590460D01*
G01X363370Y588178D02*
X364592Y589400D01*
G01X363370Y586609D02*
Y588178D01*
G01X362310Y588618D02*
Y586506D01*
G01X378599Y589077D02*
Y590907D01*
G01Y593633D02*
Y595463D01*
G01X379659Y595903D02*
X377769Y597793D01*
G01X378599Y595463D02*
X377329Y596733D01*
G01X377769Y597793D02*
X367525D01*
G01X377329Y596733D02*
X371552D01*
G01X377769Y597793D02*
X367525D01*
G01X369040Y596733D02*
X367085D01*
G01X367525Y597793D02*
X366913Y598405D01*
G01X367085Y596733D02*
X365853Y597965D01*
G01X366913Y598405D02*
Y600397D01*
G01X365853Y597965D02*
Y600837D01*
G01X366913Y600397D02*
X367525Y601009D01*
G01X365853Y600837D02*
X367085Y602069D01*
G01X367525Y601009D02*
X374604D01*
G01X367085Y602069D02*
X369023D01*
G01X367525Y601009D02*
X374604D01*
G01X371533Y602069D02*
X374164D01*
G01X374604Y601009D02*
X376286Y602691D01*
G01X374164Y602069D02*
X375226Y603131D01*
G01X376286Y602691D02*
Y607117D01*
G01X375226Y603131D02*
Y606677D01*
G01X376286Y607117D02*
X374474Y608929D01*
G01X375226Y606677D02*
X374034Y607869D01*
G01X374474Y608929D02*
X363863D01*
G01X374034Y607869D02*
X369954D01*
G01X374474Y608929D02*
X363863D01*
G01X367300Y607869D02*
X364303D01*
G01X363863Y608929D02*
X362318Y607384D01*
G01X364303Y607869D02*
X363378Y606944D01*
G01X362318Y607384D02*
Y605714D01*
G01X363378Y606944D02*
Y605801D01*
G01X359813Y596658D02*
X360313Y597158D01*
G01X358753Y597098D02*
X359873Y598218D01*
G01X360313Y597158D02*
X361612D01*
G01X359873Y598218D02*
X362052D01*
G01X361612Y597158D02*
X363097Y595673D01*
G01X362052Y598218D02*
X364157Y596113D01*
G01X363097Y595673D02*
Y594775D01*
G01X364157Y596113D02*
Y594796D01*
G01X381965Y600403D02*
Y602233D01*
G01Y604959D02*
Y606789D01*
G01X383025Y607229D02*
X373212Y617042D01*
G01X381965Y606789D02*
X379216Y609538D01*
G01X383025Y607229D02*
X373212Y617042D01*
G01X377288Y611466D02*
X375994Y612760D01*
G01X383025Y607229D02*
X373212Y617042D01*
G01X374066Y614688D02*
X372772Y615982D01*
G01X373212Y617042D02*
X363920D01*
G01X372772Y615982D02*
X369853D01*
G01X373212Y617042D02*
X363920D01*
G01X367271Y615982D02*
X364360D01*
G01X363920Y617042D02*
X362212Y615334D01*
G01X364360Y615982D02*
X363272Y614894D01*
G01X362212Y615334D02*
Y613236D01*
G01X363272Y614894D02*
Y613535D01*
G01X364152Y590460D02*
X362310Y588618D01*
G01X372501Y590460D02*
X364152D01*
G01X364592Y589400D02*
X366656D01*
G01X372501Y590460D02*
X364152D01*
G01X369382Y589400D02*
X372061D01*
G01X378599Y589077D02*
Y590907D01*
G01Y593633D02*
Y595463D01*
G01D02*
X377329Y596733D01*
G01X379659Y595903D02*
X377769Y597793D01*
G01X377329Y596733D02*
X371552D01*
G01X369040D02*
X367085D01*
G01X377769Y597793D02*
X367525D01*
G01X367085Y596733D02*
X365853Y597965D01*
G01X367525Y597793D02*
X366913Y598405D01*
G01X365853Y597965D02*
Y600837D01*
G01X366913Y598405D02*
Y600397D01*
G01X365853Y600837D02*
X367085Y602069D01*
G01X366913Y600397D02*
X367525Y601009D01*
G01X367085Y602069D02*
X369023D01*
G01X371533D02*
X374164D01*
G01X367525Y601009D02*
X374604D01*
G01X374164Y602069D02*
X375226Y603131D01*
G01X374604Y601009D02*
X376286Y602691D01*
G01X375226Y603131D02*
Y606677D01*
G01X376286Y602691D02*
Y607117D01*
G01X375226Y606677D02*
X374034Y607869D01*
G01X376286Y607117D02*
X374474Y608929D01*
G01X374034Y607869D02*
X369954D01*
G01X367300D02*
X364303D01*
G01X374474Y608929D02*
X363863D01*
G01X364303Y607869D02*
X363378Y606944D01*
G01X363863Y608929D02*
X362318Y607384D01*
G01X363378Y606944D02*
Y605801D01*
G01X362318Y607384D02*
Y605714D01*
G01X358753Y597098D02*
X359873Y598218D01*
G01X359813Y596658D02*
X360313Y597158D01*
G01X359873Y598218D02*
X362052D01*
G01X360313Y597158D02*
X361612D01*
G01X362052Y598218D02*
X364157Y596113D01*
G01X361612Y597158D02*
X363097Y595673D01*
G01X364157Y596113D02*
Y594796D01*
G01X363097Y595673D02*
Y594775D01*
G01X381965Y600403D02*
Y602233D01*
G01Y604959D02*
Y606789D01*
G01D02*
X379216Y609538D01*
G01X377288Y611466D02*
X375994Y612760D01*
G01X374066Y614688D02*
X372772Y615982D01*
G01X383025Y607229D02*
X373212Y617042D01*
G01X372772Y615982D02*
X369853D01*
G01X367271D02*
X364360D01*
G01X373212Y617042D02*
X363920D01*
G01X364360Y615982D02*
X363272Y614894D01*
G01X363920Y617042D02*
X362212Y615334D01*
G01X363272Y614894D02*
Y613535D01*
G01X362212Y615334D02*
Y613236D01*
G01X364592Y589400D02*
X366656D01*
G01X369382D02*
X372061D01*
G01X372501Y590460D02*
X364152D01*
G01D02*
X362310Y588618D01*
G01X464732Y87300D02*
X465831D01*
G01D02*
X466778Y86353D01*
G01X464732Y89900D02*
X467838Y86794D01*
G01X466778Y86353D02*
Y83820D01*
G01Y79680D02*
Y78720D01*
G01Y74380D02*
Y71091D01*
G01X467838Y86794D02*
Y70648D01*
G01X466778Y71091D02*
X466067Y70380D01*
G01X467838Y70648D02*
X466510Y69320D01*
G01X466067Y70380D02*
X465551D01*
G01X466510Y69320D02*
X465528D01*
G01X469832Y90114D02*
X473024Y86922D01*
G01X469832Y87515D02*
X470930D01*
G01X469832Y90114D02*
X473024Y86922D01*
G01X470930Y87515D02*
X471964Y86481D01*
G01X473024Y86922D02*
Y71532D01*
G01X471964Y86481D02*
Y83706D01*
G01X473024Y86922D02*
Y71532D01*
G01X471964Y79880D02*
Y78507D01*
G01X473024Y86922D02*
Y71532D01*
G01X471964Y74593D02*
Y71972D01*
G01X473024Y71532D02*
X469832Y68340D01*
G01X471964Y71972D02*
X470941Y70949D01*
G01X464732Y89900D02*
X467838Y86794D01*
G01X464732Y87300D02*
X465831D01*
G01X464732Y89900D02*
X467838Y86794D01*
G01X465831Y87300D02*
X466778Y86353D01*
G01X467838Y86794D02*
Y70648D01*
G01X466778Y86353D02*
Y83820D01*
G01X467838Y86794D02*
Y70648D01*
G01X466778Y79680D02*
Y78720D01*
G01X467838Y86794D02*
Y70648D01*
G01X466778Y74380D02*
Y71091D01*
G01X467838Y70648D02*
X466510Y69320D01*
G01X466778Y71091D02*
X466067Y70380D01*
G01X466510Y69320D02*
X465528D01*
G01X466067Y70380D02*
X465551D01*
G01X469832Y87515D02*
X470930D01*
G01D02*
X471964Y86481D01*
G01X469832Y90114D02*
X473024Y86922D01*
G01X471964Y86481D02*
Y83706D01*
G01Y79880D02*
Y78507D01*
G01Y74593D02*
Y71972D01*
G01X473024Y86922D02*
Y71532D01*
G01X471964Y71972D02*
X470941Y70949D01*
G01X473024Y71532D02*
X469832Y68340D01*
G01X428632Y183575D02*
Y141960D01*
G01Y183575D02*
Y141960D01*
G01Y183575D02*
Y141960D01*
G01Y183575D02*
Y141960D01*
G01Y183575D02*
Y141960D01*
G01Y183575D02*
Y141960D01*
G01Y183575D02*
Y141960D01*
G01Y183575D02*
Y141960D01*
G01Y183575D02*
Y141960D01*
G01Y183575D02*
Y141960D01*
G01X429692Y156950D02*
Y155550D01*
G01X428632Y183575D02*
Y141960D01*
G01X429692Y153650D02*
Y152550D01*
G01X428632Y183575D02*
Y141960D01*
G01X429692Y150650D02*
Y142400D01*
G01X428632Y141960D02*
X431170Y139422D01*
G01X429692Y142400D02*
X431610Y140482D01*
G01X428632Y141960D02*
X431170Y139422D01*
G01D02*
X432912D01*
G01X431610Y140482D02*
X432472D01*
G01X432912Y139422D02*
X433861Y140371D01*
G01X432472Y140482D02*
X433421Y141431D01*
G01X433861Y140371D02*
X434721D01*
G01X433421Y141431D02*
X435161D01*
G01X434721Y140371D02*
X435709Y139383D01*
G01X435161Y141431D02*
X436769Y139823D01*
G01X435709Y139383D02*
Y138523D01*
G01X436769Y139823D02*
Y138083D01*
G01X435709Y138523D02*
X434760Y137574D01*
G01X436769Y138083D02*
X435820Y137134D01*
G01X434760Y137574D02*
Y135832D01*
G01X435820Y137134D02*
Y136272D01*
G01X434760Y135832D02*
X436364Y134228D01*
G01X435820Y136272D02*
X436804Y135288D01*
G01X436364Y134228D02*
X438106D01*
G01X436804Y135288D02*
X437666D01*
G01X438106Y134228D02*
X439055Y135177D01*
G01X437666Y135288D02*
X438615Y136237D01*
G01X439055Y135177D02*
X439915D01*
G01X438615Y136237D02*
X440355D01*
G01X439915Y135177D02*
X440903Y134189D01*
G01X440355Y136237D02*
X441963Y134629D01*
G01X440903Y134189D02*
Y133329D01*
G01X441963Y134629D02*
Y132889D01*
G01X440903Y133329D02*
X439954Y132380D01*
G01X441963Y132889D02*
X441014Y131940D01*
G01X439954Y132380D02*
Y130638D01*
G01X441014Y131940D02*
Y131078D01*
G01X439954Y130638D02*
X442922Y127670D01*
G01X441014Y131078D02*
X443362Y128730D01*
G01X439954Y130638D02*
X442922Y127670D01*
G01D02*
X444664D01*
G01X443362Y128730D02*
X444224D01*
G01X444664Y127670D02*
X445363Y128369D01*
G01X444224Y128730D02*
X444923Y129429D01*
G01X445363Y128369D02*
X446223D01*
G01X444923Y129429D02*
X446663D01*
G01X446223Y128369D02*
X447211Y127381D01*
G01X446663Y129429D02*
X448271Y127821D01*
G01X447211Y127381D02*
Y126521D01*
G01X448271Y127821D02*
Y126081D01*
G01X447211Y126521D02*
X446512Y125822D01*
G01X448271Y126081D02*
X447572Y125382D01*
G01X446512Y125822D02*
Y124080D01*
G01X447572Y125382D02*
Y124520D01*
G01X446512Y124080D02*
X448116Y122476D01*
G01X447572Y124520D02*
X448556Y123536D01*
G01X448116Y122476D02*
X449858D01*
G01X448556Y123536D02*
X449418D01*
G01X449858Y122476D02*
X450557Y123175D01*
G01X449418Y123536D02*
X450117Y124235D01*
G01X450557Y123175D02*
X451417D01*
G01X450117Y124235D02*
X451857D01*
G01X451417Y123175D02*
X452405Y122187D01*
G01X451857Y124235D02*
X453465Y122627D01*
G01X452405Y122187D02*
Y121327D01*
G01X453465Y122627D02*
Y120887D01*
G01X452405Y121327D02*
X451706Y120628D01*
G01X453465Y120887D02*
X452766Y120188D01*
G01X451706Y120628D02*
Y118886D01*
G01X452766Y120188D02*
Y119326D01*
G01X451706Y118886D02*
X461992Y108600D01*
G01X452766Y119326D02*
X462432Y109660D01*
G01X461992Y108600D02*
X466532D01*
G01X462432Y109660D02*
X466092D01*
G01X466532Y108600D02*
X467572Y109640D01*
G01X466092Y109660D02*
X467132Y110700D01*
G01X467572Y109640D02*
X473712D01*
G01X467132Y110700D02*
X474152D01*
G01X473712Y109640D02*
X474752Y108600D01*
G01X474152Y110700D02*
X475192Y109660D01*
G01X474752Y108600D02*
X479693D01*
G01X475192Y109660D02*
X480133D01*
G01X457442Y170950D02*
X487592Y140800D01*
G01X457442Y170950D02*
X487592Y140800D01*
G01X457442Y170950D02*
X487592Y140800D01*
G01X457442Y170950D02*
X487592Y140800D01*
G01X457442Y170950D02*
X487592Y140800D01*
G01X457442Y170950D02*
X487592Y140800D01*
G01X457442Y170950D02*
X487592Y140800D01*
G01X471664Y158228D02*
X488032Y141860D01*
G01X433615Y185287D02*
Y148376D01*
G01X432555Y185287D02*
Y147936D01*
G01X433615Y148376D02*
X465731Y116260D01*
G01X432555Y147936D02*
X465291Y115200D01*
G01X465731Y116260D02*
X502661D01*
G01X465291Y115200D02*
X502221D01*
G01X462373Y171820D02*
X489593Y144600D01*
G01X429692Y156950D02*
Y155550D01*
G01Y153650D02*
Y152550D01*
G01Y150650D02*
Y142400D01*
G01X428632Y183575D02*
Y141960D01*
G01X429692Y142400D02*
X431610Y140482D01*
G01D02*
X432472D01*
G01X428632Y141960D02*
X431170Y139422D01*
G01X431610Y140482D02*
X432472D01*
G01X431170Y139422D02*
X432912D01*
G01X432472Y140482D02*
X433421Y141431D01*
G01X432912Y139422D02*
X433861Y140371D01*
G01X433421Y141431D02*
X435161D01*
G01X433861Y140371D02*
X434721D01*
G01X435161Y141431D02*
X436769Y139823D01*
G01X434721Y140371D02*
X435709Y139383D01*
G01X436769Y139823D02*
Y138083D01*
G01X435709Y139383D02*
Y138523D01*
G01X436769Y138083D02*
X435820Y137134D01*
G01X435709Y138523D02*
X434760Y137574D01*
G01X435820Y137134D02*
Y136272D01*
G01X434760Y137574D02*
Y135832D01*
G01X435820Y136272D02*
X436804Y135288D01*
G01X434760Y135832D02*
X436364Y134228D01*
G01X436804Y135288D02*
X437666D01*
G01X436364Y134228D02*
X438106D01*
G01X437666Y135288D02*
X438615Y136237D01*
G01X438106Y134228D02*
X439055Y135177D01*
G01X438615Y136237D02*
X440355D01*
G01X439055Y135177D02*
X439915D01*
G01X440355Y136237D02*
X441963Y134629D01*
G01X439915Y135177D02*
X440903Y134189D01*
G01X441963Y134629D02*
Y132889D01*
G01X440903Y134189D02*
Y133329D01*
G01X441963Y132889D02*
X441014Y131940D01*
G01X440903Y133329D02*
X439954Y132380D01*
G01X441014Y131940D02*
Y131078D01*
G01X439954Y132380D02*
Y130638D01*
G01X441014Y131078D02*
X443362Y128730D01*
G01D02*
X444224D01*
G01X439954Y130638D02*
X442922Y127670D01*
G01X443362Y128730D02*
X444224D01*
G01X442922Y127670D02*
X444664D01*
G01X444224Y128730D02*
X444923Y129429D01*
G01X444664Y127670D02*
X445363Y128369D01*
G01X444923Y129429D02*
X446663D01*
G01X445363Y128369D02*
X446223D01*
G01X446663Y129429D02*
X448271Y127821D01*
G01X446223Y128369D02*
X447211Y127381D01*
G01X448271Y127821D02*
Y126081D01*
G01X447211Y127381D02*
Y126521D01*
G01X448271Y126081D02*
X447572Y125382D01*
G01X447211Y126521D02*
X446512Y125822D01*
G01X447572Y125382D02*
Y124520D01*
G01X446512Y125822D02*
Y124080D01*
G01X447572Y124520D02*
X448556Y123536D01*
G01X446512Y124080D02*
X448116Y122476D01*
G01X448556Y123536D02*
X449418D01*
G01X448116Y122476D02*
X449858D01*
G01X449418Y123536D02*
X450117Y124235D01*
G01X449858Y122476D02*
X450557Y123175D01*
G01X450117Y124235D02*
X451857D01*
G01X450557Y123175D02*
X451417D01*
G01X451857Y124235D02*
X453465Y122627D01*
G01X451417Y123175D02*
X452405Y122187D01*
G01X453465Y122627D02*
Y120887D01*
G01X452405Y122187D02*
Y121327D01*
G01X453465Y120887D02*
X452766Y120188D01*
G01X452405Y121327D02*
X451706Y120628D01*
G01X452766Y120188D02*
Y119326D01*
G01X451706Y120628D02*
Y118886D01*
G01X452766Y119326D02*
X462432Y109660D01*
G01X451706Y118886D02*
X461992Y108600D01*
G01X462432Y109660D02*
X466092D01*
G01X461992Y108600D02*
X466532D01*
G01X466092Y109660D02*
X467132Y110700D01*
G01X466532Y108600D02*
X467572Y109640D01*
G01X467132Y110700D02*
X474152D01*
G01X467572Y109640D02*
X473712D01*
G01X474152Y110700D02*
X475192Y109660D01*
G01X473712Y109640D02*
X474752Y108600D01*
G01X475192Y109660D02*
X480133D01*
G01X474752Y108600D02*
X479693D01*
G01X471664Y158228D02*
X488032Y141860D01*
G01X457442Y170950D02*
X487592Y140800D01*
G01X432555Y185287D02*
Y147936D01*
G01X433615Y185287D02*
Y148376D01*
G01X432555Y147936D02*
X465291Y115200D01*
G01X433615Y148376D02*
X465731Y116260D01*
G01X465291Y115200D02*
X502221D01*
G01X465731Y116260D02*
X502661D01*
G01X462373Y171820D02*
X489593Y144600D01*
G01X462373Y171820D02*
X489593Y144600D01*
G01X462373Y171820D02*
X489593Y144600D01*
G01X428632Y183575D02*
Y141960D01*
G01Y183575D02*
Y141960D01*
G01Y183575D02*
Y141960D01*
G01Y183575D02*
Y141960D01*
G01Y183575D02*
Y141960D01*
G01Y183575D02*
Y141960D01*
G01Y183575D02*
Y141960D01*
G01Y183575D02*
Y141960D01*
G01Y183575D02*
Y141960D01*
G01Y183575D02*
Y141960D01*
G01X429692Y156950D02*
Y155550D01*
G01X428632Y183575D02*
Y141960D01*
G01X429692Y153650D02*
Y152550D01*
G01X428632Y183575D02*
Y141960D01*
G01X429692Y150650D02*
Y142400D01*
G01X428632Y141960D02*
X431170Y139422D01*
G01X429692Y142400D02*
X431610Y140482D01*
G01X428632Y141960D02*
X431170Y139422D01*
G01D02*
X432912D01*
G01X431610Y140482D02*
X432472D01*
G01X432912Y139422D02*
X433861Y140371D01*
G01X432472Y140482D02*
X433421Y141431D01*
G01X433861Y140371D02*
X434721D01*
G01X433421Y141431D02*
X435161D01*
G01X434721Y140371D02*
X435709Y139383D01*
G01X435161Y141431D02*
X436769Y139823D01*
G01X435709Y139383D02*
Y138523D01*
G01X436769Y139823D02*
Y138083D01*
G01X435709Y138523D02*
X434760Y137574D01*
G01X436769Y138083D02*
X435820Y137134D01*
G01X434760Y137574D02*
Y135832D01*
G01X435820Y137134D02*
Y136272D01*
G01X434760Y135832D02*
X436364Y134228D01*
G01X435820Y136272D02*
X436804Y135288D01*
G01X436364Y134228D02*
X438106D01*
G01X436804Y135288D02*
X437666D01*
G01X438106Y134228D02*
X439055Y135177D01*
G01X437666Y135288D02*
X438615Y136237D01*
G01X439055Y135177D02*
X439915D01*
G01X438615Y136237D02*
X440355D01*
G01X439915Y135177D02*
X440903Y134189D01*
G01X440355Y136237D02*
X441963Y134629D01*
G01X440903Y134189D02*
Y133329D01*
G01X441963Y134629D02*
Y132889D01*
G01X440903Y133329D02*
X439954Y132380D01*
G01X441963Y132889D02*
X441014Y131940D01*
G01X439954Y132380D02*
Y130638D01*
G01X441014Y131940D02*
Y131078D01*
G01X439954Y130638D02*
X442922Y127670D01*
G01X441014Y131078D02*
X443362Y128730D01*
G01X439954Y130638D02*
X442922Y127670D01*
G01D02*
X444664D01*
G01X443362Y128730D02*
X444224D01*
G01X444664Y127670D02*
X445363Y128369D01*
G01X444224Y128730D02*
X444923Y129429D01*
G01X445363Y128369D02*
X446223D01*
G01X444923Y129429D02*
X446663D01*
G01X446223Y128369D02*
X447211Y127381D01*
G01X446663Y129429D02*
X448271Y127821D01*
G01X447211Y127381D02*
Y126521D01*
G01X448271Y127821D02*
Y126081D01*
G01X447211Y126521D02*
X446512Y125822D01*
G01X448271Y126081D02*
X447572Y125382D01*
G01X446512Y125822D02*
Y124080D01*
G01X447572Y125382D02*
Y124520D01*
G01X446512Y124080D02*
X448116Y122476D01*
G01X447572Y124520D02*
X448556Y123536D01*
G01X448116Y122476D02*
X449858D01*
G01X448556Y123536D02*
X449418D01*
G01X449858Y122476D02*
X450557Y123175D01*
G01X449418Y123536D02*
X450117Y124235D01*
G01X450557Y123175D02*
X451417D01*
G01X450117Y124235D02*
X451857D01*
G01X451417Y123175D02*
X452405Y122187D01*
G01X451857Y124235D02*
X453465Y122627D01*
G01X452405Y122187D02*
Y121327D01*
G01X453465Y122627D02*
Y120887D01*
G01X452405Y121327D02*
X451706Y120628D01*
G01X453465Y120887D02*
X452766Y120188D01*
G01X451706Y120628D02*
Y118886D01*
G01X452766Y120188D02*
Y119326D01*
G01X451706Y118886D02*
X461992Y108600D01*
G01X452766Y119326D02*
X462432Y109660D01*
G01X461992Y108600D02*
X466532D01*
G01X462432Y109660D02*
X466092D01*
G01X466532Y108600D02*
X467572Y109640D01*
G01X466092Y109660D02*
X467132Y110700D01*
G01X467572Y109640D02*
X473712D01*
G01X467132Y110700D02*
X474152D01*
G01X473712Y109640D02*
X474752Y108600D01*
G01X474152Y110700D02*
X475192Y109660D01*
G01X474752Y108600D02*
X479693D01*
G01X475192Y109660D02*
X480133D01*
G01X457442Y170950D02*
X487592Y140800D01*
G01X457442Y170950D02*
X487592Y140800D01*
G01X457442Y170950D02*
X487592Y140800D01*
G01X457442Y170950D02*
X487592Y140800D01*
G01X457442Y170950D02*
X487592Y140800D01*
G01X457442Y170950D02*
X487592Y140800D01*
G01X457442Y170950D02*
X487592Y140800D01*
G01X471664Y158228D02*
X488032Y141860D01*
G01X433615Y185287D02*
Y148376D01*
G01X432555Y185287D02*
Y147936D01*
G01X433615Y148376D02*
X465731Y116260D01*
G01X432555Y147936D02*
X465291Y115200D01*
G01X465731Y116260D02*
X502661D01*
G01X465291Y115200D02*
X502221D01*
G01X429692Y156950D02*
Y155550D01*
G01Y153650D02*
Y152550D01*
G01Y150650D02*
Y142400D01*
G01X428632Y183575D02*
Y141960D01*
G01X429692Y142400D02*
X431610Y140482D01*
G01D02*
X432472D01*
G01X428632Y141960D02*
X431170Y139422D01*
G01X431610Y140482D02*
X432472D01*
G01X431170Y139422D02*
X432912D01*
G01X432472Y140482D02*
X433421Y141431D01*
G01X432912Y139422D02*
X433861Y140371D01*
G01X433421Y141431D02*
X435161D01*
G01X433861Y140371D02*
X434721D01*
G01X435161Y141431D02*
X436769Y139823D01*
G01X434721Y140371D02*
X435709Y139383D01*
G01X436769Y139823D02*
Y138083D01*
G01X435709Y139383D02*
Y138523D01*
G01X436769Y138083D02*
X435820Y137134D01*
G01X435709Y138523D02*
X434760Y137574D01*
G01X435820Y137134D02*
Y136272D01*
G01X434760Y137574D02*
Y135832D01*
G01X435820Y136272D02*
X436804Y135288D01*
G01X434760Y135832D02*
X436364Y134228D01*
G01X436804Y135288D02*
X437666D01*
G01X436364Y134228D02*
X438106D01*
G01X437666Y135288D02*
X438615Y136237D01*
G01X438106Y134228D02*
X439055Y135177D01*
G01X438615Y136237D02*
X440355D01*
G01X439055Y135177D02*
X439915D01*
G01X440355Y136237D02*
X441963Y134629D01*
G01X439915Y135177D02*
X440903Y134189D01*
G01X441963Y134629D02*
Y132889D01*
G01X440903Y134189D02*
Y133329D01*
G01X441963Y132889D02*
X441014Y131940D01*
G01X440903Y133329D02*
X439954Y132380D01*
G01X441014Y131940D02*
Y131078D01*
G01X439954Y132380D02*
Y130638D01*
G01X441014Y131078D02*
X443362Y128730D01*
G01D02*
X444224D01*
G01X439954Y130638D02*
X442922Y127670D01*
G01X443362Y128730D02*
X444224D01*
G01X442922Y127670D02*
X444664D01*
G01X444224Y128730D02*
X444923Y129429D01*
G01X444664Y127670D02*
X445363Y128369D01*
G01X444923Y129429D02*
X446663D01*
G01X445363Y128369D02*
X446223D01*
G01X446663Y129429D02*
X448271Y127821D01*
G01X446223Y128369D02*
X447211Y127381D01*
G01X448271Y127821D02*
Y126081D01*
G01X447211Y127381D02*
Y126521D01*
G01X448271Y126081D02*
X447572Y125382D01*
G01X447211Y126521D02*
X446512Y125822D01*
G01X447572Y125382D02*
Y124520D01*
G01X446512Y125822D02*
Y124080D01*
G01X447572Y124520D02*
X448556Y123536D01*
G01X446512Y124080D02*
X448116Y122476D01*
G01X448556Y123536D02*
X449418D01*
G01X448116Y122476D02*
X449858D01*
G01X449418Y123536D02*
X450117Y124235D01*
G01X449858Y122476D02*
X450557Y123175D01*
G01X450117Y124235D02*
X451857D01*
G01X450557Y123175D02*
X451417D01*
G01X451857Y124235D02*
X453465Y122627D01*
G01X451417Y123175D02*
X452405Y122187D01*
G01X453465Y122627D02*
Y120887D01*
G01X452405Y122187D02*
Y121327D01*
G01X453465Y120887D02*
X452766Y120188D01*
G01X452405Y121327D02*
X451706Y120628D01*
G01X452766Y120188D02*
Y119326D01*
G01X451706Y120628D02*
Y118886D01*
G01X452766Y119326D02*
X462432Y109660D01*
G01X451706Y118886D02*
X461992Y108600D01*
G01X462432Y109660D02*
X466092D01*
G01X461992Y108600D02*
X466532D01*
G01X466092Y109660D02*
X467132Y110700D01*
G01X466532Y108600D02*
X467572Y109640D01*
G01X467132Y110700D02*
X474152D01*
G01X467572Y109640D02*
X473712D01*
G01X474152Y110700D02*
X475192Y109660D01*
G01X473712Y109640D02*
X474752Y108600D01*
G01X475192Y109660D02*
X480133D01*
G01X474752Y108600D02*
X479693D01*
G01X471664Y158228D02*
X488032Y141860D01*
G01X457442Y170950D02*
X487592Y140800D01*
G01X432555Y185287D02*
Y147936D01*
G01X433615Y185287D02*
Y148376D01*
G01X432555Y147936D02*
X465291Y115200D01*
G01X433615Y148376D02*
X465731Y116260D01*
G01X465291Y115200D02*
X502221D01*
G01X465731Y116260D02*
X502661D01*
G01X462373Y171820D02*
X489593Y144600D01*
G01X462373Y171820D02*
X489593Y144600D01*
G01X462373Y171820D02*
X489593Y144600D01*
G01X462373Y171820D02*
X489593Y144600D01*
G01X429397Y185287D02*
Y184340D01*
G01X430457Y185287D02*
Y183900D01*
G01X429397Y184340D02*
X428632Y183575D01*
G01X430457Y183900D02*
X429692Y183135D01*
G01D02*
Y182050D01*
G01Y180150D02*
Y179150D01*
G01Y177250D02*
Y176250D01*
G01Y174350D02*
Y173350D01*
G01Y171450D02*
Y170450D01*
G01Y168550D02*
Y167550D01*
G01Y165650D02*
Y164650D01*
G01Y162750D02*
Y161752D01*
G01Y159850D02*
Y158850D01*
G01X457442Y189726D02*
Y170950D01*
G01X458502Y189726D02*
Y188726D01*
G01X457442Y189726D02*
Y170950D01*
G01X458502Y186826D02*
Y185650D01*
G01X457442Y189726D02*
Y170950D01*
G01X458502Y183750D02*
Y182750D01*
G01X457442Y189726D02*
Y170950D01*
G01X458502Y180850D02*
Y179850D01*
G01X457442Y189726D02*
Y170950D01*
G01X458502Y177950D02*
Y176650D01*
G01X457442Y189726D02*
Y170950D01*
G01X458502Y174750D02*
Y171390D01*
G01D02*
X459209Y170683D01*
G01X460553Y169339D02*
X461370Y168522D01*
G01X462714Y167178D02*
X463520Y166372D01*
G01X464864Y165028D02*
X465571Y164321D01*
G01X466915Y162977D02*
X467920Y161972D01*
G01X469264Y160628D02*
X470320Y159572D01*
G01X463433Y190613D02*
Y189550D01*
G01Y187650D02*
Y186150D01*
G01Y184250D02*
Y182950D01*
G01Y181050D02*
Y180050D01*
G01Y178150D02*
Y176750D01*
G01Y174850D02*
Y172260D01*
G01X462373Y190613D02*
Y171820D01*
G01X463433Y172260D02*
X464140Y171553D01*
G01D02*
X464776D01*
G01X465484Y170209D02*
X490033Y145660D01*
G01X430457Y185287D02*
Y183900D01*
G01X429397Y185287D02*
Y184340D01*
G01X430457Y183900D02*
X429692Y183135D01*
G01X429397Y184340D02*
X428632Y183575D01*
G01X429692Y183135D02*
Y182050D01*
G01Y180150D02*
Y179150D01*
G01Y177250D02*
Y176250D01*
G01Y174350D02*
Y173350D01*
G01Y171450D02*
Y170450D01*
G01Y168550D02*
Y167550D01*
G01Y165650D02*
Y164650D01*
G01Y162750D02*
Y161752D01*
G01Y159850D02*
Y158850D01*
G01X458502Y189726D02*
Y188726D01*
G01Y186826D02*
Y185650D01*
G01Y183750D02*
Y182750D01*
G01Y180850D02*
Y179850D01*
G01Y177950D02*
Y176650D01*
G01Y174750D02*
Y171390D01*
G01X457442Y189726D02*
Y170950D01*
G01X458502Y171390D02*
X459209Y170683D01*
G01X460553Y169339D02*
X461370Y168522D01*
G01X462714Y167178D02*
X463520Y166372D01*
G01X464864Y165028D02*
X465571Y164321D01*
G01X466915Y162977D02*
X467920Y161972D01*
G01X469264Y160628D02*
X470320Y159572D01*
G01X462373Y190613D02*
Y171820D01*
G01X463433Y190613D02*
Y189550D01*
G01X462373Y190613D02*
Y171820D01*
G01X463433Y187650D02*
Y186150D01*
G01X462373Y190613D02*
Y171820D01*
G01X463433Y184250D02*
Y182950D01*
G01X462373Y190613D02*
Y171820D01*
G01X463433Y181050D02*
Y180050D01*
G01X462373Y190613D02*
Y171820D01*
G01X463433Y178150D02*
Y176750D01*
G01X462373Y190613D02*
Y171820D01*
G01X463433Y174850D02*
Y172260D01*
G01D02*
X464140Y171553D01*
G01D02*
X464776D01*
G01X465484Y170209D02*
X490033Y145660D01*
G01X429397Y185287D02*
Y184340D01*
G01X430457Y185287D02*
Y183900D01*
G01X429397Y184340D02*
X428632Y183575D01*
G01X430457Y183900D02*
X429692Y183135D01*
G01D02*
Y182050D01*
G01Y180150D02*
Y179150D01*
G01Y177250D02*
Y176250D01*
G01Y174350D02*
Y173350D01*
G01Y171450D02*
Y170450D01*
G01Y168550D02*
Y167550D01*
G01Y165650D02*
Y164650D01*
G01Y162750D02*
Y161752D01*
G01Y159850D02*
Y158850D01*
G01X457442Y189726D02*
Y170950D01*
G01X458502Y189726D02*
Y188726D01*
G01X457442Y189726D02*
Y170950D01*
G01X458502Y186826D02*
Y185650D01*
G01X457442Y189726D02*
Y170950D01*
G01X458502Y183750D02*
Y182750D01*
G01X457442Y189726D02*
Y170950D01*
G01X458502Y180850D02*
Y179850D01*
G01X457442Y189726D02*
Y170950D01*
G01X458502Y177950D02*
Y176650D01*
G01X457442Y189726D02*
Y170950D01*
G01X458502Y174750D02*
Y171390D01*
G01D02*
X459209Y170683D01*
G01X460553Y169339D02*
X461370Y168522D01*
G01X462714Y167178D02*
X463520Y166372D01*
G01X464864Y165028D02*
X465571Y164321D01*
G01X466915Y162977D02*
X467920Y161972D01*
G01X469264Y160628D02*
X470320Y159572D01*
G01X430457Y185287D02*
Y183900D01*
G01X429397Y185287D02*
Y184340D01*
G01X430457Y183900D02*
X429692Y183135D01*
G01X429397Y184340D02*
X428632Y183575D01*
G01X429692Y183135D02*
Y182050D01*
G01Y180150D02*
Y179150D01*
G01Y177250D02*
Y176250D01*
G01Y174350D02*
Y173350D01*
G01Y171450D02*
Y170450D01*
G01Y168550D02*
Y167550D01*
G01Y165650D02*
Y164650D01*
G01Y162750D02*
Y161752D01*
G01Y159850D02*
Y158850D01*
G01X458502Y189726D02*
Y188726D01*
G01Y186826D02*
Y185650D01*
G01Y183750D02*
Y182750D01*
G01Y180850D02*
Y179850D01*
G01Y177950D02*
Y176650D01*
G01Y174750D02*
Y171390D01*
G01X457442Y189726D02*
Y170950D01*
G01X458502Y171390D02*
X459209Y170683D01*
G01X460553Y169339D02*
X461370Y168522D01*
G01X462714Y167178D02*
X463520Y166372D01*
G01X464864Y165028D02*
X465571Y164321D01*
G01X466915Y162977D02*
X467920Y161972D01*
G01X469264Y160628D02*
X470320Y159572D01*
G01X463433Y190613D02*
Y189550D01*
G01Y187650D02*
Y186150D01*
G01Y184250D02*
Y182950D01*
G01Y181050D02*
Y180050D01*
G01Y178150D02*
Y176750D01*
G01Y174850D02*
Y172260D01*
G01X462373Y190613D02*
Y171820D01*
G01X463433Y172260D02*
X464140Y171553D01*
G01D02*
X464776D01*
G01X465484Y170209D02*
X490033Y145660D01*
G01X462373Y190613D02*
Y171820D01*
G01X463433Y190613D02*
Y189550D01*
G01X462373Y190613D02*
Y171820D01*
G01X463433Y187650D02*
Y186150D01*
G01X462373Y190613D02*
Y171820D01*
G01X463433Y184250D02*
Y182950D01*
G01X462373Y190613D02*
Y171820D01*
G01X463433Y181050D02*
Y180050D01*
G01X462373Y190613D02*
Y171820D01*
G01X463433Y178150D02*
Y176750D01*
G01X462373Y190613D02*
Y171820D01*
G01X463433Y174850D02*
Y172260D01*
G01D02*
X464140Y171553D01*
G01D02*
X464776D01*
G01X465484Y170209D02*
X490033Y145660D01*
G01X431643Y418187D02*
Y454919D01*
G01X432703Y418187D02*
Y454479D01*
G01X431643Y454919D02*
X469416Y492692D01*
G01X432703Y454479D02*
X469856Y491632D01*
G01X464338Y416387D02*
Y434846D01*
G01X465398Y416387D02*
Y434406D01*
G01X464338Y434846D02*
X472432Y442940D01*
G01X465398Y434406D02*
X473492Y442500D01*
G01X472432Y442940D02*
Y447108D01*
G01X473492Y442500D02*
Y446668D01*
G01X472432Y447108D02*
X488537Y463213D01*
G01X473492Y446668D02*
X488977Y462153D01*
G01X439903Y418487D02*
Y444592D01*
G01X438843Y418487D02*
Y444152D01*
G01X439903Y444592D02*
X438673Y445822D01*
G01X438843Y444152D02*
X438233Y444762D01*
G01X438673Y445822D02*
X437501D01*
G01X438233Y444762D02*
X437061D01*
G01X437501Y445822D02*
X436913Y446410D01*
G01X437061Y444762D02*
X435853Y445970D01*
G01X436913Y446410D02*
Y447800D01*
G01X435853Y445970D02*
Y448240D01*
G01X436913Y447800D02*
X437545Y448432D01*
G01X435853Y448240D02*
X437105Y449492D01*
G01X437545Y448432D02*
X438673D01*
G01X437105Y449492D02*
X438233D01*
G01X438673Y448432D02*
X439903Y449662D01*
G01X438233Y449492D02*
X438843Y450102D01*
G01X439903Y449662D02*
Y455935D01*
G01X438843Y450102D02*
Y456375D01*
G01X439903Y455935D02*
X471432Y487464D01*
G01X438843Y456375D02*
X470992Y488524D01*
G01X469088Y419887D02*
Y433196D01*
G01X468028Y419887D02*
Y433636D01*
G01X469088Y433196D02*
X476992Y441100D01*
G01X468028Y433636D02*
X475932Y441540D01*
G01X476992Y441100D02*
Y444129D01*
G01X475932Y441540D02*
Y444569D01*
G01X476992Y444129D02*
X491209Y458346D01*
G01X475932Y444569D02*
X490769Y459406D01*
G01X432703Y418187D02*
Y454479D01*
G01X431643Y418187D02*
Y454919D01*
G01X432703Y454479D02*
X469856Y491632D01*
G01X431643Y454919D02*
X469416Y492692D01*
G01X465398Y416387D02*
Y434406D01*
G01X464338Y416387D02*
Y434846D01*
G01X465398Y434406D02*
X473492Y442500D01*
G01X464338Y434846D02*
X472432Y442940D01*
G01X473492Y442500D02*
Y446668D01*
G01X472432Y442940D02*
Y447108D01*
G01X473492Y446668D02*
X488977Y462153D01*
G01X472432Y447108D02*
X488537Y463213D01*
G01X438843Y418487D02*
Y444152D01*
G01X439903Y418487D02*
Y444592D01*
G01X438843Y444152D02*
X438233Y444762D01*
G01X439903Y444592D02*
X438673Y445822D01*
G01X438233Y444762D02*
X437061D01*
G01X438673Y445822D02*
X437501D01*
G01X437061Y444762D02*
X435853Y445970D01*
G01X437501Y445822D02*
X436913Y446410D01*
G01X435853Y445970D02*
Y448240D01*
G01X436913Y446410D02*
Y447800D01*
G01X435853Y448240D02*
X437105Y449492D01*
G01X436913Y447800D02*
X437545Y448432D01*
G01X437105Y449492D02*
X438233D01*
G01X437545Y448432D02*
X438673D01*
G01X438233Y449492D02*
X438843Y450102D01*
G01X438673Y448432D02*
X439903Y449662D01*
G01X438843Y450102D02*
Y456375D01*
G01X439903Y449662D02*
Y455935D01*
G01X438843Y456375D02*
X470992Y488524D01*
G01X439903Y455935D02*
X471432Y487464D01*
G01X468028Y419887D02*
Y433636D01*
G01X469088Y419887D02*
Y433196D01*
G01X468028Y433636D02*
X475932Y441540D01*
G01X469088Y433196D02*
X476992Y441100D01*
G01X475932Y441540D02*
Y444569D01*
G01X476992Y441100D02*
Y444129D01*
G01X475932Y444569D02*
X490769Y459406D01*
G01X476992Y444129D02*
X491209Y458346D01*
G01X431643Y418187D02*
Y454919D01*
G01X432703Y418187D02*
Y454479D01*
G01X431643Y454919D02*
X469416Y492692D01*
G01X432703Y454479D02*
X469856Y491632D01*
G01X464338Y416387D02*
Y434846D01*
G01X465398Y416387D02*
Y434406D01*
G01X464338Y434846D02*
X472432Y442940D01*
G01X465398Y434406D02*
X473492Y442500D01*
G01X472432Y442940D02*
Y447108D01*
G01X473492Y442500D02*
Y446668D01*
G01X472432Y447108D02*
X488537Y463213D01*
G01X473492Y446668D02*
X488977Y462153D01*
G01X439903Y418487D02*
Y444592D01*
G01X438843Y418487D02*
Y444152D01*
G01X439903Y444592D02*
X438673Y445822D01*
G01X438843Y444152D02*
X438233Y444762D01*
G01X438673Y445822D02*
X437501D01*
G01X438233Y444762D02*
X437061D01*
G01X437501Y445822D02*
X436913Y446410D01*
G01X437061Y444762D02*
X435853Y445970D01*
G01X436913Y446410D02*
Y447800D01*
G01X435853Y445970D02*
Y448240D01*
G01X436913Y447800D02*
X437545Y448432D01*
G01X435853Y448240D02*
X437105Y449492D01*
G01X437545Y448432D02*
X438673D01*
G01X437105Y449492D02*
X438233D01*
G01X438673Y448432D02*
X439903Y449662D01*
G01X438233Y449492D02*
X438843Y450102D01*
G01X439903Y449662D02*
Y455935D01*
G01X438843Y450102D02*
Y456375D01*
G01X439903Y455935D02*
X471432Y487464D01*
G01X438843Y456375D02*
X470992Y488524D01*
G01X432703Y418187D02*
Y454479D01*
G01X431643Y418187D02*
Y454919D01*
G01X432703Y454479D02*
X469856Y491632D01*
G01X431643Y454919D02*
X469416Y492692D01*
G01X465398Y416387D02*
Y434406D01*
G01X464338Y416387D02*
Y434846D01*
G01X465398Y434406D02*
X473492Y442500D01*
G01X464338Y434846D02*
X472432Y442940D01*
G01X473492Y442500D02*
Y446668D01*
G01X472432Y442940D02*
Y447108D01*
G01X473492Y446668D02*
X488977Y462153D01*
G01X472432Y447108D02*
X488537Y463213D01*
G01X438843Y418487D02*
Y444152D01*
G01X439903Y418487D02*
Y444592D01*
G01X438843Y444152D02*
X438233Y444762D01*
G01X439903Y444592D02*
X438673Y445822D01*
G01X438233Y444762D02*
X437061D01*
G01X438673Y445822D02*
X437501D01*
G01X437061Y444762D02*
X435853Y445970D01*
G01X437501Y445822D02*
X436913Y446410D01*
G01X435853Y445970D02*
Y448240D01*
G01X436913Y446410D02*
Y447800D01*
G01X435853Y448240D02*
X437105Y449492D01*
G01X436913Y447800D02*
X437545Y448432D01*
G01X437105Y449492D02*
X438233D01*
G01X437545Y448432D02*
X438673D01*
G01X438233Y449492D02*
X438843Y450102D01*
G01X438673Y448432D02*
X439903Y449662D01*
G01X438843Y450102D02*
Y456375D01*
G01X439903Y449662D02*
Y455935D01*
G01X438843Y456375D02*
X470992Y488524D01*
G01X439903Y455935D02*
X471432Y487464D01*
G01X469088Y419887D02*
Y433196D01*
G01X468028Y419887D02*
Y433636D01*
G01X469088Y433196D02*
X476992Y441100D01*
G01X468028Y433636D02*
X475932Y441540D01*
G01X476992Y441100D02*
Y444129D01*
G01X475932Y441540D02*
Y444569D01*
G01X476992Y444129D02*
X491209Y458346D01*
G01X475932Y444569D02*
X490769Y459406D01*
G01X468028Y419887D02*
Y433636D01*
G01X469088Y419887D02*
Y433196D01*
G01X468028Y433636D02*
X475932Y441540D01*
G01X469088Y433196D02*
X476992Y441100D01*
G01X475932Y441540D02*
Y444569D01*
G01X476992Y441100D02*
Y444129D01*
G01X475932Y444569D02*
X490769Y459406D01*
G01X476992Y444129D02*
X491209Y458346D01*
G01X469416Y492692D02*
X480055D01*
G01X469856Y491632D02*
X480495D01*
G01X471432Y487464D02*
X508365D01*
G01X470992Y488524D02*
X478507D01*
G01X471432Y487464D02*
X508365D01*
G01X471432D02*
X508365D01*
G01X471432D02*
X508365D01*
G01X471432D02*
X508365D01*
G01X471432D02*
X508365D01*
G01X471432D02*
X508365D01*
G01X471432D02*
X508365D01*
G01X471432D02*
X508365D01*
G01X469856Y491632D02*
X480495D01*
G01X469416Y492692D02*
X480055D01*
G01X470992Y488524D02*
X478507D01*
G01X471432Y487464D02*
X508365D01*
G01X462745Y532412D02*
Y514347D01*
G01X463805Y526760D02*
Y525340D01*
G01X462745Y532412D02*
Y514347D01*
G01X463805Y521660D02*
Y520290D01*
G01X469129Y527000D02*
X468358Y526229D01*
G01D02*
Y525338D01*
G01Y521848D02*
Y520571D01*
G01X467298Y526670D02*
Y520130D01*
G01X468358Y520571D02*
X469029Y519900D01*
G01X467298Y520130D02*
X468127Y519301D01*
G01X463805Y526760D02*
Y525340D01*
G01Y521660D02*
Y520290D01*
G01X462745Y532412D02*
Y514347D01*
G01X469129Y527000D02*
X468358Y526229D01*
G01X467298Y526670D02*
Y520130D01*
G01X468358Y526229D02*
Y525338D01*
G01X467298Y526670D02*
Y520130D01*
G01X468358Y521848D02*
Y520571D01*
G01X467298Y520130D02*
X468127Y519301D01*
G01X468358Y520571D02*
X469029Y519900D01*
G01X469416Y492692D02*
X480055D01*
G01X469856Y491632D02*
X480495D01*
G01X471432Y487464D02*
X508365D01*
G01X470992Y488524D02*
X478507D01*
G01X471432Y487464D02*
X508365D01*
G01X471432D02*
X508365D01*
G01X471432D02*
X508365D01*
G01X471432D02*
X508365D01*
G01X471432D02*
X508365D01*
G01X471432D02*
X508365D01*
G01X471432D02*
X508365D01*
G01X471432D02*
X508365D01*
G01X469856Y491632D02*
X480495D01*
G01X469416Y492692D02*
X480055D01*
G01X470992Y488524D02*
X478507D01*
G01X471432Y487464D02*
X508365D01*
G01X468127Y527499D02*
X467298Y526670D01*
G01X468127Y527499D02*
X467298Y526670D01*
G01X573151Y-46771D02*
X491716D01*
G01X572711Y-47831D02*
X491716D01*
G01X572711D02*
X491716D01*
G01X573151Y-46771D02*
X491716D01*
G01X501544Y87300D02*
X502641D01*
G01D02*
X503590Y86351D01*
G01X501544Y89900D02*
X504650Y86794D01*
G01X503590Y86351D02*
Y83820D01*
G01Y79680D02*
Y78720D01*
G01Y74380D02*
Y71091D01*
G01X504650Y86794D02*
Y70648D01*
G01X503590Y71091D02*
X502879Y70380D01*
G01X504650Y70648D02*
X503322Y69320D01*
G01X502879Y70380D02*
X502363D01*
G01X503322Y69320D02*
X502340D01*
G01X499570Y99190D02*
Y89274D01*
G01Y99190D02*
Y89274D01*
G01X539456Y87300D02*
X540401Y86355D01*
G01X539474Y88782D02*
X540989Y87266D01*
G01X539456Y87300D02*
X540401Y86355D01*
G01Y71091D02*
X539690Y70380D01*
G01D02*
X539174D01*
G01X540133Y69320D02*
X539151D01*
G01X536501Y97579D02*
Y89154D01*
G01X506644Y90114D02*
X509836Y86922D01*
G01X506644Y87515D02*
X507742D01*
G01X506644Y90114D02*
X509836Y86922D01*
G01X507742Y87515D02*
X508776Y86481D01*
G01X509836Y86922D02*
Y71532D01*
G01X508776Y86481D02*
Y83706D01*
G01X509836Y86922D02*
Y71532D01*
G01X508776Y79880D02*
Y78507D01*
G01X509836Y86922D02*
Y71532D01*
G01X508776Y74593D02*
Y71972D01*
G01X509836Y71532D02*
X506644Y68340D01*
G01X508776Y71972D02*
X507753Y70949D01*
G01X504890Y97234D02*
Y89268D01*
G01X501544Y89900D02*
X504650Y86794D01*
G01X501544Y87300D02*
X502641D01*
G01X501544Y89900D02*
X504650Y86794D01*
G01X502641Y87300D02*
X503590Y86351D01*
G01X504650Y86794D02*
Y70648D01*
G01X503590Y86351D02*
Y83820D01*
G01X504650Y86794D02*
Y70648D01*
G01X503590Y79680D02*
Y78720D01*
G01X504650Y86794D02*
Y70648D01*
G01X503590Y74380D02*
Y71091D01*
G01X504650Y70648D02*
X503322Y69320D01*
G01X503590Y71091D02*
X502879Y70380D01*
G01X503322Y69320D02*
X502340D01*
G01X502879Y70380D02*
X502363D01*
G01X499570Y99190D02*
Y89274D01*
G01X539474Y88782D02*
X540989Y87266D01*
G01X539456Y87300D02*
X540401Y86355D01*
G01Y71091D02*
X539690Y70380D01*
G01X540133Y69320D02*
X539151D01*
G01X539690Y70380D02*
X539174D01*
G01X536501Y97579D02*
Y89154D01*
G01X506644Y87515D02*
X507742D01*
G01D02*
X508776Y86481D01*
G01X506644Y90114D02*
X509836Y86922D01*
G01X508776Y86481D02*
Y83706D01*
G01Y79880D02*
Y78507D01*
G01Y74593D02*
Y71972D01*
G01X509836Y86922D02*
Y71532D01*
G01X508776Y71972D02*
X507753Y70949D01*
G01X509836Y71532D02*
X506644Y68340D01*
G01X504890Y97234D02*
Y89268D01*
G01X501544Y87300D02*
X502641D01*
G01D02*
X503590Y86351D01*
G01X501544Y89900D02*
X504650Y86794D01*
G01X503590Y86351D02*
Y83820D01*
G01Y79680D02*
Y78720D01*
G01Y74380D02*
Y71091D01*
G01X504650Y86794D02*
Y70648D01*
G01X503590Y71091D02*
X502879Y70380D01*
G01X504650Y70648D02*
X503322Y69320D01*
G01X502879Y70380D02*
X502363D01*
G01X503322Y69320D02*
X502340D01*
G01X499570Y99190D02*
Y89274D01*
G01Y99190D02*
Y89274D01*
G01X539456Y87300D02*
X540401Y86355D01*
G01X539474Y88782D02*
X540989Y87266D01*
G01X539456Y87300D02*
X540401Y86355D01*
G01Y71091D02*
X539690Y70380D01*
G01D02*
X539174D01*
G01X540133Y69320D02*
X539151D01*
G01X536501Y97579D02*
Y89154D01*
G01X506644Y90114D02*
X509836Y86922D01*
G01X506644Y87515D02*
X507742D01*
G01X506644Y90114D02*
X509836Y86922D01*
G01X507742Y87515D02*
X508776Y86481D01*
G01X509836Y86922D02*
Y71532D01*
G01X508776Y86481D02*
Y83706D01*
G01X509836Y86922D02*
Y71532D01*
G01X508776Y79880D02*
Y78507D01*
G01X509836Y86922D02*
Y71532D01*
G01X508776Y74593D02*
Y71972D01*
G01X509836Y71532D02*
X506644Y68340D01*
G01X508776Y71972D02*
X507753Y70949D01*
G01X504890Y97234D02*
Y89268D01*
G01X501544Y89900D02*
X504650Y86794D01*
G01X501544Y87300D02*
X502641D01*
G01X501544Y89900D02*
X504650Y86794D01*
G01X502641Y87300D02*
X503590Y86351D01*
G01X504650Y86794D02*
Y70648D01*
G01X503590Y86351D02*
Y83820D01*
G01X504650Y86794D02*
Y70648D01*
G01X503590Y79680D02*
Y78720D01*
G01X504650Y86794D02*
Y70648D01*
G01X503590Y74380D02*
Y71091D01*
G01X504650Y70648D02*
X503322Y69320D01*
G01X503590Y71091D02*
X502879Y70380D01*
G01X503322Y69320D02*
X502340D01*
G01X502879Y70380D02*
X502363D01*
G01X499570Y99190D02*
Y89274D01*
G01X539474Y88782D02*
X540989Y87266D01*
G01X539456Y87300D02*
X540401Y86355D01*
G01Y71091D02*
X539690Y70380D01*
G01X540133Y69320D02*
X539151D01*
G01X539690Y70380D02*
X539174D01*
G01X536501Y97579D02*
Y89154D01*
G01X506644Y87515D02*
X507742D01*
G01D02*
X508776Y86481D01*
G01X506644Y90114D02*
X509836Y86922D01*
G01X508776Y86481D02*
Y83706D01*
G01Y79880D02*
Y78507D01*
G01Y74593D02*
Y71972D01*
G01X509836Y86922D02*
Y71532D01*
G01X508776Y71972D02*
X507753Y70949D01*
G01X509836Y71532D02*
X506644Y68340D01*
G01X504890Y97234D02*
Y89268D01*
G01X479693Y108600D02*
X486993Y101300D01*
G01X480133Y109660D02*
X481770Y108023D01*
G01X479693Y108600D02*
X486993Y101300D01*
G01X483115Y106678D02*
X487433Y102360D01*
G01X486993Y101300D02*
X497460D01*
G01X487433Y102360D02*
X489942D01*
G01X486993Y101300D02*
X497460D01*
G01X491842Y102360D02*
X497900D01*
G01X497460Y101300D02*
X499570Y99190D01*
G01X497900Y102360D02*
X500630Y99630D01*
G01D02*
Y97800D01*
G01Y95900D02*
Y94900D01*
G01X487592Y140800D02*
X520393D01*
G01X488032Y141860D02*
X520833D01*
G01X520393Y140800D02*
X522643Y138550D01*
G01X520833Y141860D02*
X523703Y138990D01*
G01X522643Y138550D02*
Y137688D01*
G01X523703Y138990D02*
Y137248D01*
G01X522643Y137688D02*
X521866Y136911D01*
G01X523703Y137248D02*
X522926Y136471D01*
G01X521866Y136911D02*
Y135327D01*
G01X522926Y136471D02*
Y135767D01*
G01X521866Y135327D02*
X523630Y133563D01*
G01X522926Y135767D02*
X524070Y134623D01*
G01X521866Y135327D02*
X523630Y133563D01*
G01D02*
X525214D01*
G01X524070Y134623D02*
X524774D01*
G01X525214Y133563D02*
X525991Y134340D01*
G01D02*
X526853D01*
G01X524774Y134623D02*
X525551Y135400D01*
G01X525991Y134340D02*
X526853D01*
G01X525551Y135400D02*
X527293D01*
G01X526853Y134340D02*
X527837Y133356D01*
G01X527293Y135400D02*
X528897Y133796D01*
G01X527837Y133356D02*
Y132494D01*
G01X528897Y133796D02*
Y132054D01*
G01X527837Y132494D02*
X527010Y131667D01*
G01X528897Y132054D02*
X528070Y131227D01*
G01X527010Y131667D02*
Y130083D01*
G01X528070Y131227D02*
Y130523D01*
G01X527010Y130083D02*
X528774Y128319D01*
G01X528070Y130523D02*
X529214Y129379D01*
G01X528774Y128319D02*
X530358D01*
G01D02*
X531185Y129146D01*
G01X529214Y129379D02*
X529918D01*
G01X530358Y128319D02*
X531185Y129146D01*
G01X529918Y129379D02*
X530745Y130206D01*
G01X531185Y129146D02*
X532047D01*
G01X530745Y130206D02*
X532487D01*
G01X532047Y129146D02*
X533031Y128162D01*
G01X532487Y130206D02*
X534091Y128602D01*
G01X533031Y128162D02*
Y127300D01*
G01X534091Y128602D02*
Y126860D01*
G01X533031Y127300D02*
X532054Y126323D01*
G01X534091Y126860D02*
X533114Y125883D01*
G01X532054Y126323D02*
Y124739D01*
G01X533114Y125883D02*
Y125179D01*
G01X532054Y124739D02*
X533818Y122975D01*
G01X533114Y125179D02*
X534258Y124035D01*
G01X533818Y122975D02*
X538218D01*
G01X534258Y124035D02*
X538658D01*
G01X538218Y122975D02*
X540386Y120807D01*
G01X538658Y124035D02*
X541446Y121247D01*
G01X540386Y101464D02*
X536501Y97579D01*
G01X541446Y101021D02*
X537561Y97136D01*
G01D02*
Y95220D01*
G01X502661Y116260D02*
X504572Y114349D01*
G01X502221Y115200D02*
X503512Y113909D01*
G01X504572Y114349D02*
Y102220D01*
G01Y99980D02*
Y99052D01*
G01X503512Y113909D02*
Y98612D01*
G01X504572Y99052D02*
X505950Y97674D01*
G01X503512Y98612D02*
X504890Y97234D01*
G01X505950Y97674D02*
Y95542D01*
G01X490033Y145660D02*
X522132D01*
G01X489593Y144600D02*
X521692D01*
G01X522132Y145660D02*
X546546Y121246D01*
G01X521692Y144600D02*
X545486Y120806D01*
G01X480133Y109660D02*
X481770Y108023D01*
G01X483115Y106678D02*
X487433Y102360D01*
G01X479693Y108600D02*
X486993Y101300D01*
G01X487433Y102360D02*
X489942D01*
G01X491842D02*
X497900D01*
G01X486993Y101300D02*
X497460D01*
G01X497900Y102360D02*
X500630Y99630D01*
G01X497460Y101300D02*
X499570Y99190D01*
G01X500630Y99630D02*
Y97800D01*
G01Y95900D02*
Y94900D01*
G01X488032Y141860D02*
X520833D01*
G01X487592Y140800D02*
X520393D01*
G01X520833Y141860D02*
X523703Y138990D01*
G01X520393Y140800D02*
X522643Y138550D01*
G01X523703Y138990D02*
Y137248D01*
G01X522643Y138550D02*
Y137688D01*
G01X523703Y137248D02*
X522926Y136471D01*
G01X522643Y137688D02*
X521866Y136911D01*
G01X522926Y136471D02*
Y135767D01*
G01X521866Y136911D02*
Y135327D01*
G01X522926Y135767D02*
X524070Y134623D01*
G01D02*
X524774D01*
G01X521866Y135327D02*
X523630Y133563D01*
G01X524070Y134623D02*
X524774D01*
G01X523630Y133563D02*
X525214D01*
G01X524774Y134623D02*
X525551Y135400D01*
G01X525214Y133563D02*
X525991Y134340D01*
G01X524774Y134623D02*
X525551Y135400D01*
G01D02*
X527293D01*
G01X525991Y134340D02*
X526853D01*
G01X527293Y135400D02*
X528897Y133796D01*
G01X526853Y134340D02*
X527837Y133356D01*
G01X528897Y133796D02*
Y132054D01*
G01X527837Y133356D02*
Y132494D01*
G01X528897Y132054D02*
X528070Y131227D01*
G01X527837Y132494D02*
X527010Y131667D01*
G01X528070Y131227D02*
Y130523D01*
G01X527010Y131667D02*
Y130083D01*
G01X528070Y130523D02*
X529214Y129379D01*
G01X527010Y130083D02*
X528774Y128319D01*
G01X529214Y129379D02*
X529918D01*
G01X528774Y128319D02*
X530358D01*
G01X529214Y129379D02*
X529918D01*
G01D02*
X530745Y130206D01*
G01X530358Y128319D02*
X531185Y129146D01*
G01X530745Y130206D02*
X532487D01*
G01X531185Y129146D02*
X532047D01*
G01X532487Y130206D02*
X534091Y128602D01*
G01X532047Y129146D02*
X533031Y128162D01*
G01X534091Y128602D02*
Y126860D01*
G01X533031Y128162D02*
Y127300D01*
G01X534091Y126860D02*
X533114Y125883D01*
G01X533031Y127300D02*
X532054Y126323D01*
G01X533114Y125883D02*
Y125179D01*
G01X532054Y126323D02*
Y124739D01*
G01X533114Y125179D02*
X534258Y124035D01*
G01X532054Y124739D02*
X533818Y122975D01*
G01X534258Y124035D02*
X538658D01*
G01X533818Y122975D02*
X538218D01*
G01X538658Y124035D02*
X541446Y121247D01*
G01X538218Y122975D02*
X540386Y120807D01*
G01X541446Y101021D02*
X537561Y97136D01*
G01X540386Y101464D02*
X536501Y97579D01*
G01X537561Y97136D02*
Y95220D01*
G01X502221Y115200D02*
X503512Y113909D01*
G01X502661Y116260D02*
X504572Y114349D01*
G01X503512Y113909D02*
Y98612D01*
G01X504572Y114349D02*
Y102220D01*
G01X503512Y113909D02*
Y98612D01*
G01X504572Y99980D02*
Y99052D01*
G01X503512Y98612D02*
X504890Y97234D01*
G01X504572Y99052D02*
X505950Y97674D01*
G01D02*
Y95542D01*
G01X489593Y144600D02*
X521692D01*
G01X490033Y145660D02*
X522132D01*
G01X521692Y144600D02*
X545486Y120806D01*
G01X522132Y145660D02*
X546546Y121246D01*
G01X479693Y108600D02*
X486993Y101300D01*
G01X480133Y109660D02*
X481770Y108023D01*
G01X479693Y108600D02*
X486993Y101300D01*
G01X483115Y106678D02*
X487433Y102360D01*
G01X486993Y101300D02*
X497460D01*
G01X487433Y102360D02*
X489942D01*
G01X486993Y101300D02*
X497460D01*
G01X491842Y102360D02*
X497900D01*
G01X497460Y101300D02*
X499570Y99190D01*
G01X497900Y102360D02*
X500630Y99630D01*
G01D02*
Y97800D01*
G01Y95900D02*
Y94900D01*
G01X487592Y140800D02*
X520393D01*
G01X488032Y141860D02*
X520833D01*
G01X520393Y140800D02*
X522643Y138550D01*
G01X520833Y141860D02*
X523703Y138990D01*
G01X522643Y138550D02*
Y137688D01*
G01X523703Y138990D02*
Y137248D01*
G01X522643Y137688D02*
X521866Y136911D01*
G01X523703Y137248D02*
X522926Y136471D01*
G01X521866Y136911D02*
Y135327D01*
G01X522926Y136471D02*
Y135767D01*
G01X521866Y135327D02*
X523630Y133563D01*
G01X522926Y135767D02*
X524070Y134623D01*
G01X521866Y135327D02*
X523630Y133563D01*
G01D02*
X525214D01*
G01X524070Y134623D02*
X524774D01*
G01X525214Y133563D02*
X525991Y134340D01*
G01D02*
X526853D01*
G01X524774Y134623D02*
X525551Y135400D01*
G01X525991Y134340D02*
X526853D01*
G01X525551Y135400D02*
X527293D01*
G01X526853Y134340D02*
X527837Y133356D01*
G01X527293Y135400D02*
X528897Y133796D01*
G01X527837Y133356D02*
Y132494D01*
G01X528897Y133796D02*
Y132054D01*
G01X527837Y132494D02*
X527010Y131667D01*
G01X528897Y132054D02*
X528070Y131227D01*
G01X527010Y131667D02*
Y130083D01*
G01X528070Y131227D02*
Y130523D01*
G01X527010Y130083D02*
X528774Y128319D01*
G01X528070Y130523D02*
X529214Y129379D01*
G01X528774Y128319D02*
X530358D01*
G01D02*
X531185Y129146D01*
G01X529214Y129379D02*
X529918D01*
G01X530358Y128319D02*
X531185Y129146D01*
G01X529918Y129379D02*
X530745Y130206D01*
G01X531185Y129146D02*
X532047D01*
G01X530745Y130206D02*
X532487D01*
G01X532047Y129146D02*
X533031Y128162D01*
G01X532487Y130206D02*
X534091Y128602D01*
G01X533031Y128162D02*
Y127300D01*
G01X534091Y128602D02*
Y126860D01*
G01X533031Y127300D02*
X532054Y126323D01*
G01X534091Y126860D02*
X533114Y125883D01*
G01X532054Y126323D02*
Y124739D01*
G01X533114Y125883D02*
Y125179D01*
G01X532054Y124739D02*
X533818Y122975D01*
G01X533114Y125179D02*
X534258Y124035D01*
G01X533818Y122975D02*
X538218D01*
G01X534258Y124035D02*
X538658D01*
G01X538218Y122975D02*
X540386Y120807D01*
G01X538658Y124035D02*
X541446Y121247D01*
G01X540386Y101464D02*
X536501Y97579D01*
G01X541446Y101021D02*
X537561Y97136D01*
G01D02*
Y95220D01*
G01X502661Y116260D02*
X504572Y114349D01*
G01X502221Y115200D02*
X503512Y113909D01*
G01X504572Y114349D02*
Y102220D01*
G01Y99980D02*
Y99052D01*
G01X503512Y113909D02*
Y98612D01*
G01X504572Y99052D02*
X505950Y97674D01*
G01X503512Y98612D02*
X504890Y97234D01*
G01X505950Y97674D02*
Y95542D01*
G01X480133Y109660D02*
X481770Y108023D01*
G01X483115Y106678D02*
X487433Y102360D01*
G01X479693Y108600D02*
X486993Y101300D01*
G01X487433Y102360D02*
X489942D01*
G01X491842D02*
X497900D01*
G01X486993Y101300D02*
X497460D01*
G01X497900Y102360D02*
X500630Y99630D01*
G01X497460Y101300D02*
X499570Y99190D01*
G01X500630Y99630D02*
Y97800D01*
G01Y95900D02*
Y94900D01*
G01X488032Y141860D02*
X520833D01*
G01X487592Y140800D02*
X520393D01*
G01X520833Y141860D02*
X523703Y138990D01*
G01X520393Y140800D02*
X522643Y138550D01*
G01X523703Y138990D02*
Y137248D01*
G01X522643Y138550D02*
Y137688D01*
G01X523703Y137248D02*
X522926Y136471D01*
G01X522643Y137688D02*
X521866Y136911D01*
G01X522926Y136471D02*
Y135767D01*
G01X521866Y136911D02*
Y135327D01*
G01X522926Y135767D02*
X524070Y134623D01*
G01D02*
X524774D01*
G01X521866Y135327D02*
X523630Y133563D01*
G01X524070Y134623D02*
X524774D01*
G01X523630Y133563D02*
X525214D01*
G01X524774Y134623D02*
X525551Y135400D01*
G01X525214Y133563D02*
X525991Y134340D01*
G01X524774Y134623D02*
X525551Y135400D01*
G01D02*
X527293D01*
G01X525991Y134340D02*
X526853D01*
G01X527293Y135400D02*
X528897Y133796D01*
G01X526853Y134340D02*
X527837Y133356D01*
G01X528897Y133796D02*
Y132054D01*
G01X527837Y133356D02*
Y132494D01*
G01X528897Y132054D02*
X528070Y131227D01*
G01X527837Y132494D02*
X527010Y131667D01*
G01X528070Y131227D02*
Y130523D01*
G01X527010Y131667D02*
Y130083D01*
G01X528070Y130523D02*
X529214Y129379D01*
G01X527010Y130083D02*
X528774Y128319D01*
G01X529214Y129379D02*
X529918D01*
G01X528774Y128319D02*
X530358D01*
G01X529214Y129379D02*
X529918D01*
G01D02*
X530745Y130206D01*
G01X530358Y128319D02*
X531185Y129146D01*
G01X530745Y130206D02*
X532487D01*
G01X531185Y129146D02*
X532047D01*
G01X532487Y130206D02*
X534091Y128602D01*
G01X532047Y129146D02*
X533031Y128162D01*
G01X534091Y128602D02*
Y126860D01*
G01X533031Y128162D02*
Y127300D01*
G01X534091Y126860D02*
X533114Y125883D01*
G01X533031Y127300D02*
X532054Y126323D01*
G01X533114Y125883D02*
Y125179D01*
G01X532054Y126323D02*
Y124739D01*
G01X533114Y125179D02*
X534258Y124035D01*
G01X532054Y124739D02*
X533818Y122975D01*
G01X534258Y124035D02*
X538658D01*
G01X533818Y122975D02*
X538218D01*
G01X538658Y124035D02*
X541446Y121247D01*
G01X538218Y122975D02*
X540386Y120807D01*
G01X541446Y101021D02*
X537561Y97136D01*
G01X540386Y101464D02*
X536501Y97579D01*
G01X537561Y97136D02*
Y95220D01*
G01X502221Y115200D02*
X503512Y113909D01*
G01X502661Y116260D02*
X504572Y114349D01*
G01X503512Y113909D02*
Y98612D01*
G01X504572Y114349D02*
Y102220D01*
G01X503512Y113909D02*
Y98612D01*
G01X504572Y99980D02*
Y99052D01*
G01X503512Y98612D02*
X504890Y97234D01*
G01X504572Y99052D02*
X505950Y97674D01*
G01D02*
Y95542D01*
G01X490033Y145660D02*
X522132D01*
G01X489593Y144600D02*
X521692D01*
G01X522132Y145660D02*
X546546Y121246D01*
G01X521692Y144600D02*
X545486Y120806D01*
G01X489593Y144600D02*
X521692D01*
G01X490033Y145660D02*
X522132D01*
G01X521692Y144600D02*
X545486Y120806D01*
G01X522132Y145660D02*
X546546Y121246D01*
G01X488204Y201289D02*
X488911Y200582D01*
G01X490255Y199238D02*
X490962Y198531D01*
G01X492306Y197187D02*
X493013Y196480D01*
G01X494357Y195136D02*
X495120Y194373D01*
G01X496465Y193028D02*
X497172Y192321D01*
G01X498516Y190977D02*
X499270Y190223D01*
G01X500615Y188878D02*
X501322Y188171D01*
G01X502666Y186827D02*
X503372Y186120D01*
G01X504717Y184776D02*
X505803Y183689D01*
G01X487458Y200542D02*
X505371Y182629D01*
G01X505803Y183689D02*
X508904D01*
G01X505371Y182629D02*
X508464D01*
G01X508904Y183689D02*
X509611Y182982D01*
G01X510955Y181638D02*
X511662Y180931D01*
G01X513006Y179587D02*
X513713Y178880D01*
G01X515057Y177536D02*
X515764Y176829D01*
G01X517108Y175485D02*
X519233Y173360D01*
G01X508464Y182629D02*
X518793Y172300D01*
G01X519233Y173360D02*
X521863D01*
G01X518793Y172300D02*
X522303D01*
G01X521863Y173360D02*
X522473Y173970D01*
G01X522303Y172300D02*
X523533Y173530D01*
G01X522473Y173970D02*
Y176970D01*
G01X523533Y173530D02*
Y176530D01*
G01X522473Y176970D02*
X523703Y178200D01*
G01X523533Y176530D02*
X524143Y177140D01*
G01X522473Y176970D02*
X523703Y178200D01*
G01D02*
X525973D01*
G01D02*
X527203Y176970D01*
G01X524143Y177140D02*
X525533D01*
G01X525973Y178200D02*
X527203Y176970D01*
G01X525533Y177140D02*
X526143Y176530D01*
G01X527203Y176970D02*
Y173970D01*
G01X526143Y176530D02*
Y173530D01*
G01X527203Y173970D02*
X527813Y173360D01*
G01X526143Y173530D02*
X527373Y172300D01*
G01X527813Y173360D02*
X538832D01*
G01X527373Y172300D02*
X538392D01*
G01X538832Y173360D02*
X563891Y148301D01*
G01X538392Y172300D02*
X563451Y147241D01*
G01X487458Y200542D02*
X505371Y182629D01*
G01X488204Y201289D02*
X488911Y200582D01*
G01X487458Y200542D02*
X505371Y182629D01*
G01X490255Y199238D02*
X490962Y198531D01*
G01X487458Y200542D02*
X505371Y182629D01*
G01X492306Y197187D02*
X493013Y196480D01*
G01X487458Y200542D02*
X505371Y182629D01*
G01X494357Y195136D02*
X495120Y194373D01*
G01X487458Y200542D02*
X505371Y182629D01*
G01X496465Y193028D02*
X497172Y192321D01*
G01X487458Y200542D02*
X505371Y182629D01*
G01X498516Y190977D02*
X499270Y190223D01*
G01X487458Y200542D02*
X505371Y182629D01*
G01X500615Y188878D02*
X501322Y188171D01*
G01X487458Y200542D02*
X505371Y182629D01*
G01X502666Y186827D02*
X503372Y186120D01*
G01X487458Y200542D02*
X505371Y182629D01*
G01X504717Y184776D02*
X505803Y183689D01*
G01X505371Y182629D02*
X508464D01*
G01X505803Y183689D02*
X508904D01*
G01X508464Y182629D02*
X518793Y172300D01*
G01X508904Y183689D02*
X509611Y182982D01*
G01X508464Y182629D02*
X518793Y172300D01*
G01X510955Y181638D02*
X511662Y180931D01*
G01X508464Y182629D02*
X518793Y172300D01*
G01X513006Y179587D02*
X513713Y178880D01*
G01X508464Y182629D02*
X518793Y172300D01*
G01X515057Y177536D02*
X515764Y176829D01*
G01X508464Y182629D02*
X518793Y172300D01*
G01X517108Y175485D02*
X519233Y173360D01*
G01X518793Y172300D02*
X522303D01*
G01X519233Y173360D02*
X521863D01*
G01X522303Y172300D02*
X523533Y173530D01*
G01X521863Y173360D02*
X522473Y173970D01*
G01X523533Y173530D02*
Y176530D01*
G01X522473Y173970D02*
Y176970D01*
G01X523533Y176530D02*
X524143Y177140D01*
G01D02*
X525533D01*
G01X522473Y176970D02*
X523703Y178200D01*
G01X524143Y177140D02*
X525533D01*
G01X523703Y178200D02*
X525973D01*
G01X524143Y177140D02*
X525533D01*
G01D02*
X526143Y176530D01*
G01X525973Y178200D02*
X527203Y176970D01*
G01X526143Y176530D02*
Y173530D01*
G01X527203Y176970D02*
Y173970D01*
G01X526143Y173530D02*
X527373Y172300D01*
G01X527203Y173970D02*
X527813Y173360D01*
G01X527373Y172300D02*
X538392D01*
G01X527813Y173360D02*
X538832D01*
G01X538392Y172300D02*
X563451Y147241D01*
G01X538832Y173360D02*
X563891Y148301D01*
G01X490991Y204288D02*
X508645Y186634D01*
G01X490241Y203538D02*
X508205Y185574D01*
G01X508645Y186634D02*
X513558D01*
G01X508205Y185574D02*
X513118D01*
G01X513558Y186634D02*
X519032Y181160D01*
G01X513118Y185574D02*
X518592Y180100D01*
G01X519032Y181160D02*
X537333D01*
G01X518592Y180100D02*
X536893D01*
G01X537333Y181160D02*
X565858Y152635D01*
G01X536893Y180100D02*
X565418Y151575D01*
G01X490241Y203538D02*
X508205Y185574D01*
G01X490991Y204288D02*
X508645Y186634D01*
G01X508205Y185574D02*
X513118D01*
G01X508645Y186634D02*
X513558D01*
G01X513118Y185574D02*
X518592Y180100D01*
G01X513558Y186634D02*
X519032Y181160D01*
G01X518592Y180100D02*
X536893D01*
G01X519032Y181160D02*
X537333D01*
G01X536893Y180100D02*
X565418Y151575D01*
G01X537333Y181160D02*
X565858Y152635D01*
G01X487458Y200542D02*
X505371Y182629D01*
G01X488204Y201289D02*
X488911Y200582D01*
G01X487458Y200542D02*
X505371Y182629D01*
G01X490255Y199238D02*
X490962Y198531D01*
G01X487458Y200542D02*
X505371Y182629D01*
G01X492306Y197187D02*
X493013Y196480D01*
G01X487458Y200542D02*
X505371Y182629D01*
G01X494357Y195136D02*
X495120Y194373D01*
G01X487458Y200542D02*
X505371Y182629D01*
G01X496465Y193028D02*
X497172Y192321D01*
G01X487458Y200542D02*
X505371Y182629D01*
G01X498516Y190977D02*
X499270Y190223D01*
G01X487458Y200542D02*
X505371Y182629D01*
G01X500615Y188878D02*
X501322Y188171D01*
G01X487458Y200542D02*
X505371Y182629D01*
G01X502666Y186827D02*
X503372Y186120D01*
G01X487458Y200542D02*
X505371Y182629D01*
G01X504717Y184776D02*
X505803Y183689D01*
G01X505371Y182629D02*
X508464D01*
G01X505803Y183689D02*
X508904D01*
G01X508464Y182629D02*
X518793Y172300D01*
G01X508904Y183689D02*
X509611Y182982D01*
G01X508464Y182629D02*
X518793Y172300D01*
G01X510955Y181638D02*
X511662Y180931D01*
G01X508464Y182629D02*
X518793Y172300D01*
G01X513006Y179587D02*
X513713Y178880D01*
G01X508464Y182629D02*
X518793Y172300D01*
G01X515057Y177536D02*
X515764Y176829D01*
G01X508464Y182629D02*
X518793Y172300D01*
G01X517108Y175485D02*
X519233Y173360D01*
G01X518793Y172300D02*
X522303D01*
G01X519233Y173360D02*
X521863D01*
G01X522303Y172300D02*
X523533Y173530D01*
G01X521863Y173360D02*
X522473Y173970D01*
G01X523533Y173530D02*
Y176530D01*
G01X522473Y173970D02*
Y176970D01*
G01X523533Y176530D02*
X524143Y177140D01*
G01D02*
X525533D01*
G01X522473Y176970D02*
X523703Y178200D01*
G01X524143Y177140D02*
X525533D01*
G01X523703Y178200D02*
X525973D01*
G01X524143Y177140D02*
X525533D01*
G01D02*
X526143Y176530D01*
G01X525973Y178200D02*
X527203Y176970D01*
G01X526143Y176530D02*
Y173530D01*
G01X527203Y176970D02*
Y173970D01*
G01X526143Y173530D02*
X527373Y172300D01*
G01X527203Y173970D02*
X527813Y173360D01*
G01X527373Y172300D02*
X538392D01*
G01X527813Y173360D02*
X538832D01*
G01X538392Y172300D02*
X563451Y147241D01*
G01X538832Y173360D02*
X563891Y148301D01*
G01X490991Y204288D02*
X508645Y186634D01*
G01X490241Y203538D02*
X508205Y185574D01*
G01X508645Y186634D02*
X513558D01*
G01X508205Y185574D02*
X513118D01*
G01X513558Y186634D02*
X519032Y181160D01*
G01X513118Y185574D02*
X518592Y180100D01*
G01X519032Y181160D02*
X537333D01*
G01X518592Y180100D02*
X536893D01*
G01X537333Y181160D02*
X565858Y152635D01*
G01X536893Y180100D02*
X565418Y151575D01*
G01X488204Y201289D02*
X488911Y200582D01*
G01X490255Y199238D02*
X490962Y198531D01*
G01X492306Y197187D02*
X493013Y196480D01*
G01X494357Y195136D02*
X495120Y194373D01*
G01X496465Y193028D02*
X497172Y192321D01*
G01X498516Y190977D02*
X499270Y190223D01*
G01X500615Y188878D02*
X501322Y188171D01*
G01X502666Y186827D02*
X503372Y186120D01*
G01X504717Y184776D02*
X505803Y183689D01*
G01X487458Y200542D02*
X505371Y182629D01*
G01X505803Y183689D02*
X508904D01*
G01X505371Y182629D02*
X508464D01*
G01X508904Y183689D02*
X509611Y182982D01*
G01X510955Y181638D02*
X511662Y180931D01*
G01X513006Y179587D02*
X513713Y178880D01*
G01X515057Y177536D02*
X515764Y176829D01*
G01X517108Y175485D02*
X519233Y173360D01*
G01X508464Y182629D02*
X518793Y172300D01*
G01X519233Y173360D02*
X521863D01*
G01X518793Y172300D02*
X522303D01*
G01X521863Y173360D02*
X522473Y173970D01*
G01X522303Y172300D02*
X523533Y173530D01*
G01X522473Y173970D02*
Y176970D01*
G01X523533Y173530D02*
Y176530D01*
G01X522473Y176970D02*
X523703Y178200D01*
G01X523533Y176530D02*
X524143Y177140D01*
G01X522473Y176970D02*
X523703Y178200D01*
G01D02*
X525973D01*
G01D02*
X527203Y176970D01*
G01X524143Y177140D02*
X525533D01*
G01X525973Y178200D02*
X527203Y176970D01*
G01X525533Y177140D02*
X526143Y176530D01*
G01X527203Y176970D02*
Y173970D01*
G01X526143Y176530D02*
Y173530D01*
G01X527203Y173970D02*
X527813Y173360D01*
G01X526143Y173530D02*
X527373Y172300D01*
G01X527813Y173360D02*
X538832D01*
G01X527373Y172300D02*
X538392D01*
G01X538832Y173360D02*
X563891Y148301D01*
G01X538392Y172300D02*
X563451Y147241D01*
G01X490241Y203538D02*
X508205Y185574D01*
G01X490991Y204288D02*
X508645Y186634D01*
G01X508205Y185574D02*
X513118D01*
G01X508645Y186634D02*
X513558D01*
G01X513118Y185574D02*
X518592Y180100D01*
G01X513558Y186634D02*
X519032Y181160D01*
G01X518592Y180100D02*
X536893D01*
G01X519032Y181160D02*
X537333D01*
G01X536893Y180100D02*
X565418Y151575D01*
G01X537333Y181160D02*
X565858Y152635D01*
G01X488537Y463213D02*
X529223D01*
G01X488977Y462153D02*
X529666D01*
G01X529223Y463213D02*
X540402Y474392D01*
G01X529664Y462154D02*
X541462Y473952D01*
G01X491209Y458346D02*
X514450D01*
G01X490769Y459406D02*
X514890D01*
G01X514450Y458346D02*
X515322Y457474D01*
G01X514890Y459406D02*
X516382Y457914D01*
G01X515322Y457474D02*
Y455709D01*
G01X516382Y457914D02*
Y456152D01*
G01X515322Y455709D02*
X516811Y454220D01*
G01X516382Y456152D02*
X517254Y455280D01*
G01X516811Y454220D02*
X519390D01*
G01X517254Y455280D02*
X518950D01*
G01X519390Y454220D02*
X520882Y455712D01*
G01X518950Y455280D02*
X519822Y456152D01*
G01X520882Y455712D02*
Y457328D01*
G01X519822Y456152D02*
Y457768D01*
G01X520882Y457328D02*
X521642Y458088D01*
G01X519822Y457768D02*
X521202Y459148D01*
G01X521642Y458088D02*
X523562D01*
G01X521202Y459148D02*
X524002D01*
G01X523562Y458088D02*
X524322Y457328D01*
G01X524002Y459148D02*
X525382Y457768D01*
G01X524322Y457328D02*
Y455712D01*
G01X525382Y457768D02*
Y456152D01*
G01X524322Y455712D02*
X525814Y454220D01*
G01X525382Y456152D02*
X526254Y455280D01*
G01X525814Y454220D02*
X528290D01*
G01D02*
X546535Y472465D01*
G01X526254Y455280D02*
X527850D01*
G01X528290Y454220D02*
X546535Y472465D01*
G01X527850Y455280D02*
X538592Y466022D01*
G01X528290Y454220D02*
X546535Y472465D01*
G01X528290Y454220D02*
X546535Y472465D01*
G01X528290Y454220D02*
X546535Y472465D01*
G01X528290Y454220D02*
X546535Y472465D01*
G01X528290Y454220D02*
X546535Y472465D01*
G01X528290Y454220D02*
X546535Y472465D01*
G01X488977Y462153D02*
X529666D01*
G01X488537Y463213D02*
X529223D01*
G01X529664Y462154D02*
X541462Y473952D01*
G01X529223Y463213D02*
X540402Y474392D01*
G01X490769Y459406D02*
X514890D01*
G01X491209Y458346D02*
X514450D01*
G01X514890Y459406D02*
X516382Y457914D01*
G01X514450Y458346D02*
X515322Y457474D01*
G01X516382Y457914D02*
Y456152D01*
G01X515322Y457474D02*
Y455709D01*
G01X516382Y456152D02*
X517254Y455280D01*
G01X515322Y455709D02*
X516811Y454220D01*
G01X517254Y455280D02*
X518950D01*
G01X516811Y454220D02*
X519390D01*
G01X518950Y455280D02*
X519822Y456152D01*
G01X519390Y454220D02*
X520882Y455712D01*
G01X519822Y456152D02*
Y457768D01*
G01X520882Y455712D02*
Y457328D01*
G01X519822Y457768D02*
X521202Y459148D01*
G01X520882Y457328D02*
X521642Y458088D01*
G01X521202Y459148D02*
X524002D01*
G01X521642Y458088D02*
X523562D01*
G01X524002Y459148D02*
X525382Y457768D01*
G01X523562Y458088D02*
X524322Y457328D01*
G01X525382Y457768D02*
Y456152D01*
G01X524322Y457328D02*
Y455712D01*
G01X525382Y456152D02*
X526254Y455280D01*
G01X524322Y455712D02*
X525814Y454220D01*
G01X526254Y455280D02*
X527850D01*
G01X525814Y454220D02*
X528290D01*
G01X526254Y455280D02*
X527850D01*
G01D02*
X538592Y466022D01*
G01X528290Y454220D02*
X546535Y472465D01*
G01X505262Y418100D02*
X509922Y422760D01*
G01X506013Y417351D02*
X510362Y421700D01*
G01X509922Y422760D02*
X525102D01*
G01X510362Y421700D02*
X525542D01*
G01X525102Y422760D02*
X528602Y426260D01*
G01X525542Y421700D02*
X529042Y425200D01*
G01X528602Y426260D02*
X535820D01*
G01X529042Y425200D02*
X536260D01*
G01X535820Y426260D02*
X581552Y471992D01*
G01X536260Y425200D02*
X582612Y471552D01*
G01X507512Y414500D02*
X511662Y418650D01*
G01X506642Y415130D02*
X511222Y419710D01*
G01X511662Y418650D02*
X526942D01*
G01X511222Y419710D02*
X526502D01*
G01X526942Y418650D02*
X530292Y422000D01*
G01X526502Y419710D02*
X529852Y423060D01*
G01X530292Y422000D02*
X538760D01*
G01X529852Y423060D02*
X538320D01*
G01X538760Y422000D02*
X572845Y456085D01*
G01X538320Y423060D02*
X572405Y457145D01*
G01X506013Y417351D02*
X510362Y421700D01*
G01X505262Y418100D02*
X509922Y422760D01*
G01X510362Y421700D02*
X525542D01*
G01X509922Y422760D02*
X525102D01*
G01X525542Y421700D02*
X529042Y425200D01*
G01X525102Y422760D02*
X528602Y426260D01*
G01X529042Y425200D02*
X536260D01*
G01X528602Y426260D02*
X535820D01*
G01X536260Y425200D02*
X582612Y471552D01*
G01X535820Y426260D02*
X581552Y471992D01*
G01X506642Y415130D02*
X511222Y419710D01*
G01X507512Y414500D02*
X511662Y418650D01*
G01X511222Y419710D02*
X526502D01*
G01X511662Y418650D02*
X526942D01*
G01X526502Y419710D02*
X529852Y423060D01*
G01X526942Y418650D02*
X530292Y422000D01*
G01X529852Y423060D02*
X538320D01*
G01X530292Y422000D02*
X538760D01*
G01X538320Y423060D02*
X572405Y457145D01*
G01X538760Y422000D02*
X572845Y456085D01*
G01X538320Y423060D02*
X572405Y457145D01*
G01X488537Y463213D02*
X529223D01*
G01X488977Y462153D02*
X529666D01*
G01X529223Y463213D02*
X540402Y474392D01*
G01X529664Y462154D02*
X541462Y473952D01*
G01X488977Y462153D02*
X529666D01*
G01X488537Y463213D02*
X529223D01*
G01X529664Y462154D02*
X541462Y473952D01*
G01X529223Y463213D02*
X540402Y474392D01*
G01X505262Y418100D02*
X509922Y422760D01*
G01X506013Y417351D02*
X510362Y421700D01*
G01X509922Y422760D02*
X525102D01*
G01X510362Y421700D02*
X525542D01*
G01X525102Y422760D02*
X528602Y426260D01*
G01X525542Y421700D02*
X529042Y425200D01*
G01X528602Y426260D02*
X535820D01*
G01X529042Y425200D02*
X536260D01*
G01X535820Y426260D02*
X581552Y471992D01*
G01X536260Y425200D02*
X582612Y471552D01*
G01X491209Y458346D02*
X514450D01*
G01X490769Y459406D02*
X514890D01*
G01X514450Y458346D02*
X515322Y457474D01*
G01X514890Y459406D02*
X516382Y457914D01*
G01X515322Y457474D02*
Y455709D01*
G01X516382Y457914D02*
Y456152D01*
G01X515322Y455709D02*
X516811Y454220D01*
G01X516382Y456152D02*
X517254Y455280D01*
G01X516811Y454220D02*
X519390D01*
G01X517254Y455280D02*
X518950D01*
G01X519390Y454220D02*
X520882Y455712D01*
G01X518950Y455280D02*
X519822Y456152D01*
G01X520882Y455712D02*
Y457328D01*
G01X519822Y456152D02*
Y457768D01*
G01X520882Y457328D02*
X521642Y458088D01*
G01X519822Y457768D02*
X521202Y459148D01*
G01X521642Y458088D02*
X523562D01*
G01X521202Y459148D02*
X524002D01*
G01X523562Y458088D02*
X524322Y457328D01*
G01X524002Y459148D02*
X525382Y457768D01*
G01X524322Y457328D02*
Y455712D01*
G01X525382Y457768D02*
Y456152D01*
G01X524322Y455712D02*
X525814Y454220D01*
G01X525382Y456152D02*
X526254Y455280D01*
G01X525814Y454220D02*
X528290D01*
G01D02*
X546535Y472465D01*
G01X526254Y455280D02*
X527850D01*
G01X528290Y454220D02*
X546535Y472465D01*
G01X527850Y455280D02*
X538592Y466022D01*
G01X528290Y454220D02*
X546535Y472465D01*
G01X528290Y454220D02*
X546535Y472465D01*
G01X528290Y454220D02*
X546535Y472465D01*
G01X528290Y454220D02*
X546535Y472465D01*
G01X528290Y454220D02*
X546535Y472465D01*
G01X528290Y454220D02*
X546535Y472465D01*
G01X507512Y414500D02*
X511662Y418650D01*
G01X506642Y415130D02*
X511222Y419710D01*
G01X511662Y418650D02*
X526942D01*
G01X511222Y419710D02*
X526502D01*
G01X526942Y418650D02*
X530292Y422000D01*
G01X526502Y419710D02*
X529852Y423060D01*
G01X530292Y422000D02*
X538760D01*
G01X529852Y423060D02*
X538320D01*
G01X538760Y422000D02*
X572845Y456085D01*
G01X538320Y423060D02*
X572405Y457145D01*
G01X506013Y417351D02*
X510362Y421700D01*
G01X505262Y418100D02*
X509922Y422760D01*
G01X510362Y421700D02*
X525542D01*
G01X509922Y422760D02*
X525102D01*
G01X525542Y421700D02*
X529042Y425200D01*
G01X525102Y422760D02*
X528602Y426260D01*
G01X529042Y425200D02*
X536260D01*
G01X528602Y426260D02*
X535820D01*
G01X536260Y425200D02*
X582612Y471552D01*
G01X535820Y426260D02*
X581552Y471992D01*
G01X490769Y459406D02*
X514890D01*
G01X491209Y458346D02*
X514450D01*
G01X514890Y459406D02*
X516382Y457914D01*
G01X514450Y458346D02*
X515322Y457474D01*
G01X516382Y457914D02*
Y456152D01*
G01X515322Y457474D02*
Y455709D01*
G01X516382Y456152D02*
X517254Y455280D01*
G01X515322Y455709D02*
X516811Y454220D01*
G01X517254Y455280D02*
X518950D01*
G01X516811Y454220D02*
X519390D01*
G01X518950Y455280D02*
X519822Y456152D01*
G01X519390Y454220D02*
X520882Y455712D01*
G01X519822Y456152D02*
Y457768D01*
G01X520882Y455712D02*
Y457328D01*
G01X519822Y457768D02*
X521202Y459148D01*
G01X520882Y457328D02*
X521642Y458088D01*
G01X521202Y459148D02*
X524002D01*
G01X521642Y458088D02*
X523562D01*
G01X524002Y459148D02*
X525382Y457768D01*
G01X523562Y458088D02*
X524322Y457328D01*
G01X525382Y457768D02*
Y456152D01*
G01X524322Y457328D02*
Y455712D01*
G01X525382Y456152D02*
X526254Y455280D01*
G01X524322Y455712D02*
X525814Y454220D01*
G01X526254Y455280D02*
X527850D01*
G01X525814Y454220D02*
X528290D01*
G01X526254Y455280D02*
X527850D01*
G01D02*
X538592Y466022D01*
G01X528290Y454220D02*
X546535Y472465D01*
G01X506642Y415130D02*
X511222Y419710D01*
G01X507512Y414500D02*
X511662Y418650D01*
G01X511222Y419710D02*
X526502D01*
G01X511662Y418650D02*
X526942D01*
G01X526502Y419710D02*
X529852Y423060D01*
G01X526942Y418650D02*
X530292Y422000D01*
G01X529852Y423060D02*
X538320D01*
G01X530292Y422000D02*
X538760D01*
G01X538320Y423060D02*
X572405Y457145D01*
G01X538760Y422000D02*
X572845Y456085D01*
G01X538320Y423060D02*
X572405Y457145D01*
G01X499556Y514336D02*
Y532411D01*
G01X500616Y520290D02*
Y521660D01*
G01X499556Y514336D02*
Y532411D01*
G01X500616Y525340D02*
Y526760D01*
G01X480055Y492692D02*
X481343Y493980D01*
G01X482806Y495443D02*
X483712Y496349D01*
G01X480495Y491632D02*
X484772Y495909D01*
G01X483712Y496349D02*
Y499241D01*
G01X484772Y495909D02*
Y498801D01*
G01X483712Y499241D02*
X486120Y501649D01*
G01X484772Y498801D02*
X486560Y500589D01*
G01X486120Y501649D02*
X487952D01*
G01X490192D02*
X491192D01*
G01X493432D02*
X494432D01*
G01X496672D02*
X497672D01*
G01X499912D02*
X501012D01*
G01X486560Y500589D02*
X501452D01*
G01X501012Y501649D02*
X503564Y504201D01*
G01X501452Y500589D02*
X504624Y503761D01*
G01X503564Y504201D02*
Y506922D01*
G01Y509162D02*
Y511780D01*
G01X504624Y503761D02*
Y512220D01*
G01X503564Y511780D02*
X502644Y512700D01*
G01X504624Y512220D02*
X501544Y515300D01*
G01X536367Y514400D02*
Y532411D01*
G01X537427Y520290D02*
Y521660D01*
G01X536367Y514400D02*
Y532411D01*
G01X537427Y525340D02*
Y526760D01*
G01X540402Y511753D02*
X539455Y512700D01*
G01X541462Y512193D02*
X538355Y515300D01*
G01X505840Y519900D02*
X505169Y520571D01*
G01X504939Y519300D02*
X504109Y520130D01*
G01X505169Y520571D02*
Y521848D01*
G01Y525338D02*
Y526229D01*
G01X504109Y520130D02*
Y526670D01*
G01X505169Y526229D02*
X505940Y527000D01*
G01X480747Y488524D02*
X481747D01*
G01X483987D02*
X484987D01*
G01X487227D02*
X488227D01*
G01X490467D02*
X491467D01*
G01X493707D02*
X497947D01*
G01X500187D02*
X501187D01*
G01X503427D02*
X504427D01*
G01X508365Y487464D02*
X510024Y489123D01*
G01X506667Y488524D02*
X507925D01*
G01X508365Y487464D02*
X510024Y489123D01*
G01X507925Y488524D02*
X508964Y489563D01*
G01X510024Y489123D02*
Y512134D01*
G01X508964Y489563D02*
Y492740D01*
G01X510024Y489123D02*
Y512134D01*
G01X508964Y494716D02*
Y496275D01*
G01X510024Y489123D02*
Y512134D01*
G01X508964Y498183D02*
Y500443D01*
G01X510024Y489123D02*
Y512134D01*
G01X508964Y502683D02*
Y503683D01*
G01X510024Y489123D02*
Y512134D01*
G01X508964Y505923D02*
Y506923D01*
G01X510024Y489123D02*
Y512134D01*
G01X508964Y509163D02*
Y511694D01*
G01X510024Y512134D02*
X506644Y515514D01*
G01X508964Y511694D02*
X507744Y512914D01*
G01X539320Y467600D02*
X540170D01*
G01X500616Y520290D02*
Y521660D01*
G01Y525340D02*
Y526760D01*
G01X499556Y514336D02*
Y532411D01*
G01X480495Y491632D02*
X484772Y495909D01*
G01X480055Y492692D02*
X481343Y493980D01*
G01X480495Y491632D02*
X484772Y495909D01*
G01X482806Y495443D02*
X483712Y496349D01*
G01X484772Y495909D02*
Y498801D01*
G01X483712Y496349D02*
Y499241D01*
G01X484772Y498801D02*
X486560Y500589D01*
G01X483712Y499241D02*
X486120Y501649D01*
G01X486560Y500589D02*
X501452D01*
G01X486120Y501649D02*
X487952D01*
G01X486560Y500589D02*
X501452D01*
G01X490192Y501649D02*
X491192D01*
G01X486560Y500589D02*
X501452D01*
G01X493432Y501649D02*
X494432D01*
G01X486560Y500589D02*
X501452D01*
G01X496672Y501649D02*
X497672D01*
G01X486560Y500589D02*
X501452D01*
G01X499912Y501649D02*
X501012D01*
G01X501452Y500589D02*
X504624Y503761D01*
G01X501012Y501649D02*
X503564Y504201D01*
G01X504624Y503761D02*
Y512220D01*
G01X503564Y504201D02*
Y506922D01*
G01X504624Y503761D02*
Y512220D01*
G01X503564Y509162D02*
Y511780D01*
G01X504624Y512220D02*
X501544Y515300D01*
G01X503564Y511780D02*
X502644Y512700D01*
G01X537427Y520290D02*
Y521660D01*
G01Y525340D02*
Y526760D01*
G01X536367Y514400D02*
Y532411D01*
G01X541462Y512193D02*
X538355Y515300D01*
G01X540402Y511753D02*
X539455Y512700D01*
G01X504939Y519300D02*
X504109Y520130D01*
G01X505840Y519900D02*
X505169Y520571D01*
G01X504109Y520130D02*
Y526670D01*
G01X505169Y520571D02*
Y521848D01*
G01X504109Y520130D02*
Y526670D01*
G01X505169Y525338D02*
Y526229D01*
G01D02*
X505940Y527000D01*
G01X480747Y488524D02*
X481747D01*
G01X483987D02*
X484987D01*
G01X487227D02*
X488227D01*
G01X490467D02*
X491467D01*
G01X493707D02*
X497947D01*
G01X500187D02*
X501187D01*
G01X503427D02*
X504427D01*
G01X506667D02*
X507925D01*
G01X506667D02*
X507925D01*
G01D02*
X508964Y489563D01*
G01X508365Y487464D02*
X510024Y489123D01*
G01X508964Y489563D02*
Y492740D01*
G01Y494716D02*
Y496275D01*
G01Y498183D02*
Y500443D01*
G01Y502683D02*
Y503683D01*
G01Y505923D02*
Y506923D01*
G01Y509163D02*
Y511694D01*
G01X510024Y489123D02*
Y512134D01*
G01X508964Y511694D02*
X507744Y512914D01*
G01X510024Y512134D02*
X506644Y515514D01*
G01X539320Y467600D02*
X540170D01*
G01X499556Y514336D02*
Y532411D01*
G01X500616Y520290D02*
Y521660D01*
G01X499556Y514336D02*
Y532411D01*
G01X500616Y525340D02*
Y526760D01*
G01X480055Y492692D02*
X481343Y493980D01*
G01X482806Y495443D02*
X483712Y496349D01*
G01X480495Y491632D02*
X484772Y495909D01*
G01X483712Y496349D02*
Y499241D01*
G01X484772Y495909D02*
Y498801D01*
G01X483712Y499241D02*
X486120Y501649D01*
G01X484772Y498801D02*
X486560Y500589D01*
G01X486120Y501649D02*
X487952D01*
G01X490192D02*
X491192D01*
G01X493432D02*
X494432D01*
G01X496672D02*
X497672D01*
G01X499912D02*
X501012D01*
G01X486560Y500589D02*
X501452D01*
G01X501012Y501649D02*
X503564Y504201D01*
G01X501452Y500589D02*
X504624Y503761D01*
G01X503564Y504201D02*
Y506922D01*
G01Y509162D02*
Y511780D01*
G01X504624Y503761D02*
Y512220D01*
G01X503564Y511780D02*
X502644Y512700D01*
G01X504624Y512220D02*
X501544Y515300D01*
G01X536367Y514400D02*
Y532411D01*
G01X537427Y520290D02*
Y521660D01*
G01X536367Y514400D02*
Y532411D01*
G01X537427Y525340D02*
Y526760D01*
G01X540402Y511753D02*
X539455Y512700D01*
G01X541462Y512193D02*
X538355Y515300D01*
G01X505840Y519900D02*
X505169Y520571D01*
G01X504939Y519300D02*
X504109Y520130D01*
G01X505169Y520571D02*
Y521848D01*
G01Y525338D02*
Y526229D01*
G01X504109Y520130D02*
Y526670D01*
G01X505169Y526229D02*
X505940Y527000D01*
G01X480747Y488524D02*
X481747D01*
G01X483987D02*
X484987D01*
G01X487227D02*
X488227D01*
G01X490467D02*
X491467D01*
G01X493707D02*
X497947D01*
G01X500187D02*
X501187D01*
G01X503427D02*
X504427D01*
G01X508365Y487464D02*
X510024Y489123D01*
G01X506667Y488524D02*
X507925D01*
G01X508365Y487464D02*
X510024Y489123D01*
G01X507925Y488524D02*
X508964Y489563D01*
G01X510024Y489123D02*
Y512134D01*
G01X508964Y489563D02*
Y492740D01*
G01X510024Y489123D02*
Y512134D01*
G01X508964Y494716D02*
Y496275D01*
G01X510024Y489123D02*
Y512134D01*
G01X508964Y498183D02*
Y500443D01*
G01X510024Y489123D02*
Y512134D01*
G01X508964Y502683D02*
Y503683D01*
G01X510024Y489123D02*
Y512134D01*
G01X508964Y505923D02*
Y506923D01*
G01X510024Y489123D02*
Y512134D01*
G01X508964Y509163D02*
Y511694D01*
G01X510024Y512134D02*
X506644Y515514D01*
G01X508964Y511694D02*
X507744Y512914D01*
G01X500616Y520290D02*
Y521660D01*
G01Y525340D02*
Y526760D01*
G01X499556Y514336D02*
Y532411D01*
G01X480495Y491632D02*
X484772Y495909D01*
G01X480055Y492692D02*
X481343Y493980D01*
G01X480495Y491632D02*
X484772Y495909D01*
G01X482806Y495443D02*
X483712Y496349D01*
G01X484772Y495909D02*
Y498801D01*
G01X483712Y496349D02*
Y499241D01*
G01X484772Y498801D02*
X486560Y500589D01*
G01X483712Y499241D02*
X486120Y501649D01*
G01X486560Y500589D02*
X501452D01*
G01X486120Y501649D02*
X487952D01*
G01X486560Y500589D02*
X501452D01*
G01X490192Y501649D02*
X491192D01*
G01X486560Y500589D02*
X501452D01*
G01X493432Y501649D02*
X494432D01*
G01X486560Y500589D02*
X501452D01*
G01X496672Y501649D02*
X497672D01*
G01X486560Y500589D02*
X501452D01*
G01X499912Y501649D02*
X501012D01*
G01X501452Y500589D02*
X504624Y503761D01*
G01X501012Y501649D02*
X503564Y504201D01*
G01X504624Y503761D02*
Y512220D01*
G01X503564Y504201D02*
Y506922D01*
G01X504624Y503761D02*
Y512220D01*
G01X503564Y509162D02*
Y511780D01*
G01X504624Y512220D02*
X501544Y515300D01*
G01X503564Y511780D02*
X502644Y512700D01*
G01X537427Y520290D02*
Y521660D01*
G01Y525340D02*
Y526760D01*
G01X536367Y514400D02*
Y532411D01*
G01X541462Y512193D02*
X538355Y515300D01*
G01X540402Y511753D02*
X539455Y512700D01*
G01X504939Y519300D02*
X504109Y520130D01*
G01X505840Y519900D02*
X505169Y520571D01*
G01X504109Y520130D02*
Y526670D01*
G01X505169Y520571D02*
Y521848D01*
G01X504109Y520130D02*
Y526670D01*
G01X505169Y525338D02*
Y526229D01*
G01D02*
X505940Y527000D01*
G01X480747Y488524D02*
X481747D01*
G01X483987D02*
X484987D01*
G01X487227D02*
X488227D01*
G01X490467D02*
X491467D01*
G01X493707D02*
X497947D01*
G01X500187D02*
X501187D01*
G01X503427D02*
X504427D01*
G01X506667D02*
X507925D01*
G01X506667D02*
X507925D01*
G01D02*
X508964Y489563D01*
G01X508365Y487464D02*
X510024Y489123D01*
G01X508964Y489563D02*
Y492740D01*
G01Y494716D02*
Y496275D01*
G01Y498183D02*
Y500443D01*
G01Y502683D02*
Y503683D01*
G01Y505923D02*
Y506923D01*
G01Y509163D02*
Y511694D01*
G01X510024Y489123D02*
Y512134D01*
G01X508964Y511694D02*
X507744Y512914D01*
G01X510024Y512134D02*
X506644Y515514D01*
G01X539320Y467600D02*
X540170D01*
G01X539320D02*
X540170D01*
G01X504109Y526670D02*
X504939Y527500D01*
G01X504109Y526670D02*
X504939Y527500D01*
G01X504109Y526670D02*
X504939Y527500D01*
G01X504109Y526670D02*
X504939Y527500D01*
G01X777571Y-42660D02*
X583560D01*
G01X777571Y-43720D02*
X583560D01*
G01Y-42660D02*
G03Y-47440I0J-2390D01*
G01Y-43720D02*
G03Y-46380I0J-1330D01*
G01Y-47440D02*
X777171D01*
G01X583560Y-46380D02*
X777171D01*
G01Y-50100D02*
X576480D01*
G01X777171Y-51160D02*
X576040D01*
G01X576480Y-50100D02*
X573151Y-46771D01*
G01X576040Y-51160D02*
X572711Y-47831D01*
G01X777571Y-43720D02*
X583560D01*
G01X777571Y-42660D02*
X583560D01*
G01Y-43720D02*
G03Y-46380I0J-1330D01*
G01Y-42660D02*
G03Y-47440I0J-2390D01*
G01Y-46380D02*
X777171D01*
G01X583560Y-47440D02*
X777171D01*
G01Y-51160D02*
X576040D01*
G01X777171Y-50100D02*
X576480D01*
G01X576040Y-51160D02*
X572711Y-47831D01*
G01X576480Y-50100D02*
X573151Y-46771D01*
G01X540989Y87266D02*
X541461Y86794D01*
G01X540401Y86355D02*
Y83820D01*
G01Y79680D02*
Y78720D01*
G01Y74380D02*
Y71091D01*
G01X541461Y86794D02*
Y70648D01*
G01D02*
X540133Y69320D01*
G01X544530Y89038D02*
X546303Y87266D01*
G01X543455Y87515D02*
X544553D01*
G01X544530Y89038D02*
X546303Y87266D01*
G01D02*
X546647Y86922D01*
G01X544553Y87515D02*
X545587Y86481D01*
G01X546647Y86922D02*
Y71532D01*
G01X545587Y86481D02*
Y83706D01*
G01X546647Y86922D02*
Y71532D01*
G01X545587Y79880D02*
Y78507D01*
G01X546647Y86922D02*
Y71532D01*
G01X545587Y74593D02*
Y71972D01*
G01X546647Y71532D02*
X543455Y68340D01*
G01X545587Y71972D02*
X544564Y70949D01*
G01X541701Y96976D02*
Y89268D01*
G01X540989Y87266D02*
X541461Y86794D01*
G01D02*
Y70648D01*
G01X540401Y86355D02*
Y83820D01*
G01X541461Y86794D02*
Y70648D01*
G01X540401Y79680D02*
Y78720D01*
G01X541461Y86794D02*
Y70648D01*
G01X540401Y74380D02*
Y71091D01*
G01X541461Y70648D02*
X540133Y69320D01*
G01X575166Y89900D02*
X578272Y86794D01*
G01X575166Y87300D02*
X576265D01*
G01X575166Y89900D02*
X578272Y86794D01*
G01X576265Y87300D02*
X577212Y86353D01*
G01X578272Y86794D02*
Y70648D01*
G01X577212Y86353D02*
Y83820D01*
G01X578272Y86794D02*
Y70648D01*
G01X577212Y79680D02*
Y78720D01*
G01X578272Y86794D02*
Y70648D01*
G01X577212Y74380D02*
Y71091D01*
G01X578272Y70648D02*
X576944Y69320D01*
G01X577212Y71091D02*
X576501Y70380D01*
G01X578272Y70648D02*
X576944Y69320D01*
G01D02*
X575962D01*
G01X576501Y70380D02*
X575985D01*
G01X573592Y96900D02*
Y93661D01*
G01X543455Y87515D02*
X544553D01*
G01D02*
X545587Y86481D01*
G01X544530Y89038D02*
X546303Y87266D01*
G01X544553Y87515D02*
X545587Y86481D01*
G01X546303Y87266D02*
X546647Y86922D01*
G01X545587Y86481D02*
Y83706D01*
G01Y79880D02*
Y78507D01*
G01Y74593D02*
Y71972D01*
G01X546647Y86922D02*
Y71532D01*
G01X545587Y71972D02*
X544564Y70949D01*
G01X546647Y71532D02*
X543455Y68340D01*
G01X541701Y96976D02*
Y89268D01*
G01X540989Y87266D02*
X541461Y86794D01*
G01X540401Y86355D02*
Y83820D01*
G01Y79680D02*
Y78720D01*
G01Y74380D02*
Y71091D01*
G01X541461Y86794D02*
Y70648D01*
G01D02*
X540133Y69320D01*
G01X540989Y87266D02*
X541461Y86794D01*
G01D02*
Y70648D01*
G01X540401Y86355D02*
Y83820D01*
G01X541461Y86794D02*
Y70648D01*
G01X540401Y79680D02*
Y78720D01*
G01X541461Y86794D02*
Y70648D01*
G01X540401Y74380D02*
Y71091D01*
G01X541461Y70648D02*
X540133Y69320D01*
G01X575166Y87300D02*
X576265D01*
G01D02*
X577212Y86353D01*
G01X575166Y89900D02*
X578272Y86794D01*
G01X577212Y86353D02*
Y83820D01*
G01Y79680D02*
Y78720D01*
G01Y74380D02*
Y71091D01*
G01X578272Y86794D02*
Y70648D01*
G01X577212Y71091D02*
X576501Y70380D01*
G01D02*
X575985D01*
G01X578272Y70648D02*
X576944Y69320D01*
G01X576501Y70380D02*
X575985D01*
G01X576944Y69320D02*
X575962D01*
G01X573592Y96900D02*
Y93661D01*
G01X580266Y90114D02*
X583458Y86922D01*
G01X580266Y87515D02*
X581364D01*
G01X580266Y90114D02*
X583458Y86922D01*
G01X581364Y87515D02*
X582398Y86481D01*
G01X583458Y86922D02*
Y71532D01*
G01X582398Y86481D02*
Y83706D01*
G01X583458Y86922D02*
Y71532D01*
G01X582398Y79880D02*
Y78507D01*
G01X583458Y86922D02*
Y71532D01*
G01X582398Y74593D02*
Y71972D01*
G01X583458Y71532D02*
X580266Y68340D01*
G01X582398Y71972D02*
X581375Y70949D01*
G01X578542Y96350D02*
Y89238D01*
G01X580266Y87515D02*
X581364D01*
G01D02*
X582398Y86481D01*
G01X580266Y90114D02*
X583458Y86922D01*
G01X582398Y86481D02*
Y83706D01*
G01Y79880D02*
Y78507D01*
G01Y74593D02*
Y71972D01*
G01X583458Y86922D02*
Y71532D01*
G01X582398Y71972D02*
X581375Y70949D01*
G01X583458Y71532D02*
X580266Y68340D01*
G01X578542Y96350D02*
Y89238D01*
G01X575166Y87300D02*
X576265D01*
G01D02*
X577212Y86353D01*
G01X575166Y89900D02*
X578272Y86794D01*
G01X577212Y86353D02*
Y83820D01*
G01Y79680D02*
Y78720D01*
G01Y74380D02*
Y71091D01*
G01X578272Y86794D02*
Y70648D01*
G01X577212Y71091D02*
X576501Y70380D01*
G01D02*
X575985D01*
G01X578272Y70648D02*
X576944Y69320D01*
G01X576501Y70380D02*
X575985D01*
G01X576944Y69320D02*
X575962D01*
G01X573592Y96900D02*
Y93661D01*
G01X544530Y89038D02*
X546303Y87266D01*
G01X543455Y87515D02*
X544553D01*
G01X544530Y89038D02*
X546303Y87266D01*
G01D02*
X546647Y86922D01*
G01X544553Y87515D02*
X545587Y86481D01*
G01X546647Y86922D02*
Y71532D01*
G01X545587Y86481D02*
Y83706D01*
G01X546647Y86922D02*
Y71532D01*
G01X545587Y79880D02*
Y78507D01*
G01X546647Y86922D02*
Y71532D01*
G01X545587Y74593D02*
Y71972D01*
G01X546647Y71532D02*
X543455Y68340D01*
G01X545587Y71972D02*
X544564Y70949D01*
G01X541701Y96976D02*
Y89268D01*
G01X580266Y90114D02*
X583458Y86922D01*
G01X580266Y87515D02*
X581364D01*
G01X580266Y90114D02*
X583458Y86922D01*
G01X581364Y87515D02*
X582398Y86481D01*
G01X583458Y86922D02*
Y71532D01*
G01X582398Y86481D02*
Y83706D01*
G01X583458Y86922D02*
Y71532D01*
G01X582398Y79880D02*
Y78507D01*
G01X583458Y86922D02*
Y71532D01*
G01X582398Y74593D02*
Y71972D01*
G01X583458Y71532D02*
X580266Y68340D01*
G01X582398Y71972D02*
X581375Y70949D01*
G01X578542Y96350D02*
Y89238D01*
G01X575166Y89900D02*
X578272Y86794D01*
G01X575166Y87300D02*
X576265D01*
G01X575166Y89900D02*
X578272Y86794D01*
G01X576265Y87300D02*
X577212Y86353D01*
G01X578272Y86794D02*
Y70648D01*
G01X577212Y86353D02*
Y83820D01*
G01X578272Y86794D02*
Y70648D01*
G01X577212Y79680D02*
Y78720D01*
G01X578272Y86794D02*
Y70648D01*
G01X577212Y74380D02*
Y71091D01*
G01X578272Y70648D02*
X576944Y69320D01*
G01X577212Y71091D02*
X576501Y70380D01*
G01X578272Y70648D02*
X576944Y69320D01*
G01D02*
X575962D01*
G01X576501Y70380D02*
X575985D01*
G01X573592Y96900D02*
Y93661D01*
G01X543455Y87515D02*
X544553D01*
G01D02*
X545587Y86481D01*
G01X544530Y89038D02*
X546303Y87266D01*
G01X544553Y87515D02*
X545587Y86481D01*
G01X546303Y87266D02*
X546647Y86922D01*
G01X545587Y86481D02*
Y83706D01*
G01Y79880D02*
Y78507D01*
G01Y74593D02*
Y71972D01*
G01X546647Y86922D02*
Y71532D01*
G01X545587Y71972D02*
X544564Y70949D01*
G01X546647Y71532D02*
X543455Y68340D01*
G01X541701Y96976D02*
Y89268D01*
G01X580266Y87515D02*
X581364D01*
G01D02*
X582398Y86481D01*
G01X580266Y90114D02*
X583458Y86922D01*
G01X582398Y86481D02*
Y83706D01*
G01Y79880D02*
Y78507D01*
G01Y74593D02*
Y71972D01*
G01X583458Y86922D02*
Y71532D01*
G01X582398Y71972D02*
X581375Y70949D01*
G01X583458Y71532D02*
X580266Y68340D01*
G01X578542Y96350D02*
Y89238D01*
G01X540386Y120807D02*
Y101464D01*
G01X541446Y121247D02*
Y118420D01*
G01X540386Y120807D02*
Y101464D01*
G01X541446Y116180D02*
Y104093D01*
G01X540386Y120807D02*
Y101464D01*
G01X541446Y101853D02*
Y101021D01*
G01X546546Y121246D02*
Y100321D01*
G01X545486Y120806D02*
Y100761D01*
G01X546546Y100321D02*
X542761Y96536D01*
G01X545486Y100761D02*
X541701Y96976D01*
G01X542761Y96536D02*
Y95281D01*
G01X541446Y121247D02*
Y118420D01*
G01Y116180D02*
Y104093D01*
G01Y101853D02*
Y101021D01*
G01X540386Y120807D02*
Y101464D01*
G01X563891Y148301D02*
X574691D01*
G01X563451Y147241D02*
X574251D01*
G01X574691Y148301D02*
X577452Y145540D01*
G01X574251Y147241D02*
X576392Y145100D01*
G01X577452Y145540D02*
Y104150D01*
G01X576392Y145100D02*
Y99700D01*
G01X577902Y99710D02*
X574652Y96460D01*
G01X576392Y99700D02*
X573592Y96900D01*
G01X574652Y96460D02*
Y94940D01*
G01X545486Y120806D02*
Y100761D01*
G01X546546Y121246D02*
Y100321D01*
G01X545486Y100761D02*
X541701Y96976D01*
G01X546546Y100321D02*
X542761Y96536D01*
G01D02*
Y95281D01*
G01X540386Y120807D02*
Y101464D01*
G01X541446Y121247D02*
Y118420D01*
G01X540386Y120807D02*
Y101464D01*
G01X541446Y116180D02*
Y104093D01*
G01X540386Y120807D02*
Y101464D01*
G01X541446Y101853D02*
Y101021D01*
G01Y121247D02*
Y118420D01*
G01Y116180D02*
Y104093D01*
G01Y101853D02*
Y101021D01*
G01X540386Y120807D02*
Y101464D01*
G01X563451Y147241D02*
X574251D01*
G01X563891Y148301D02*
X574691D01*
G01X574251Y147241D02*
X576392Y145100D01*
G01X574691Y148301D02*
X577452Y145540D01*
G01X576392Y145100D02*
Y99700D01*
G01X577452Y145540D02*
Y104150D01*
G01X576392Y99700D02*
X573592Y96900D01*
G01X577902Y99710D02*
X574652Y96460D01*
G01D02*
Y94940D01*
G01X565858Y152635D02*
X576157D01*
G01X565418Y151575D02*
X575717D01*
G01X576157Y152635D02*
X581452Y147340D01*
G01X575717Y151575D02*
X580392Y146900D01*
G01X581452Y147340D02*
Y97760D01*
G01X580392Y146900D02*
Y98200D01*
G01X581452Y97760D02*
X579602Y95910D01*
G01X580392Y98200D02*
X578542Y96350D01*
G01X579602Y95910D02*
Y95290D01*
G01X565418Y151575D02*
X575717D01*
G01X565858Y152635D02*
X576157D01*
G01X575717Y151575D02*
X580392Y146900D01*
G01X576157Y152635D02*
X581452Y147340D01*
G01X580392Y146900D02*
Y98200D01*
G01X581452Y147340D02*
Y97760D01*
G01X580392Y98200D02*
X578542Y96350D01*
G01X581452Y97760D02*
X579602Y95910D01*
G01D02*
Y95290D01*
G01X563451Y147241D02*
X574251D01*
G01X563891Y148301D02*
X574691D01*
G01X574251Y147241D02*
X576392Y145100D01*
G01X574691Y148301D02*
X577452Y145540D01*
G01X576392Y145100D02*
Y99700D01*
G01X577452Y145540D02*
Y104150D01*
G01X576392Y99700D02*
X573592Y96900D01*
G01X577902Y99710D02*
X574652Y96460D01*
G01D02*
Y94940D01*
G01X546546Y121246D02*
Y100321D01*
G01X545486Y120806D02*
Y100761D01*
G01X546546Y100321D02*
X542761Y96536D01*
G01X545486Y100761D02*
X541701Y96976D01*
G01X542761Y96536D02*
Y95281D01*
G01X565858Y152635D02*
X576157D01*
G01X565418Y151575D02*
X575717D01*
G01X576157Y152635D02*
X581452Y147340D01*
G01X575717Y151575D02*
X580392Y146900D01*
G01X581452Y147340D02*
Y97760D01*
G01X580392Y146900D02*
Y98200D01*
G01X581452Y97760D02*
X579602Y95910D01*
G01X580392Y98200D02*
X578542Y96350D01*
G01X579602Y95910D02*
Y95290D01*
G01X563891Y148301D02*
X574691D01*
G01X563451Y147241D02*
X574251D01*
G01X574691Y148301D02*
X577452Y145540D01*
G01X574251Y147241D02*
X576392Y145100D01*
G01X577452Y145540D02*
Y104150D01*
G01X576392Y145100D02*
Y99700D01*
G01X577902Y99710D02*
X574652Y96460D01*
G01X576392Y99700D02*
X573592Y96900D01*
G01X574652Y96460D02*
Y94940D01*
G01X545486Y120806D02*
Y100761D01*
G01X546546Y121246D02*
Y100321D01*
G01X545486Y100761D02*
X541701Y96976D01*
G01X546546Y100321D02*
X542761Y96536D01*
G01D02*
Y95281D01*
G01X565418Y151575D02*
X575717D01*
G01X565858Y152635D02*
X576157D01*
G01X575717Y151575D02*
X580392Y146900D01*
G01X576157Y152635D02*
X581452Y147340D01*
G01X580392Y146900D02*
Y98200D01*
G01X581452Y147340D02*
Y97760D01*
G01X580392Y98200D02*
X578542Y96350D01*
G01X581452Y97760D02*
X579602Y95910D01*
G01D02*
Y95290D01*
G01X572845Y456085D02*
X574076D01*
G01X572845D02*
X574076D01*
G01X572405Y457145D02*
X574519D01*
G01X572845Y456085D02*
X574076D01*
G01D02*
X575137Y455024D01*
G01X574519Y457145D02*
X575580Y456084D01*
G01X575137Y455024D02*
X577249D01*
G01X575580Y456084D02*
X576806D01*
G01X577249Y455024D02*
X579640Y457415D01*
G01X576806Y456084D02*
X578580Y457858D01*
G01X579640Y457415D02*
Y459527D01*
G01X578580Y457858D02*
Y459084D01*
G01X579640Y459527D02*
X578672Y460495D01*
G01X578580Y459084D02*
X577612Y460052D01*
G01X578672Y460495D02*
Y461909D01*
G01X577612Y460052D02*
Y462349D01*
G01X578672Y461909D02*
X580348Y463585D01*
G01X577612Y462349D02*
X579908Y464645D01*
G01X580348Y463585D02*
X581579D01*
G01X579908Y464645D02*
X582019D01*
G01X580348Y463585D02*
X581579D01*
G01D02*
X582697Y462467D01*
G01X582019Y464645D02*
X583137Y463527D01*
G01X582697Y462467D02*
X584808D01*
G01X583137Y463527D02*
X584368D01*
G01X584808Y462467D02*
X587572Y465231D01*
G01X584368Y463527D02*
X586512Y465671D01*
G01X572405Y457145D02*
X574519D01*
G01D02*
X575580Y456084D01*
G01X572845Y456085D02*
X574076D01*
G01X574519Y457145D02*
X575580Y456084D01*
G01X574076Y456085D02*
X575137Y455024D01*
G01X575580Y456084D02*
X576806D01*
G01X575137Y455024D02*
X577249D01*
G01X576806Y456084D02*
X578580Y457858D01*
G01X577249Y455024D02*
X579640Y457415D01*
G01X578580Y457858D02*
Y459084D01*
G01X579640Y457415D02*
Y459527D01*
G01X578580Y459084D02*
X577612Y460052D01*
G01X579640Y459527D02*
X578672Y460495D01*
G01X577612Y460052D02*
Y462349D01*
G01X578672Y460495D02*
Y461909D01*
G01X577612Y462349D02*
X579908Y464645D01*
G01X578672Y461909D02*
X580348Y463585D01*
G01X579908Y464645D02*
X582019D01*
G01D02*
X583137Y463527D01*
G01X580348Y463585D02*
X581579D01*
G01X582019Y464645D02*
X583137Y463527D01*
G01X581579Y463585D02*
X582697Y462467D01*
G01X583137Y463527D02*
X584368D01*
G01X582697Y462467D02*
X584808D01*
G01X584368Y463527D02*
X586512Y465671D01*
G01X584808Y462467D02*
X587572Y465231D01*
G01X572845Y456085D02*
X574076D01*
G01X572845D02*
X574076D01*
G01X572405Y457145D02*
X574519D01*
G01X572845Y456085D02*
X574076D01*
G01D02*
X575137Y455024D01*
G01X574519Y457145D02*
X575580Y456084D01*
G01X575137Y455024D02*
X577249D01*
G01X575580Y456084D02*
X576806D01*
G01X577249Y455024D02*
X579640Y457415D01*
G01X576806Y456084D02*
X578580Y457858D01*
G01X579640Y457415D02*
Y459527D01*
G01X578580Y457858D02*
Y459084D01*
G01X579640Y459527D02*
X578672Y460495D01*
G01X578580Y459084D02*
X577612Y460052D01*
G01X578672Y460495D02*
Y461909D01*
G01X577612Y460052D02*
Y462349D01*
G01X578672Y461909D02*
X580348Y463585D01*
G01X577612Y462349D02*
X579908Y464645D01*
G01X580348Y463585D02*
X581579D01*
G01X579908Y464645D02*
X582019D01*
G01X580348Y463585D02*
X581579D01*
G01D02*
X582697Y462467D01*
G01X582019Y464645D02*
X583137Y463527D01*
G01X582697Y462467D02*
X584808D01*
G01X583137Y463527D02*
X584368D01*
G01X584808Y462467D02*
X587572Y465231D01*
G01X584368Y463527D02*
X586512Y465671D01*
G01X572405Y457145D02*
X574519D01*
G01D02*
X575580Y456084D01*
G01X572845Y456085D02*
X574076D01*
G01X574519Y457145D02*
X575580Y456084D01*
G01X574076Y456085D02*
X575137Y455024D01*
G01X575580Y456084D02*
X576806D01*
G01X575137Y455024D02*
X577249D01*
G01X576806Y456084D02*
X578580Y457858D01*
G01X577249Y455024D02*
X579640Y457415D01*
G01X578580Y457858D02*
Y459084D01*
G01X579640Y457415D02*
Y459527D01*
G01X578580Y459084D02*
X577612Y460052D01*
G01X579640Y459527D02*
X578672Y460495D01*
G01X577612Y460052D02*
Y462349D01*
G01X578672Y460495D02*
Y461909D01*
G01X577612Y462349D02*
X579908Y464645D01*
G01X578672Y461909D02*
X580348Y463585D01*
G01X579908Y464645D02*
X582019D01*
G01D02*
X583137Y463527D01*
G01X580348Y463585D02*
X581579D01*
G01X582019Y464645D02*
X583137Y463527D01*
G01X581579Y463585D02*
X582697Y462467D01*
G01X583137Y463527D02*
X584368D01*
G01X582697Y462467D02*
X584808D01*
G01X584368Y463527D02*
X586512Y465671D01*
G01X584808Y462467D02*
X587572Y465231D01*
G01X540402Y474392D02*
Y506416D01*
G01Y508656D02*
Y511753D01*
G01X541462Y473952D02*
Y512193D01*
G01X542651Y519900D02*
X541980Y520571D01*
G01X541750Y519300D02*
X540920Y520130D01*
G01X541980Y520571D02*
Y521848D01*
G01Y525338D02*
Y526229D01*
G01X540920Y520130D02*
Y526670D01*
G01X541980Y526229D02*
X542751Y527000D01*
G01X540170Y467600D02*
X540992Y468422D01*
G01X541720Y470000D02*
X542570D01*
G01D02*
X543292Y470722D01*
G01X543920Y472200D02*
X544770D01*
G01D02*
X545475Y472905D01*
G01X546535Y472465D02*
Y512434D01*
G01X545475Y472905D02*
Y474980D01*
G01X546535Y472465D02*
Y512434D01*
G01X545475Y477100D02*
Y478220D01*
G01X546535Y472465D02*
Y512434D01*
G01X545475Y480340D02*
Y481460D01*
G01X546535Y472465D02*
Y512434D01*
G01X545475Y483580D02*
Y484700D01*
G01X546535Y472465D02*
Y512434D01*
G01X545475Y486820D02*
Y487940D01*
G01X546535Y472465D02*
Y512434D01*
G01X545475Y490060D02*
Y499816D01*
G01X546535Y472465D02*
Y512434D01*
G01X545475Y502284D02*
Y503516D01*
G01X546535Y472465D02*
Y512434D01*
G01X545475Y505784D02*
Y506916D01*
G01X546535Y472465D02*
Y512434D01*
G01X545475Y509260D02*
Y511994D01*
G01X546535Y512434D02*
X543455Y515514D01*
G01X545475Y511994D02*
X544359Y513110D01*
G01X541462Y473952D02*
Y512193D01*
G01X540402Y474392D02*
Y506416D01*
G01X541462Y473952D02*
Y512193D01*
G01X540402Y508656D02*
Y511753D01*
G01X541750Y519300D02*
X540920Y520130D01*
G01X542651Y519900D02*
X541980Y520571D01*
G01X540920Y520130D02*
Y526670D01*
G01X541980Y520571D02*
Y521848D01*
G01X540920Y520130D02*
Y526670D01*
G01X541980Y525338D02*
Y526229D01*
G01D02*
X542751Y527000D01*
G01X540170Y467600D02*
X540992Y468422D01*
G01X541720Y470000D02*
X542570D01*
G01D02*
X543292Y470722D01*
G01X543920Y472200D02*
X544770D01*
G01D02*
X545475Y472905D01*
G01D02*
Y474980D01*
G01Y477100D02*
Y478220D01*
G01Y480340D02*
Y481460D01*
G01Y483580D02*
Y484700D01*
G01Y486820D02*
Y487940D01*
G01Y490060D02*
Y499816D01*
G01Y502284D02*
Y503516D01*
G01Y505784D02*
Y506916D01*
G01Y509260D02*
Y511994D01*
G01X546535Y472465D02*
Y512434D01*
G01X545475Y511994D02*
X544359Y513110D01*
G01X546535Y512434D02*
X543455Y515514D01*
G01X573178Y514400D02*
Y532411D01*
G01X574238Y520290D02*
Y521660D01*
G01X573178Y514400D02*
Y532411D01*
G01X574238Y525340D02*
Y526760D01*
G01X581552Y471992D02*
Y479951D01*
G01Y481883D02*
Y483059D01*
G01Y485299D02*
Y486299D01*
G01Y488539D02*
Y489539D01*
G01Y491779D02*
Y492779D01*
G01Y495019D02*
Y496019D01*
G01Y498259D02*
Y499259D01*
G01Y501499D02*
Y502711D01*
G01X582612Y471552D02*
Y503151D01*
G01X581552Y502711D02*
X580191Y504072D01*
G01X578904Y505359D02*
X577286Y506977D01*
G01X582612Y503151D02*
X578346Y507417D01*
G01X577286Y506977D02*
Y511680D01*
G01X578346Y507417D02*
Y512120D01*
G01X577286Y511680D02*
X576266Y512700D01*
G01X578346Y512120D02*
X575166Y515300D01*
G01X579462Y519900D02*
X578791Y520571D01*
G01X578561Y519300D02*
X577731Y520130D01*
G01X578791Y520571D02*
Y521848D01*
G01Y525338D02*
Y526229D01*
G01X577731Y520130D02*
Y526670D01*
G01X578791Y526229D02*
X579562Y527000D01*
G01X587572Y465231D02*
Y504743D01*
G01X586512Y465671D02*
Y484732D01*
G01X587572Y465231D02*
Y504743D01*
G01X586512Y486972D02*
Y487972D01*
G01X587572Y465231D02*
Y504743D01*
G01X586512Y490212D02*
Y491212D01*
G01X587572Y465231D02*
Y504743D01*
G01X586512Y493452D02*
Y494452D01*
G01X587572Y465231D02*
Y504743D01*
G01X586512Y496692D02*
Y497692D01*
G01X587572Y465231D02*
Y504743D01*
G01X586512Y499932D02*
Y500932D01*
G01X587572Y465231D02*
Y504743D01*
G01X586512Y503172D02*
Y504303D01*
G01X587572Y504743D02*
X583726Y508589D01*
G01X586512Y504303D02*
X585058Y505757D01*
G01X587572Y504743D02*
X583726Y508589D01*
G01X583836Y506979D02*
X582666Y508149D01*
G01X583726Y508589D02*
Y512054D01*
G01X582666Y508149D02*
Y511614D01*
G01X583726Y512054D02*
X580266Y515514D01*
G01X582666Y511614D02*
X581366Y512914D01*
G01X574238Y520290D02*
Y521660D01*
G01Y525340D02*
Y526760D01*
G01X573178Y514400D02*
Y532411D01*
G01X582612Y471552D02*
Y503151D01*
G01X581552Y471992D02*
Y479951D01*
G01X582612Y471552D02*
Y503151D01*
G01X581552Y481883D02*
Y483059D01*
G01X582612Y471552D02*
Y503151D01*
G01X581552Y485299D02*
Y486299D01*
G01X582612Y471552D02*
Y503151D01*
G01X581552Y488539D02*
Y489539D01*
G01X582612Y471552D02*
Y503151D01*
G01X581552Y491779D02*
Y492779D01*
G01X582612Y471552D02*
Y503151D01*
G01X581552Y495019D02*
Y496019D01*
G01X582612Y471552D02*
Y503151D01*
G01X581552Y498259D02*
Y499259D01*
G01X582612Y471552D02*
Y503151D01*
G01X581552Y501499D02*
Y502711D01*
G01X582612Y503151D02*
X578346Y507417D01*
G01X581552Y502711D02*
X580191Y504072D01*
G01X582612Y503151D02*
X578346Y507417D01*
G01X578904Y505359D02*
X577286Y506977D01*
G01X578346Y507417D02*
Y512120D01*
G01X577286Y506977D02*
Y511680D01*
G01X578346Y512120D02*
X575166Y515300D01*
G01X577286Y511680D02*
X576266Y512700D01*
G01X578561Y519300D02*
X577731Y520130D01*
G01X579462Y519900D02*
X578791Y520571D01*
G01X577731Y520130D02*
Y526670D01*
G01X578791Y520571D02*
Y521848D01*
G01X577731Y520130D02*
Y526670D01*
G01X578791Y525338D02*
Y526229D01*
G01D02*
X579562Y527000D01*
G01X586512Y465671D02*
Y484732D01*
G01Y486972D02*
Y487972D01*
G01Y490212D02*
Y491212D01*
G01Y493452D02*
Y494452D01*
G01Y496692D02*
Y497692D01*
G01Y499932D02*
Y500932D01*
G01Y503172D02*
Y504303D01*
G01X587572Y465231D02*
Y504743D01*
G01X586512Y504303D02*
X585058Y505757D01*
G01X583836Y506979D02*
X582666Y508149D01*
G01X587572Y504743D02*
X583726Y508589D01*
G01X582666Y508149D02*
Y511614D01*
G01X583726Y508589D02*
Y512054D01*
G01X582666Y511614D02*
X581366Y512914D01*
G01X583726Y512054D02*
X580266Y515514D01*
G01X540402Y474392D02*
Y506416D01*
G01Y508656D02*
Y511753D01*
G01X541462Y473952D02*
Y512193D01*
G01Y473952D02*
Y512193D01*
G01X540402Y474392D02*
Y506416D01*
G01X541462Y473952D02*
Y512193D01*
G01X540402Y508656D02*
Y511753D01*
G01X573178Y514400D02*
Y532411D01*
G01X574238Y520290D02*
Y521660D01*
G01X573178Y514400D02*
Y532411D01*
G01X574238Y525340D02*
Y526760D01*
G01X581552Y471992D02*
Y479951D01*
G01Y481883D02*
Y483059D01*
G01Y485299D02*
Y486299D01*
G01Y488539D02*
Y489539D01*
G01Y491779D02*
Y492779D01*
G01Y495019D02*
Y496019D01*
G01Y498259D02*
Y499259D01*
G01Y501499D02*
Y502711D01*
G01X582612Y471552D02*
Y503151D01*
G01X581552Y502711D02*
X580191Y504072D01*
G01X578904Y505359D02*
X577286Y506977D01*
G01X582612Y503151D02*
X578346Y507417D01*
G01X577286Y506977D02*
Y511680D01*
G01X578346Y507417D02*
Y512120D01*
G01X577286Y511680D02*
X576266Y512700D01*
G01X578346Y512120D02*
X575166Y515300D01*
G01X542651Y519900D02*
X541980Y520571D01*
G01X541750Y519300D02*
X540920Y520130D01*
G01X541980Y520571D02*
Y521848D01*
G01Y525338D02*
Y526229D01*
G01X540920Y520130D02*
Y526670D01*
G01X541980Y526229D02*
X542751Y527000D01*
G01X540170Y467600D02*
X540992Y468422D01*
G01X541720Y470000D02*
X542570D01*
G01D02*
X543292Y470722D01*
G01X543920Y472200D02*
X544770D01*
G01D02*
X545475Y472905D01*
G01X546535Y472465D02*
Y512434D01*
G01X545475Y472905D02*
Y474980D01*
G01X546535Y472465D02*
Y512434D01*
G01X545475Y477100D02*
Y478220D01*
G01X546535Y472465D02*
Y512434D01*
G01X545475Y480340D02*
Y481460D01*
G01X546535Y472465D02*
Y512434D01*
G01X545475Y483580D02*
Y484700D01*
G01X546535Y472465D02*
Y512434D01*
G01X545475Y486820D02*
Y487940D01*
G01X546535Y472465D02*
Y512434D01*
G01X545475Y490060D02*
Y499816D01*
G01X546535Y472465D02*
Y512434D01*
G01X545475Y502284D02*
Y503516D01*
G01X546535Y472465D02*
Y512434D01*
G01X545475Y505784D02*
Y506916D01*
G01X546535Y472465D02*
Y512434D01*
G01X545475Y509260D02*
Y511994D01*
G01X546535Y512434D02*
X543455Y515514D01*
G01X545475Y511994D02*
X544359Y513110D01*
G01X579462Y519900D02*
X578791Y520571D01*
G01X578561Y519300D02*
X577731Y520130D01*
G01X578791Y520571D02*
Y521848D01*
G01Y525338D02*
Y526229D01*
G01X577731Y520130D02*
Y526670D01*
G01X578791Y526229D02*
X579562Y527000D01*
G01X587572Y465231D02*
Y504743D01*
G01X586512Y465671D02*
Y484732D01*
G01X587572Y465231D02*
Y504743D01*
G01X586512Y486972D02*
Y487972D01*
G01X587572Y465231D02*
Y504743D01*
G01X586512Y490212D02*
Y491212D01*
G01X587572Y465231D02*
Y504743D01*
G01X586512Y493452D02*
Y494452D01*
G01X587572Y465231D02*
Y504743D01*
G01X586512Y496692D02*
Y497692D01*
G01X587572Y465231D02*
Y504743D01*
G01X586512Y499932D02*
Y500932D01*
G01X587572Y465231D02*
Y504743D01*
G01X586512Y503172D02*
Y504303D01*
G01X587572Y504743D02*
X583726Y508589D01*
G01X586512Y504303D02*
X585058Y505757D01*
G01X587572Y504743D02*
X583726Y508589D01*
G01X583836Y506979D02*
X582666Y508149D01*
G01X583726Y508589D02*
Y512054D01*
G01X582666Y508149D02*
Y511614D01*
G01X583726Y512054D02*
X580266Y515514D01*
G01X582666Y511614D02*
X581366Y512914D01*
G01X574238Y520290D02*
Y521660D01*
G01Y525340D02*
Y526760D01*
G01X573178Y514400D02*
Y532411D01*
G01X582612Y471552D02*
Y503151D01*
G01X581552Y471992D02*
Y479951D01*
G01X582612Y471552D02*
Y503151D01*
G01X581552Y481883D02*
Y483059D01*
G01X582612Y471552D02*
Y503151D01*
G01X581552Y485299D02*
Y486299D01*
G01X582612Y471552D02*
Y503151D01*
G01X581552Y488539D02*
Y489539D01*
G01X582612Y471552D02*
Y503151D01*
G01X581552Y491779D02*
Y492779D01*
G01X582612Y471552D02*
Y503151D01*
G01X581552Y495019D02*
Y496019D01*
G01X582612Y471552D02*
Y503151D01*
G01X581552Y498259D02*
Y499259D01*
G01X582612Y471552D02*
Y503151D01*
G01X581552Y501499D02*
Y502711D01*
G01X582612Y503151D02*
X578346Y507417D01*
G01X581552Y502711D02*
X580191Y504072D01*
G01X582612Y503151D02*
X578346Y507417D01*
G01X578904Y505359D02*
X577286Y506977D01*
G01X578346Y507417D02*
Y512120D01*
G01X577286Y506977D02*
Y511680D01*
G01X578346Y512120D02*
X575166Y515300D01*
G01X577286Y511680D02*
X576266Y512700D01*
G01X541750Y519300D02*
X540920Y520130D01*
G01X542651Y519900D02*
X541980Y520571D01*
G01X540920Y520130D02*
Y526670D01*
G01X541980Y520571D02*
Y521848D01*
G01X540920Y520130D02*
Y526670D01*
G01X541980Y525338D02*
Y526229D01*
G01D02*
X542751Y527000D01*
G01X540170Y467600D02*
X540992Y468422D01*
G01X541720Y470000D02*
X542570D01*
G01D02*
X543292Y470722D01*
G01X543920Y472200D02*
X544770D01*
G01D02*
X545475Y472905D01*
G01D02*
Y474980D01*
G01Y477100D02*
Y478220D01*
G01Y480340D02*
Y481460D01*
G01Y483580D02*
Y484700D01*
G01Y486820D02*
Y487940D01*
G01Y490060D02*
Y499816D01*
G01Y502284D02*
Y503516D01*
G01Y505784D02*
Y506916D01*
G01Y509260D02*
Y511994D01*
G01X546535Y472465D02*
Y512434D01*
G01X545475Y511994D02*
X544359Y513110D01*
G01X546535Y512434D02*
X543455Y515514D01*
G01X578561Y519300D02*
X577731Y520130D01*
G01X579462Y519900D02*
X578791Y520571D01*
G01X577731Y520130D02*
Y526670D01*
G01X578791Y520571D02*
Y521848D01*
G01X577731Y520130D02*
Y526670D01*
G01X578791Y525338D02*
Y526229D01*
G01D02*
X579562Y527000D01*
G01X586512Y465671D02*
Y484732D01*
G01Y486972D02*
Y487972D01*
G01Y490212D02*
Y491212D01*
G01Y493452D02*
Y494452D01*
G01Y496692D02*
Y497692D01*
G01Y499932D02*
Y500932D01*
G01Y503172D02*
Y504303D01*
G01X587572Y465231D02*
Y504743D01*
G01X586512Y504303D02*
X585058Y505757D01*
G01X583836Y506979D02*
X582666Y508149D01*
G01X587572Y504743D02*
X583726Y508589D01*
G01X582666Y508149D02*
Y511614D01*
G01X583726Y508589D02*
Y512054D01*
G01X582666Y511614D02*
X581366Y512914D01*
G01X583726Y512054D02*
X580266Y515514D01*
G01X540920Y526670D02*
X541750Y527500D01*
G01X540920Y526670D02*
X541750Y527500D01*
G01X577731Y526670D02*
X578561Y527500D01*
G01X577731Y526670D02*
X578561Y527500D01*
G01X540920Y526670D02*
X541750Y527500D01*
G01X577731Y526670D02*
X578561Y527500D01*
G01X540920Y526670D02*
X541750Y527500D01*
G01X577731Y526670D02*
X578561Y527500D01*
G01X777171Y-47440D02*
G02Y-50100I0J-1330D01*
G01Y-46380D02*
G02Y-51160I0J-2390D01*
G01Y-46380D02*
G02Y-51160I0J-2390D01*
G01Y-47440D02*
G02Y-50100I0J-1330D01*
G01X789494Y86794D02*
X786388Y89900D01*
G01X784534Y98013D02*
Y89154D01*
G01X789494Y86794D02*
X786388Y89900D01*
G01X784534Y98013D02*
Y89154D01*
G01X789494Y86794D02*
X786388Y89900D01*
G01X784534Y98013D02*
Y89154D01*
G01X789494Y86794D02*
X786388Y89900D01*
G01X784534Y98013D02*
Y89154D01*
G01X785594Y95220D02*
Y97570D01*
G01X786612Y100091D02*
X784534Y98013D01*
G01X785594Y97570D02*
X788292Y100268D01*
G01X786612Y141940D02*
Y100091D01*
G01Y141940D02*
Y100091D01*
G01Y141940D02*
Y100091D01*
G01Y141940D02*
Y100091D01*
G01Y141940D02*
Y100091D01*
G01Y141940D02*
Y100091D01*
G01X788975Y144303D02*
X786612Y141940D01*
G01X788975Y144303D02*
X786612Y141940D01*
G01X785594Y95220D02*
Y97570D01*
G01X786612Y100091D02*
X784534Y98013D01*
G01X785594Y97570D02*
X788292Y100268D01*
G01X786612Y141940D02*
Y100091D01*
G01Y141940D02*
Y100091D01*
G01Y141940D02*
Y100091D01*
G01Y141940D02*
Y100091D01*
G01Y141940D02*
Y100091D01*
G01Y141940D02*
Y100091D01*
G01X788975Y144303D02*
X786612Y141940D01*
G01X788975Y144303D02*
X786612Y141940D01*
G01X788975Y144303D02*
X786612Y141940D01*
G01D02*
Y100091D01*
G01X785594Y97570D02*
X788292Y100268D01*
G01X786612Y100091D02*
X784534Y98013D01*
G01X785594Y95220D02*
Y97570D01*
G01X788975Y144303D02*
X786612Y141940D01*
G01D02*
Y100091D01*
G01X785594Y97570D02*
X788292Y100268D01*
G01X786612Y100091D02*
X784534Y98013D01*
G01X785594Y95220D02*
Y97570D01*
G01X789680Y512008D02*
X786388Y515300D01*
G01X784400Y514400D02*
Y532411D01*
G01X785460Y520290D02*
Y521660D01*
G01X784400Y514400D02*
Y532411D01*
G01X785460Y525340D02*
Y526760D01*
G01X789680Y512008D02*
X786388Y515300D01*
G01X784400Y514400D02*
Y532411D01*
G01X785460Y520290D02*
Y521660D01*
G01X784400Y514400D02*
Y532411D01*
G01X785460Y525340D02*
Y526760D01*
G01Y520290D02*
Y521660D01*
G01Y525340D02*
Y526760D01*
G01X784400Y514400D02*
Y532411D01*
G01X789680Y512008D02*
X786388Y515300D01*
G01X785460Y520290D02*
Y521660D01*
G01Y525340D02*
Y526760D01*
G01X784400Y514400D02*
Y532411D01*
G01X789680Y512008D02*
X786388Y515300D01*
G01X787723Y70380D02*
X787207D01*
G01X787184Y69320D02*
X788166D01*
G01X788434Y71091D02*
X787723Y70380D01*
G01X788166Y69320D02*
X789494Y70648D01*
G01X788434Y86353D02*
Y83820D01*
G01Y79680D02*
Y78720D01*
G01Y74380D02*
Y71091D01*
G01X789494Y70648D02*
Y86794D01*
G01X787487Y87300D02*
X788434Y86353D01*
G01X787723Y70380D02*
X787207D01*
G01X787184Y69320D02*
X788166D01*
G01X788434Y71091D02*
X787723Y70380D01*
G01X788166Y69320D02*
X789494Y70648D01*
G01X788434Y86353D02*
Y83820D01*
G01Y79680D02*
Y78720D01*
G01Y74380D02*
Y71091D01*
G01X789494Y70648D02*
Y86794D01*
G01X787487Y87300D02*
X788434Y86353D01*
G01X787487Y87300D02*
X788434Y86353D01*
G01X789494Y70648D02*
Y86794D01*
G01X788434Y86353D02*
Y83820D01*
G01X789494Y70648D02*
Y86794D01*
G01X788434Y79680D02*
Y78720D01*
G01X789494Y70648D02*
Y86794D01*
G01X788434Y74380D02*
Y71091D01*
G01X788166Y69320D02*
X789494Y70648D01*
G01X788434Y71091D02*
X787723Y70380D01*
G01X787184Y69320D02*
X788166D01*
G01X787723Y70380D02*
X787207D01*
G01X787487Y87300D02*
X788434Y86353D01*
G01X789494Y70648D02*
Y86794D01*
G01X788434Y86353D02*
Y83820D01*
G01X789494Y70648D02*
Y86794D01*
G01X788434Y79680D02*
Y78720D01*
G01X789494Y70648D02*
Y86794D01*
G01X788434Y74380D02*
Y71091D01*
G01X788166Y69320D02*
X789494Y70648D01*
G01X788434Y71091D02*
X787723Y70380D01*
G01X787184Y69320D02*
X788166D01*
G01X787723Y70380D02*
X787207D01*
G01X794680Y86922D02*
X791488Y90114D01*
G01Y87515D02*
X792586D01*
G01X794680Y86922D02*
X791488Y90114D01*
G01X792586Y87515D02*
X793620Y86481D01*
G01X794680Y71532D02*
Y86922D01*
G01X793620Y86481D02*
Y83706D01*
G01X794680Y71532D02*
Y86922D01*
G01X793620Y79880D02*
Y78507D01*
G01X794680Y71532D02*
Y86922D01*
G01X793620Y74593D02*
Y71972D01*
G01X791488Y68340D02*
X794680Y71532D01*
G01X793620Y71972D02*
X792597Y70949D01*
G01X789734Y97505D02*
Y89268D01*
G01X794680Y86922D02*
X791488Y90114D01*
G01Y87515D02*
X792586D01*
G01X794680Y86922D02*
X791488Y90114D01*
G01X792586Y87515D02*
X793620Y86481D01*
G01X794680Y71532D02*
Y86922D01*
G01X793620Y86481D02*
Y83706D01*
G01X794680Y71532D02*
Y86922D01*
G01X793620Y79880D02*
Y78507D01*
G01X794680Y71532D02*
Y86922D01*
G01X793620Y74593D02*
Y71972D01*
G01X791488Y68340D02*
X794680Y71532D01*
G01X793620Y71972D02*
X792597Y70949D01*
G01X789734Y97505D02*
Y89268D01*
G01X824298Y87300D02*
X825245Y86353D01*
G01X823199Y89900D02*
X826305Y86794D01*
G01X825245Y86353D02*
Y83820D01*
G01Y79680D02*
Y78720D01*
G01Y74380D02*
Y71091D01*
G01X826305Y86794D02*
Y70648D01*
G01X825245Y71091D02*
X824534Y70380D01*
G01X826305Y70648D02*
X824977Y69320D01*
G01X824534Y70380D02*
X824018D01*
G01X824977Y69320D02*
X823995D01*
G01X828299Y90114D02*
X831491Y86922D01*
G01X828299Y87515D02*
X829397D01*
G01X828299Y90114D02*
X831491Y86922D01*
G01X829397Y87515D02*
X830431Y86481D01*
G01X831491Y86922D02*
Y71532D01*
G01X830431Y86481D02*
Y83706D01*
G01X831491Y86922D02*
Y71532D01*
G01X830431Y79880D02*
Y78507D01*
G01X831491Y86922D02*
Y71532D01*
G01X830431Y74593D02*
Y71972D01*
G01X831491Y71532D02*
X828299Y68340D01*
G01X830431Y71972D02*
X829408Y70949D01*
G01X793620Y71972D02*
X792597Y70949D01*
G01X791488Y68340D02*
X794680Y71532D01*
G01X793620Y86481D02*
Y83706D01*
G01Y79880D02*
Y78507D01*
G01Y74593D02*
Y71972D01*
G01X794680Y71532D02*
Y86922D01*
G01X791488Y87515D02*
X792586D01*
G01D02*
X793620Y86481D01*
G01X794680Y86922D02*
X791488Y90114D01*
G01X789734Y97505D02*
Y89268D01*
G01X793620Y71972D02*
X792597Y70949D01*
G01X791488Y68340D02*
X794680Y71532D01*
G01X793620Y86481D02*
Y83706D01*
G01Y79880D02*
Y78507D01*
G01Y74593D02*
Y71972D01*
G01X794680Y71532D02*
Y86922D01*
G01X791488Y87515D02*
X792586D01*
G01D02*
X793620Y86481D01*
G01X794680Y86922D02*
X791488Y90114D01*
G01X789734Y97505D02*
Y89268D01*
G01X823199Y89900D02*
X826305Y86794D01*
G01X824298Y87300D02*
X825245Y86353D01*
G01X826305Y86794D02*
Y70648D01*
G01X825245Y86353D02*
Y83820D01*
G01X826305Y86794D02*
Y70648D01*
G01X825245Y79680D02*
Y78720D01*
G01X826305Y86794D02*
Y70648D01*
G01X825245Y74380D02*
Y71091D01*
G01X826305Y70648D02*
X824977Y69320D01*
G01X825245Y71091D02*
X824534Y70380D01*
G01X824977Y69320D02*
X823995D01*
G01X824534Y70380D02*
X824018D01*
G01X828299Y87515D02*
X829397D01*
G01D02*
X830431Y86481D01*
G01X828299Y90114D02*
X831491Y86922D01*
G01X830431Y86481D02*
Y83706D01*
G01Y79880D02*
Y78507D01*
G01Y74593D02*
Y71972D01*
G01X831491Y86922D02*
Y71532D01*
G01X830431Y71972D02*
X829408Y70949D01*
G01X831491Y71532D02*
X828299Y68340D01*
G01X787672Y101720D02*
Y102680D01*
G01Y104920D02*
Y105680D01*
G01Y107920D02*
Y108680D01*
G01Y110920D02*
Y111680D01*
G01Y113920D02*
Y114680D01*
G01Y116920D02*
Y141497D01*
G01D02*
X789418Y143243D01*
G01X790070Y144303D02*
X788975D01*
G01X789418Y143243D02*
X790513D01*
G01X792520Y146753D02*
X790070Y144303D01*
G01D02*
X788975D01*
G01X790513Y143243D02*
X793580Y146310D01*
G01X792520Y147848D02*
Y146753D01*
G01X793580Y146310D02*
Y147405D01*
G01X899915Y255243D02*
X792520Y147848D01*
G01X793580Y147405D02*
X900358Y254183D01*
G01X787672Y101720D02*
Y102680D01*
G01Y104920D02*
Y105680D01*
G01Y107920D02*
Y108680D01*
G01Y110920D02*
Y111680D01*
G01Y113920D02*
Y114680D01*
G01Y116920D02*
Y141497D01*
G01D02*
X789418Y143243D01*
G01X790070Y144303D02*
X788975D01*
G01X789418Y143243D02*
X790513D01*
G01X792520Y146753D02*
X790070Y144303D01*
G01D02*
X788975D01*
G01X790513Y143243D02*
X793580Y146310D01*
G01X792520Y147848D02*
Y146753D01*
G01X793580Y146310D02*
Y147405D01*
G01X899915Y255243D02*
X792520Y147848D01*
G01X793580Y147405D02*
X900358Y254183D01*
G01X793580Y147405D02*
X900358Y254183D01*
G01X899915Y255243D02*
X792520Y147848D01*
G01X793580Y146310D02*
Y147405D01*
G01X792520Y147848D02*
Y146753D01*
G01X790513Y143243D02*
X793580Y146310D01*
G01X792520Y146753D02*
X790070Y144303D01*
G01X789418Y143243D02*
X790513D01*
G01D02*
X793580Y146310D01*
G01X790070Y144303D02*
X788975D01*
G01X787672Y141497D02*
X789418Y143243D01*
G01D02*
X790513D01*
G01X787672Y101720D02*
Y102680D01*
G01Y104920D02*
Y105680D01*
G01Y107920D02*
Y108680D01*
G01Y110920D02*
Y111680D01*
G01Y113920D02*
Y114680D01*
G01Y116920D02*
Y141497D01*
G01X793580Y147405D02*
X900358Y254183D01*
G01X899915Y255243D02*
X792520Y147848D01*
G01X793580Y146310D02*
Y147405D01*
G01X792520Y147848D02*
Y146753D01*
G01X790513Y143243D02*
X793580Y146310D01*
G01X792520Y146753D02*
X790070Y144303D01*
G01X789418Y143243D02*
X790513D01*
G01D02*
X793580Y146310D01*
G01X790070Y144303D02*
X788975D01*
G01X787672Y141497D02*
X789418Y143243D01*
G01D02*
X790513D01*
G01X787672Y101720D02*
Y102680D01*
G01Y104920D02*
Y105680D01*
G01Y107920D02*
Y108680D01*
G01Y110920D02*
Y111680D01*
G01Y113920D02*
Y114680D01*
G01Y116920D02*
Y141497D01*
G01X803872Y152304D02*
X901902Y250334D01*
G01X901459Y251394D02*
X802812Y152747D01*
G01X803872Y149029D02*
Y152304D01*
G01X802812Y152747D02*
Y149472D01*
G01X802383Y147540D02*
X803872Y149029D01*
G01X802812Y149472D02*
X801940Y148600D01*
G01X801144Y147540D02*
X802383D01*
G01D02*
X803872Y149029D01*
G01X801940Y148600D02*
X800701D01*
G01X800072Y146468D02*
X801144Y147540D01*
G01D02*
X802383D01*
G01X800701Y148600D02*
X799012Y146911D01*
G01X800072Y144347D02*
Y146468D01*
G01X799012Y146911D02*
Y143904D01*
G01X803372Y141047D02*
X800072Y144347D01*
G01X799012Y143904D02*
X802312Y140604D01*
G01X803372Y138365D02*
Y141047D01*
G01X802312Y140604D02*
Y138808D01*
G01X800483Y135476D02*
X803372Y138365D01*
G01X802312Y138808D02*
X800040Y136536D01*
G01X793243Y135476D02*
X800483D01*
G01X800040Y136536D02*
X792800D01*
G01X792272Y134505D02*
X793243Y135476D01*
G01X792800Y136536D02*
X791212Y134948D01*
G01X792272Y98540D02*
Y99372D01*
G01Y101612D02*
Y102372D01*
G01Y104612D02*
Y105372D01*
G01Y107612D02*
Y108372D01*
G01Y110612D02*
Y111372D01*
G01Y113612D02*
Y134505D01*
G01X791212Y134948D02*
Y98983D01*
G01X790794Y97062D02*
X792272Y98540D01*
G01X791212Y98983D02*
X789734Y97505D01*
G01X790794Y95506D02*
Y97062D01*
G01X803872Y152304D02*
X901902Y250334D01*
G01X901459Y251394D02*
X802812Y152747D01*
G01X803872Y149029D02*
Y152304D01*
G01X802812Y152747D02*
Y149472D01*
G01X802383Y147540D02*
X803872Y149029D01*
G01X802812Y149472D02*
X801940Y148600D01*
G01X801144Y147540D02*
X802383D01*
G01D02*
X803872Y149029D01*
G01X801940Y148600D02*
X800701D01*
G01X800072Y146468D02*
X801144Y147540D01*
G01D02*
X802383D01*
G01X800701Y148600D02*
X799012Y146911D01*
G01X800072Y144347D02*
Y146468D01*
G01X799012Y146911D02*
Y143904D01*
G01X803372Y141047D02*
X800072Y144347D01*
G01X799012Y143904D02*
X802312Y140604D01*
G01X803372Y138365D02*
Y141047D01*
G01X802312Y140604D02*
Y138808D01*
G01X800483Y135476D02*
X803372Y138365D01*
G01X802312Y138808D02*
X800040Y136536D01*
G01X793243Y135476D02*
X800483D01*
G01X800040Y136536D02*
X792800D01*
G01X792272Y134505D02*
X793243Y135476D01*
G01X792800Y136536D02*
X791212Y134948D01*
G01X792272Y98540D02*
Y99372D01*
G01Y101612D02*
Y102372D01*
G01Y104612D02*
Y105372D01*
G01Y107612D02*
Y108372D01*
G01Y110612D02*
Y111372D01*
G01Y113612D02*
Y134505D01*
G01X791212Y134948D02*
Y98983D01*
G01X790794Y97062D02*
X792272Y98540D01*
G01X791212Y98983D02*
X789734Y97505D01*
G01X790794Y95506D02*
Y97062D01*
G01Y95506D02*
Y97062D01*
G01X791212Y98983D02*
X789734Y97505D01*
G01X790794Y97062D02*
X792272Y98540D01*
G01X791212Y134948D02*
Y98983D01*
G01X792272Y98540D02*
Y99372D01*
G01X791212Y134948D02*
Y98983D01*
G01X792272Y101612D02*
Y102372D01*
G01X791212Y134948D02*
Y98983D01*
G01X792272Y104612D02*
Y105372D01*
G01X791212Y134948D02*
Y98983D01*
G01X792272Y107612D02*
Y108372D01*
G01X791212Y134948D02*
Y98983D01*
G01X792272Y110612D02*
Y111372D01*
G01X791212Y134948D02*
Y98983D01*
G01X792272Y113612D02*
Y134505D01*
G01X792800Y136536D02*
X791212Y134948D01*
G01X792272Y134505D02*
X793243Y135476D01*
G01X800040Y136536D02*
X792800D01*
G01X793243Y135476D02*
X800483D01*
G01X802312Y138808D02*
X800040Y136536D01*
G01X800483Y135476D02*
X803372Y138365D01*
G01X802312Y140604D02*
Y138808D01*
G01X803372Y138365D02*
Y141047D01*
G01X799012Y143904D02*
X802312Y140604D01*
G01X803372Y141047D02*
X800072Y144347D01*
G01X799012Y146911D02*
Y143904D01*
G01X800072Y144347D02*
Y146468D01*
G01X800701Y148600D02*
X799012Y146911D01*
G01X800072Y146468D02*
X801144Y147540D01*
G01X801940Y148600D02*
X800701D01*
G01D02*
X799012Y146911D01*
G01X801144Y147540D02*
X802383D01*
G01X802812Y149472D02*
X801940Y148600D01*
G01D02*
X800701D01*
G01X802383Y147540D02*
X803872Y149029D01*
G01X802812Y152747D02*
Y149472D01*
G01X803872Y149029D02*
Y152304D01*
G01X901459Y251394D02*
X802812Y152747D01*
G01X803872Y152304D02*
X901902Y250334D01*
G01X790794Y95506D02*
Y97062D01*
G01X791212Y98983D02*
X789734Y97505D01*
G01X790794Y97062D02*
X792272Y98540D01*
G01X791212Y134948D02*
Y98983D01*
G01X792272Y98540D02*
Y99372D01*
G01X791212Y134948D02*
Y98983D01*
G01X792272Y101612D02*
Y102372D01*
G01X791212Y134948D02*
Y98983D01*
G01X792272Y104612D02*
Y105372D01*
G01X791212Y134948D02*
Y98983D01*
G01X792272Y107612D02*
Y108372D01*
G01X791212Y134948D02*
Y98983D01*
G01X792272Y110612D02*
Y111372D01*
G01X791212Y134948D02*
Y98983D01*
G01X792272Y113612D02*
Y134505D01*
G01X792800Y136536D02*
X791212Y134948D01*
G01X792272Y134505D02*
X793243Y135476D01*
G01X800040Y136536D02*
X792800D01*
G01X793243Y135476D02*
X800483D01*
G01X802312Y138808D02*
X800040Y136536D01*
G01X800483Y135476D02*
X803372Y138365D01*
G01X802312Y140604D02*
Y138808D01*
G01X803372Y138365D02*
Y141047D01*
G01X799012Y143904D02*
X802312Y140604D01*
G01X803372Y141047D02*
X800072Y144347D01*
G01X799012Y146911D02*
Y143904D01*
G01X800072Y144347D02*
Y146468D01*
G01X800701Y148600D02*
X799012Y146911D01*
G01X800072Y146468D02*
X801144Y147540D01*
G01X801940Y148600D02*
X800701D01*
G01D02*
X799012Y146911D01*
G01X801144Y147540D02*
X802383D01*
G01X802812Y149472D02*
X801940Y148600D01*
G01D02*
X800701D01*
G01X802383Y147540D02*
X803872Y149029D01*
G01X802812Y152747D02*
Y149472D01*
G01X803872Y149029D02*
Y152304D01*
G01X901459Y251394D02*
X802812Y152747D01*
G01X803872Y152304D02*
X901902Y250334D01*
G01X853440Y396959D02*
X803259Y447140D01*
G01X853440Y396959D02*
X803259Y447140D01*
G01X853440Y396959D02*
X803259Y447140D01*
G01X853440Y396959D02*
X803259Y447140D01*
G01X854500Y397399D02*
X803699Y448200D01*
G01X803259Y447140D02*
X799359D01*
G01X803699Y448200D02*
X799799D01*
G01X799359Y447140D02*
X789620Y456879D01*
G01X799799Y448200D02*
X790680Y457319D01*
G01X789620Y456879D02*
Y458623D01*
G01X790680Y457319D02*
Y458183D01*
G01X789620Y458623D02*
X790712Y459715D01*
G01X790680Y458183D02*
X791152Y458655D01*
G01X790712Y459715D02*
X791748D01*
G01X791152Y458655D02*
X792188D01*
G01X791748Y459715D02*
X792420Y460387D01*
G01X792210Y458676D02*
X793480Y459947D01*
G01X792420Y460387D02*
Y462383D01*
G01X793480Y459947D02*
Y462823D01*
G01X792420Y462383D02*
X791648Y463155D01*
G01X793480Y462823D02*
X792088Y464215D01*
G01X791648Y463155D02*
X790512D01*
G01X792088Y464215D02*
X790952D01*
G01X790512Y463155D02*
X789220Y464447D01*
G01X790952Y464215D02*
X790280Y464887D01*
G01X789220Y464447D02*
Y467223D01*
G01X854500Y397399D02*
X803699Y448200D01*
G01X803259Y447140D02*
X799359D01*
G01X803699Y448200D02*
X799799D01*
G01X799359Y447140D02*
X789620Y456879D01*
G01X799799Y448200D02*
X790680Y457319D01*
G01X789620Y456879D02*
Y458623D01*
G01X790680Y457319D02*
Y458183D01*
G01X789620Y458623D02*
X790712Y459715D01*
G01X790680Y458183D02*
X791152Y458655D01*
G01X790712Y459715D02*
X791748D01*
G01X791152Y458655D02*
X792188D01*
G01X791748Y459715D02*
X792420Y460387D01*
G01X792210Y458676D02*
X793480Y459947D01*
G01X792420Y460387D02*
Y462383D01*
G01X793480Y459947D02*
Y462823D01*
G01X792420Y462383D02*
X791648Y463155D01*
G01X793480Y462823D02*
X792088Y464215D01*
G01X791648Y463155D02*
X790512D01*
G01X792088Y464215D02*
X790952D01*
G01X790512Y463155D02*
X789220Y464447D01*
G01X790952Y464215D02*
X790280Y464887D01*
G01X789220Y464447D02*
Y467223D01*
G01X854500Y397399D02*
X803699Y448200D01*
G01D02*
X799799D01*
G01X803259Y447140D02*
X799359D01*
G01X799799Y448200D02*
X790680Y457319D01*
G01X799359Y447140D02*
X789620Y456879D01*
G01X790680Y457319D02*
Y458183D01*
G01X789620Y456879D02*
Y458623D01*
G01X790680Y458183D02*
X791152Y458655D01*
G01X789620Y458623D02*
X790712Y459715D01*
G01X791152Y458655D02*
X792188D01*
G01X790712Y459715D02*
X791748D01*
G01X792210Y458676D02*
X793480Y459947D01*
G01X791748Y459715D02*
X792420Y460387D01*
G01X793480Y459947D02*
Y462823D01*
G01X792420Y460387D02*
Y462383D01*
G01X793480Y462823D02*
X792088Y464215D01*
G01X792420Y462383D02*
X791648Y463155D01*
G01X792088Y464215D02*
X790952D01*
G01X791648Y463155D02*
X790512D01*
G01X790952Y464215D02*
X790280Y464887D01*
G01X790512Y463155D02*
X789220Y464447D01*
G01D02*
Y467223D01*
G01X854500Y397399D02*
X803699Y448200D01*
G01D02*
X799799D01*
G01X803259Y447140D02*
X799359D01*
G01X799799Y448200D02*
X790680Y457319D01*
G01X799359Y447140D02*
X789620Y456879D01*
G01X790680Y457319D02*
Y458183D01*
G01X789620Y456879D02*
Y458623D01*
G01X790680Y458183D02*
X791152Y458655D01*
G01X789620Y458623D02*
X790712Y459715D01*
G01X791152Y458655D02*
X792188D01*
G01X790712Y459715D02*
X791748D01*
G01X792210Y458676D02*
X793480Y459947D01*
G01X791748Y459715D02*
X792420Y460387D01*
G01X793480Y459947D02*
Y462823D01*
G01X792420Y460387D02*
Y462383D01*
G01X793480Y462823D02*
X792088Y464215D01*
G01X792420Y462383D02*
X791648Y463155D01*
G01X792088Y464215D02*
X790952D01*
G01X791648Y463155D02*
X790512D01*
G01X790952Y464215D02*
X790280Y464887D01*
G01X790512Y463155D02*
X789220Y464447D01*
G01D02*
Y467223D01*
G01X797480Y454688D02*
Y475960D01*
G01X796420Y475520D02*
Y454248D01*
G01X800984Y451184D02*
X797480Y454688D01*
G01X796420Y454248D02*
X800544Y450124D01*
G01X805016Y451184D02*
X800984D01*
G01X800544Y450124D02*
X804576D01*
G01X857700Y398500D02*
X805016Y451184D01*
G01X804576Y450124D02*
X856640Y398060D01*
G01X804576Y450124D02*
X856640Y398060D01*
G01X857700Y398500D02*
X805016Y451184D01*
G01X800544Y450124D02*
X804576D01*
G01X805016Y451184D02*
X800984D01*
G01X796420Y454248D02*
X800544Y450124D01*
G01X800984Y451184D02*
X797480Y454688D01*
G01X796420Y475520D02*
Y454248D01*
G01X797480Y454688D02*
Y475960D01*
G01Y454688D02*
Y475960D01*
G01X796420Y475520D02*
Y454248D01*
G01X800984Y451184D02*
X797480Y454688D01*
G01X796420Y454248D02*
X800544Y450124D01*
G01X805016Y451184D02*
X800984D01*
G01X800544Y450124D02*
X804576D01*
G01X857700Y398500D02*
X805016Y451184D01*
G01X804576Y450124D02*
X856640Y398060D01*
G01X804576Y450124D02*
X856640Y398060D01*
G01X857700Y398500D02*
X805016Y451184D01*
G01X800544Y450124D02*
X804576D01*
G01X805016Y451184D02*
X800984D01*
G01X796420Y454248D02*
X800544Y450124D01*
G01X800984Y451184D02*
X797480Y454688D01*
G01X796420Y475520D02*
Y454248D01*
G01X797480Y454688D02*
Y475960D01*
G01X790280Y464887D02*
Y466783D01*
G01X789220Y467223D02*
X790712Y468715D01*
G01X790280Y466783D02*
X791152Y467655D01*
G01X790712Y468715D02*
X792043D01*
G01X791152Y467655D02*
X792483D01*
G01X790712Y468715D02*
X792043D01*
G01D02*
X792612Y469284D01*
G01X792483Y467655D02*
X793672Y468844D01*
G01X792612Y469284D02*
Y471286D01*
G01X793672Y468844D02*
Y471726D01*
G01X792612Y471286D02*
X791743Y472155D01*
G01D02*
X790212D01*
G01X793672Y471726D02*
X792183Y473215D01*
G01X791743Y472155D02*
X790212D01*
G01X792183Y473215D02*
X790652D01*
G01X790212Y472155D02*
X788620Y473747D01*
G01X790652Y473215D02*
X789680Y474187D01*
G01X788620Y473747D02*
Y506680D01*
G01Y509120D02*
Y511568D01*
G01X789680Y474187D02*
Y512008D01*
G01X788620Y511568D02*
X787369Y512819D01*
G01X790280Y464887D02*
Y466783D01*
G01X789220Y467223D02*
X790712Y468715D01*
G01X790280Y466783D02*
X791152Y467655D01*
G01X790712Y468715D02*
X792043D01*
G01X791152Y467655D02*
X792483D01*
G01X790712Y468715D02*
X792043D01*
G01D02*
X792612Y469284D01*
G01X792483Y467655D02*
X793672Y468844D01*
G01X792612Y469284D02*
Y471286D01*
G01X793672Y468844D02*
Y471726D01*
G01X792612Y471286D02*
X791743Y472155D01*
G01D02*
X790212D01*
G01X793672Y471726D02*
X792183Y473215D01*
G01X791743Y472155D02*
X790212D01*
G01X792183Y473215D02*
X790652D01*
G01X790212Y472155D02*
X788620Y473747D01*
G01X790652Y473215D02*
X789680Y474187D01*
G01X788620Y473747D02*
Y506680D01*
G01Y509120D02*
Y511568D01*
G01X789680Y474187D02*
Y512008D01*
G01X788620Y511568D02*
X787369Y512819D01*
G01X790280Y464887D02*
Y466783D01*
G01D02*
X791152Y467655D01*
G01X789220Y467223D02*
X790712Y468715D01*
G01X791152Y467655D02*
X792483D01*
G01D02*
X793672Y468844D01*
G01X790712Y468715D02*
X792043D01*
G01X792483Y467655D02*
X793672Y468844D01*
G01X792043Y468715D02*
X792612Y469284D01*
G01X793672Y468844D02*
Y471726D01*
G01X792612Y469284D02*
Y471286D01*
G01X793672Y471726D02*
X792183Y473215D01*
G01X792612Y471286D02*
X791743Y472155D01*
G01X793672Y471726D02*
X792183Y473215D01*
G01D02*
X790652D01*
G01X791743Y472155D02*
X790212D01*
G01X790652Y473215D02*
X789680Y474187D01*
G01X790212Y472155D02*
X788620Y473747D01*
G01X789680Y474187D02*
Y512008D01*
G01X788620Y473747D02*
Y506680D01*
G01X789680Y474187D02*
Y512008D01*
G01X788620Y509120D02*
Y511568D01*
G01D02*
X787369Y512819D01*
G01X790280Y464887D02*
Y466783D01*
G01D02*
X791152Y467655D01*
G01X789220Y467223D02*
X790712Y468715D01*
G01X791152Y467655D02*
X792483D01*
G01D02*
X793672Y468844D01*
G01X790712Y468715D02*
X792043D01*
G01X792483Y467655D02*
X793672Y468844D01*
G01X792043Y468715D02*
X792612Y469284D01*
G01X793672Y468844D02*
Y471726D01*
G01X792612Y469284D02*
Y471286D01*
G01X793672Y471726D02*
X792183Y473215D01*
G01X792612Y471286D02*
X791743Y472155D01*
G01X793672Y471726D02*
X792183Y473215D01*
G01D02*
X790652D01*
G01X791743Y472155D02*
X790212D01*
G01X790652Y473215D02*
X789680Y474187D01*
G01X790212Y472155D02*
X788620Y473747D01*
G01X789680Y474187D02*
Y512008D01*
G01X788620Y473747D02*
Y506680D01*
G01X789680Y474187D02*
Y512008D01*
G01X788620Y509120D02*
Y511568D01*
G01D02*
X787369Y512819D01*
G01X790013Y526229D02*
X790784Y527000D01*
G01X790013Y520571D02*
Y521848D01*
G01Y525338D02*
Y526229D01*
G01X788953Y526670D02*
Y520130D01*
G01X790684Y519900D02*
X790013Y520571D01*
G01X788953Y520130D02*
X789783Y519300D01*
G01X793326Y513974D02*
X793028D01*
G01X791488Y512914D02*
X792886D01*
G01X794580Y512720D02*
X793326Y513974D01*
G01X792886Y512914D02*
X793520Y512280D01*
G01X794580Y506092D02*
Y512720D01*
G01X793520Y512280D02*
Y509520D01*
G01X794580Y506092D02*
Y512720D01*
G01X793520Y507080D02*
Y505649D01*
G01X797480Y503192D02*
X794580Y506092D01*
G01X793520Y505649D02*
X796420Y502749D01*
G01X797480Y500749D02*
Y503192D01*
G01X796420Y502749D02*
Y501192D01*
G01X795623Y498892D02*
X797480Y500749D01*
G01X796420Y501192D02*
X795180Y499952D01*
G01X794452Y498892D02*
X795623D01*
G01D02*
X797480Y500749D01*
G01X795180Y499952D02*
X794009D01*
G01X793580Y498020D02*
X794452Y498892D01*
G01X794009Y499952D02*
X792520Y498463D01*
G01X793580Y496324D02*
Y498020D01*
G01X792520Y498463D02*
Y495881D01*
G01X794452Y495452D02*
X793580Y496324D01*
G01X792520Y495881D02*
X794009Y494392D01*
G01X795991Y495452D02*
X794452D01*
G01X794009Y494392D02*
X795548D01*
G01X797480Y493963D02*
X795991Y495452D01*
G01X795548Y494392D02*
X796420Y493520D01*
G01X797480Y491381D02*
Y493963D01*
G01X796420Y493520D02*
Y491824D01*
G01X795991Y489892D02*
X797480Y491381D01*
G01X796420Y491824D02*
X795548Y490952D01*
G01X794652Y489892D02*
X795991D01*
G01X795548Y490952D02*
X794209D01*
G01X793780Y489020D02*
X794652Y489892D01*
G01X794209Y490952D02*
X792720Y489463D01*
G01X793780Y487324D02*
Y489020D01*
G01X792720Y489463D02*
Y486881D01*
G01X794652Y486452D02*
X793780Y487324D01*
G01X792720Y486881D02*
X794209Y485392D01*
G01X795991Y486452D02*
X794652D01*
G01X794209Y485392D02*
X795548D01*
G01X797480Y484963D02*
X795991Y486452D01*
G01X795548Y485392D02*
X796420Y484520D01*
G01X797480Y482381D02*
Y484963D01*
G01X796420Y484520D02*
Y482824D01*
G01X795991Y480892D02*
X797480Y482381D01*
G01X796420Y482824D02*
X795548Y481952D01*
G01X794852Y480892D02*
X795991D01*
G01X795548Y481952D02*
X794409D01*
G01X793980Y480020D02*
X794852Y480892D01*
G01X794409Y481952D02*
X792920Y480463D01*
G01X793980Y478324D02*
Y480020D01*
G01X792920Y480463D02*
Y477881D01*
G01X794852Y477452D02*
X793980Y478324D01*
G01X792920Y477881D02*
X794409Y476392D01*
G01X795988Y477452D02*
X794852D01*
G01X794409Y476392D02*
X795548D01*
G01X797480Y475960D02*
X795988Y477452D01*
G01X795548Y476392D02*
X796420Y475520D01*
G01X788953Y520130D02*
X789783Y519300D01*
G01X790684Y519900D02*
X790013Y520571D01*
G01X788953Y526670D02*
Y520130D01*
G01X790013Y520571D02*
Y521848D01*
G01X788953Y526670D02*
Y520130D01*
G01X790013Y525338D02*
Y526229D01*
G01D02*
X790784Y527000D01*
G01X795548Y476392D02*
X796420Y475520D01*
G01X797480Y475960D02*
X795988Y477452D01*
G01X794409Y476392D02*
X795548D01*
G01X795988Y477452D02*
X794852D01*
G01X792920Y477881D02*
X794409Y476392D01*
G01X794852Y477452D02*
X793980Y478324D01*
G01X792920Y480463D02*
Y477881D01*
G01X793980Y478324D02*
Y480020D01*
G01X794409Y481952D02*
X792920Y480463D01*
G01X793980Y480020D02*
X794852Y480892D01*
G01X795548Y481952D02*
X794409D01*
G01X794852Y480892D02*
X795991D01*
G01X796420Y482824D02*
X795548Y481952D01*
G01X795991Y480892D02*
X797480Y482381D01*
G01X796420Y484520D02*
Y482824D01*
G01X797480Y482381D02*
Y484963D01*
G01X795548Y485392D02*
X796420Y484520D01*
G01X797480Y484963D02*
X795991Y486452D01*
G01X794209Y485392D02*
X795548D01*
G01X795991Y486452D02*
X794652D01*
G01X792720Y486881D02*
X794209Y485392D01*
G01X794652Y486452D02*
X793780Y487324D01*
G01X792720Y489463D02*
Y486881D01*
G01X793780Y487324D02*
Y489020D01*
G01X794209Y490952D02*
X792720Y489463D01*
G01X793780Y489020D02*
X794652Y489892D01*
G01X795548Y490952D02*
X794209D01*
G01X794652Y489892D02*
X795991D01*
G01X796420Y491824D02*
X795548Y490952D01*
G01X795991Y489892D02*
X797480Y491381D01*
G01X796420Y493520D02*
Y491824D01*
G01X797480Y491381D02*
Y493963D01*
G01X795548Y494392D02*
X796420Y493520D01*
G01X797480Y493963D02*
X795991Y495452D01*
G01X794009Y494392D02*
X795548D01*
G01X795991Y495452D02*
X794452D01*
G01X792520Y495881D02*
X794009Y494392D01*
G01X794452Y495452D02*
X793580Y496324D01*
G01X792520Y498463D02*
Y495881D01*
G01X793580Y496324D02*
Y498020D01*
G01X794009Y499952D02*
X792520Y498463D01*
G01X793580Y498020D02*
X794452Y498892D01*
G01X795180Y499952D02*
X794009D01*
G01X794452Y498892D02*
X795623D01*
G01X796420Y501192D02*
X795180Y499952D01*
G01D02*
X794009D01*
G01X795623Y498892D02*
X797480Y500749D01*
G01X796420Y502749D02*
Y501192D01*
G01X797480Y500749D02*
Y503192D01*
G01X793520Y505649D02*
X796420Y502749D01*
G01X797480Y503192D02*
X794580Y506092D01*
G01X793520Y512280D02*
Y509520D01*
G01Y507080D02*
Y505649D01*
G01X794580Y506092D02*
Y512720D01*
G01X792886Y512914D02*
X793520Y512280D01*
G01X794580Y512720D02*
X793326Y513974D01*
G01X791488Y512914D02*
X792886D01*
G01X793326Y513974D02*
X793028D01*
G01X790013Y526229D02*
X790784Y527000D01*
G01X790013Y520571D02*
Y521848D01*
G01Y525338D02*
Y526229D01*
G01X788953Y526670D02*
Y520130D01*
G01X790684Y519900D02*
X790013Y520571D01*
G01X788953Y520130D02*
X789783Y519300D01*
G01X793326Y513974D02*
X793028D01*
G01X791488Y512914D02*
X792886D01*
G01X794580Y512720D02*
X793326Y513974D01*
G01X792886Y512914D02*
X793520Y512280D01*
G01X794580Y506092D02*
Y512720D01*
G01X793520Y512280D02*
Y509520D01*
G01X794580Y506092D02*
Y512720D01*
G01X793520Y507080D02*
Y505649D01*
G01X797480Y503192D02*
X794580Y506092D01*
G01X793520Y505649D02*
X796420Y502749D01*
G01X797480Y500749D02*
Y503192D01*
G01X796420Y502749D02*
Y501192D01*
G01X795623Y498892D02*
X797480Y500749D01*
G01X796420Y501192D02*
X795180Y499952D01*
G01X794452Y498892D02*
X795623D01*
G01D02*
X797480Y500749D01*
G01X795180Y499952D02*
X794009D01*
G01X793580Y498020D02*
X794452Y498892D01*
G01X794009Y499952D02*
X792520Y498463D01*
G01X793580Y496324D02*
Y498020D01*
G01X792520Y498463D02*
Y495881D01*
G01X794452Y495452D02*
X793580Y496324D01*
G01X792520Y495881D02*
X794009Y494392D01*
G01X795991Y495452D02*
X794452D01*
G01X794009Y494392D02*
X795548D01*
G01X797480Y493963D02*
X795991Y495452D01*
G01X795548Y494392D02*
X796420Y493520D01*
G01X797480Y491381D02*
Y493963D01*
G01X796420Y493520D02*
Y491824D01*
G01X795991Y489892D02*
X797480Y491381D01*
G01X796420Y491824D02*
X795548Y490952D01*
G01X794652Y489892D02*
X795991D01*
G01X795548Y490952D02*
X794209D01*
G01X793780Y489020D02*
X794652Y489892D01*
G01X794209Y490952D02*
X792720Y489463D01*
G01X793780Y487324D02*
Y489020D01*
G01X792720Y489463D02*
Y486881D01*
G01X794652Y486452D02*
X793780Y487324D01*
G01X792720Y486881D02*
X794209Y485392D01*
G01X795991Y486452D02*
X794652D01*
G01X794209Y485392D02*
X795548D01*
G01X797480Y484963D02*
X795991Y486452D01*
G01X795548Y485392D02*
X796420Y484520D01*
G01X797480Y482381D02*
Y484963D01*
G01X796420Y484520D02*
Y482824D01*
G01X795991Y480892D02*
X797480Y482381D01*
G01X796420Y482824D02*
X795548Y481952D01*
G01X794852Y480892D02*
X795991D01*
G01X795548Y481952D02*
X794409D01*
G01X793980Y480020D02*
X794852Y480892D01*
G01X794409Y481952D02*
X792920Y480463D01*
G01X793980Y478324D02*
Y480020D01*
G01X792920Y480463D02*
Y477881D01*
G01X794852Y477452D02*
X793980Y478324D01*
G01X792920Y477881D02*
X794409Y476392D01*
G01X795988Y477452D02*
X794852D01*
G01X794409Y476392D02*
X795548D01*
G01X797480Y475960D02*
X795988Y477452D01*
G01X795548Y476392D02*
X796420Y475520D01*
G01X821211Y532411D02*
Y514400D01*
G01X822271Y526760D02*
Y525340D01*
G01X821211Y532411D02*
Y514400D01*
G01X822271Y521660D02*
Y520290D01*
G01X827595Y527000D02*
X826824Y526229D01*
G01D02*
Y525338D01*
G01Y521848D02*
Y520571D01*
G01X825764Y526670D02*
Y520130D01*
G01X826824Y520571D02*
X827495Y519900D01*
G01X825764Y520130D02*
X826594Y519300D01*
G01X788953Y520130D02*
X789783Y519300D01*
G01X790684Y519900D02*
X790013Y520571D01*
G01X788953Y526670D02*
Y520130D01*
G01X790013Y520571D02*
Y521848D01*
G01X788953Y526670D02*
Y520130D01*
G01X790013Y525338D02*
Y526229D01*
G01D02*
X790784Y527000D01*
G01X795548Y476392D02*
X796420Y475520D01*
G01X797480Y475960D02*
X795988Y477452D01*
G01X794409Y476392D02*
X795548D01*
G01X795988Y477452D02*
X794852D01*
G01X792920Y477881D02*
X794409Y476392D01*
G01X794852Y477452D02*
X793980Y478324D01*
G01X792920Y480463D02*
Y477881D01*
G01X793980Y478324D02*
Y480020D01*
G01X794409Y481952D02*
X792920Y480463D01*
G01X793980Y480020D02*
X794852Y480892D01*
G01X795548Y481952D02*
X794409D01*
G01X794852Y480892D02*
X795991D01*
G01X796420Y482824D02*
X795548Y481952D01*
G01X795991Y480892D02*
X797480Y482381D01*
G01X796420Y484520D02*
Y482824D01*
G01X797480Y482381D02*
Y484963D01*
G01X795548Y485392D02*
X796420Y484520D01*
G01X797480Y484963D02*
X795991Y486452D01*
G01X794209Y485392D02*
X795548D01*
G01X795991Y486452D02*
X794652D01*
G01X792720Y486881D02*
X794209Y485392D01*
G01X794652Y486452D02*
X793780Y487324D01*
G01X792720Y489463D02*
Y486881D01*
G01X793780Y487324D02*
Y489020D01*
G01X794209Y490952D02*
X792720Y489463D01*
G01X793780Y489020D02*
X794652Y489892D01*
G01X795548Y490952D02*
X794209D01*
G01X794652Y489892D02*
X795991D01*
G01X796420Y491824D02*
X795548Y490952D01*
G01X795991Y489892D02*
X797480Y491381D01*
G01X796420Y493520D02*
Y491824D01*
G01X797480Y491381D02*
Y493963D01*
G01X795548Y494392D02*
X796420Y493520D01*
G01X797480Y493963D02*
X795991Y495452D01*
G01X794009Y494392D02*
X795548D01*
G01X795991Y495452D02*
X794452D01*
G01X792520Y495881D02*
X794009Y494392D01*
G01X794452Y495452D02*
X793580Y496324D01*
G01X792520Y498463D02*
Y495881D01*
G01X793580Y496324D02*
Y498020D01*
G01X794009Y499952D02*
X792520Y498463D01*
G01X793580Y498020D02*
X794452Y498892D01*
G01X795180Y499952D02*
X794009D01*
G01X794452Y498892D02*
X795623D01*
G01X796420Y501192D02*
X795180Y499952D01*
G01D02*
X794009D01*
G01X795623Y498892D02*
X797480Y500749D01*
G01X796420Y502749D02*
Y501192D01*
G01X797480Y500749D02*
Y503192D01*
G01X793520Y505649D02*
X796420Y502749D01*
G01X797480Y503192D02*
X794580Y506092D01*
G01X793520Y512280D02*
Y509520D01*
G01Y507080D02*
Y505649D01*
G01X794580Y506092D02*
Y512720D01*
G01X792886Y512914D02*
X793520Y512280D01*
G01X794580Y512720D02*
X793326Y513974D01*
G01X791488Y512914D02*
X792886D01*
G01X793326Y513974D02*
X793028D01*
G01X822271Y526760D02*
Y525340D01*
G01Y521660D02*
Y520290D01*
G01X821211Y532411D02*
Y514400D01*
G01X827595Y527000D02*
X826824Y526229D01*
G01X825764Y526670D02*
Y520130D01*
G01X826824Y526229D02*
Y525338D01*
G01X825764Y526670D02*
Y520130D01*
G01X826824Y521848D02*
Y520571D01*
G01X825764Y520130D02*
X826594Y519300D01*
G01X826824Y520571D02*
X827495Y519900D01*
G01X789783Y527500D02*
X788953Y526670D01*
G01X789783Y527500D02*
X788953Y526670D01*
G01X789783Y527500D02*
X788953Y526670D01*
G01X826594Y527500D02*
X825764Y526670D01*
G01X789783Y527500D02*
X788953Y526670D01*
G01X826594Y527500D02*
X825764Y526670D01*
G01X861345Y70380D02*
X860829D01*
G01X860806Y69320D02*
X861788D01*
G01X862056Y71091D02*
X861345Y70380D01*
G01D02*
X860829D01*
G01X861788Y69320D02*
X863116Y70648D01*
G01X862056Y86353D02*
Y83820D01*
G01Y79680D02*
Y78720D01*
G01Y74380D02*
Y71091D01*
G01X863116Y70648D02*
Y86794D01*
G01X861109Y87300D02*
X862056Y86353D01*
G01X863116Y86794D02*
X860010Y89900D01*
G01X859768Y94500D02*
X858172Y96096D01*
G01X861345Y70380D02*
X860829D01*
G01X860806Y69320D02*
X861788D01*
G01X862056Y71091D02*
X861345Y70380D01*
G01D02*
X860829D01*
G01X861788Y69320D02*
X863116Y70648D01*
G01X862056Y86353D02*
Y83820D01*
G01Y79680D02*
Y78720D01*
G01Y74380D02*
Y71091D01*
G01X863116Y70648D02*
Y86794D01*
G01X861109Y87300D02*
X862056Y86353D01*
G01X863116Y86794D02*
X860010Y89900D01*
G01X859768Y94500D02*
X858172Y96096D01*
G01X894967Y97331D02*
Y89154D01*
G01X898156Y70380D02*
X897640D01*
G01X897617Y69320D02*
X898599D01*
G01X898867Y71091D02*
X898156Y70380D01*
G01D02*
X897640D01*
G01X898599Y69320D02*
X899927Y70648D01*
G01X898867Y86353D02*
Y83820D01*
G01Y79680D02*
Y78720D01*
G01Y74380D02*
Y71091D01*
G01X899927Y70648D02*
Y86794D01*
G01X896821Y87300D02*
X897920D01*
G01D02*
X898867Y86353D01*
G01X899927Y86794D02*
X896821Y89900D01*
G01X894967Y97331D02*
Y89154D01*
G01X898156Y70380D02*
X897640D01*
G01X897617Y69320D02*
X898599D01*
G01X898867Y71091D02*
X898156Y70380D01*
G01D02*
X897640D01*
G01X898599Y69320D02*
X899927Y70648D01*
G01X898867Y86353D02*
Y83820D01*
G01Y79680D02*
Y78720D01*
G01Y74380D02*
Y71091D01*
G01X899927Y70648D02*
Y86794D01*
G01X896821Y87300D02*
X897920D01*
G01D02*
X898867Y86353D01*
G01X899927Y86794D02*
X896821Y89900D01*
G01X868302Y86922D02*
X865110Y90114D01*
G01Y87515D02*
X866208D01*
G01X868302Y86922D02*
X865110Y90114D01*
G01X866208Y87515D02*
X867242Y86481D01*
G01X868302Y71532D02*
Y86922D01*
G01X867242Y86481D02*
Y83706D01*
G01X868302Y71532D02*
Y86922D01*
G01X867242Y79880D02*
Y78507D01*
G01X868302Y71532D02*
Y86922D01*
G01X867242Y74593D02*
Y71972D01*
G01X865110Y68340D02*
X868302Y71532D01*
G01X867242Y71972D02*
X866219Y70949D01*
G01X866936Y93332D02*
X863104Y97164D01*
G01X868302Y86922D02*
X865110Y90114D01*
G01Y87515D02*
X866208D01*
G01X868302Y86922D02*
X865110Y90114D01*
G01X866208Y87515D02*
X867242Y86481D01*
G01X868302Y71532D02*
Y86922D01*
G01X867242Y86481D02*
Y83706D01*
G01X868302Y71532D02*
Y86922D01*
G01X867242Y79880D02*
Y78507D01*
G01X868302Y71532D02*
Y86922D01*
G01X867242Y74593D02*
Y71972D01*
G01X865110Y68340D02*
X868302Y71532D01*
G01X867242Y71972D02*
X866219Y70949D01*
G01X866936Y93332D02*
X863104Y97164D01*
G01X905113Y86922D02*
X901921Y90114D01*
G01Y87515D02*
X903019D01*
G01X905113Y86922D02*
X901921Y90114D01*
G01X903019Y87515D02*
X904053Y86481D01*
G01X905113Y71532D02*
Y86922D01*
G01X904053Y86481D02*
Y83706D01*
G01X905113Y71532D02*
Y86922D01*
G01X904053Y79880D02*
Y78507D01*
G01X905113Y71532D02*
Y86922D01*
G01X904053Y74593D02*
Y71972D01*
G01X901921Y68340D02*
X905113Y71532D01*
G01X904053Y71972D02*
X903030Y70949D01*
G01X905113Y86922D02*
X901921Y90114D01*
G01Y87515D02*
X903019D01*
G01X905113Y86922D02*
X901921Y90114D01*
G01X903019Y87515D02*
X904053Y86481D01*
G01X905113Y71532D02*
Y86922D01*
G01X904053Y86481D02*
Y83706D01*
G01X905113Y71532D02*
Y86922D01*
G01X904053Y79880D02*
Y78507D01*
G01X905113Y71532D02*
Y86922D01*
G01X904053Y74593D02*
Y71972D01*
G01X901921Y68340D02*
X905113Y71532D01*
G01X904053Y71972D02*
X903030Y70949D01*
G01X863116Y86794D02*
X860010Y89900D01*
G01X861109Y87300D02*
X862056Y86353D01*
G01X863116Y70648D02*
Y86794D01*
G01X862056Y86353D02*
Y83820D01*
G01X863116Y70648D02*
Y86794D01*
G01X862056Y79680D02*
Y78720D01*
G01X863116Y70648D02*
Y86794D01*
G01X862056Y74380D02*
Y71091D01*
G01X861788Y69320D02*
X863116Y70648D01*
G01X862056Y71091D02*
X861345Y70380D01*
G01X860806Y69320D02*
X861788D01*
G01D02*
X863116Y70648D01*
G01X861345Y70380D02*
X860829D01*
G01X859768Y94500D02*
X858172Y96096D01*
G01X863116Y86794D02*
X860010Y89900D01*
G01X861109Y87300D02*
X862056Y86353D01*
G01X863116Y70648D02*
Y86794D01*
G01X862056Y86353D02*
Y83820D01*
G01X863116Y70648D02*
Y86794D01*
G01X862056Y79680D02*
Y78720D01*
G01X863116Y70648D02*
Y86794D01*
G01X862056Y74380D02*
Y71091D01*
G01X861788Y69320D02*
X863116Y70648D01*
G01X862056Y71091D02*
X861345Y70380D01*
G01X860806Y69320D02*
X861788D01*
G01D02*
X863116Y70648D01*
G01X861345Y70380D02*
X860829D01*
G01X859768Y94500D02*
X858172Y96096D01*
G01X899927Y86794D02*
X896821Y89900D01*
G01Y87300D02*
X897920D01*
G01X899927Y86794D02*
X896821Y89900D01*
G01X897920Y87300D02*
X898867Y86353D01*
G01X899927Y70648D02*
Y86794D01*
G01X898867Y86353D02*
Y83820D01*
G01X899927Y70648D02*
Y86794D01*
G01X898867Y79680D02*
Y78720D01*
G01X899927Y70648D02*
Y86794D01*
G01X898867Y74380D02*
Y71091D01*
G01X898599Y69320D02*
X899927Y70648D01*
G01X898867Y71091D02*
X898156Y70380D01*
G01X897617Y69320D02*
X898599D01*
G01D02*
X899927Y70648D01*
G01X898156Y70380D02*
X897640D01*
G01X894967Y97331D02*
Y89154D01*
G01X899927Y86794D02*
X896821Y89900D01*
G01Y87300D02*
X897920D01*
G01X899927Y86794D02*
X896821Y89900D01*
G01X897920Y87300D02*
X898867Y86353D01*
G01X899927Y70648D02*
Y86794D01*
G01X898867Y86353D02*
Y83820D01*
G01X899927Y70648D02*
Y86794D01*
G01X898867Y79680D02*
Y78720D01*
G01X899927Y70648D02*
Y86794D01*
G01X898867Y74380D02*
Y71091D01*
G01X898599Y69320D02*
X899927Y70648D01*
G01X898867Y71091D02*
X898156Y70380D01*
G01X897617Y69320D02*
X898599D01*
G01D02*
X899927Y70648D01*
G01X898156Y70380D02*
X897640D01*
G01X894967Y97331D02*
Y89154D01*
G01X867242Y71972D02*
X866219Y70949D01*
G01X865110Y68340D02*
X868302Y71532D01*
G01X867242Y86481D02*
Y83706D01*
G01Y79880D02*
Y78507D01*
G01Y74593D02*
Y71972D01*
G01X868302Y71532D02*
Y86922D01*
G01X865110Y87515D02*
X866208D01*
G01D02*
X867242Y86481D01*
G01X868302Y86922D02*
X865110Y90114D01*
G01X866936Y93332D02*
X863104Y97164D01*
G01X867242Y71972D02*
X866219Y70949D01*
G01X865110Y68340D02*
X868302Y71532D01*
G01X867242Y86481D02*
Y83706D01*
G01Y79880D02*
Y78507D01*
G01Y74593D02*
Y71972D01*
G01X868302Y71532D02*
Y86922D01*
G01X865110Y87515D02*
X866208D01*
G01D02*
X867242Y86481D01*
G01X868302Y86922D02*
X865110Y90114D01*
G01X866936Y93332D02*
X863104Y97164D01*
G01X904053Y71972D02*
X903030Y70949D01*
G01X901921Y68340D02*
X905113Y71532D01*
G01X904053Y86481D02*
Y83706D01*
G01Y79880D02*
Y78507D01*
G01Y74593D02*
Y71972D01*
G01X905113Y71532D02*
Y86922D01*
G01X901921Y87515D02*
X903019D01*
G01D02*
X904053Y86481D01*
G01X905113Y86922D02*
X901921Y90114D01*
G01X904053Y71972D02*
X903030Y70949D01*
G01X901921Y68340D02*
X905113Y71532D01*
G01X904053Y86481D02*
Y83706D01*
G01Y79880D02*
Y78507D01*
G01Y74593D02*
Y71972D01*
G01X905113Y71532D02*
Y86922D01*
G01X901921Y87515D02*
X903019D01*
G01D02*
X904053Y86481D01*
G01X905113Y86922D02*
X901921Y90114D01*
G01X857112Y95653D02*
X858036Y94729D01*
G01X857112Y129357D02*
Y95653D01*
G01X858172Y96096D02*
Y97024D01*
G01X857112Y129357D02*
Y95653D01*
G01X858172Y99264D02*
Y100024D01*
G01X857112Y129357D02*
Y95653D01*
G01X858172Y102264D02*
Y103024D01*
G01X857112Y129357D02*
Y95653D01*
G01X858172Y105264D02*
Y106024D01*
G01X857112Y129357D02*
Y95653D01*
G01X858172Y108264D02*
Y129800D01*
G01X855712Y130757D02*
X857112Y129357D01*
G01X858172Y129800D02*
X856772Y131200D01*
G01X855712Y149048D02*
Y130757D01*
G01X856772Y131200D02*
Y148605D01*
G01X857109Y150445D02*
X855712Y149048D01*
G01X856772Y148605D02*
X857552Y149385D01*
G01X858891Y150445D02*
X857109D01*
G01X857552Y149385D02*
X859331D01*
G01X859690Y151244D02*
X858891Y150445D01*
G01D02*
X857109D01*
G01X859331Y149385D02*
X860750Y150804D01*
G01X859690Y153816D02*
Y151244D01*
G01X860750Y150804D02*
Y154256D01*
G01X858821Y154685D02*
X859690Y153816D01*
G01X860750Y154256D02*
X859261Y155745D01*
G01X856462Y154685D02*
X858821D01*
G01X859261Y155745D02*
X856902D01*
G01X855140Y156007D02*
X856462Y154685D01*
G01X856902Y155745D02*
X856200Y156447D01*
G01X855140Y159553D02*
Y156007D01*
G01X857112Y95653D02*
X858036Y94729D01*
G01X857112Y129357D02*
Y95653D01*
G01X858172Y96096D02*
Y97024D01*
G01X857112Y129357D02*
Y95653D01*
G01X858172Y99264D02*
Y100024D01*
G01X857112Y129357D02*
Y95653D01*
G01X858172Y102264D02*
Y103024D01*
G01X857112Y129357D02*
Y95653D01*
G01X858172Y105264D02*
Y106024D01*
G01X857112Y129357D02*
Y95653D01*
G01X858172Y108264D02*
Y129800D01*
G01X855712Y130757D02*
X857112Y129357D01*
G01X858172Y129800D02*
X856772Y131200D01*
G01X855712Y149048D02*
Y130757D01*
G01X856772Y131200D02*
Y148605D01*
G01X857109Y150445D02*
X855712Y149048D01*
G01X856772Y148605D02*
X857552Y149385D01*
G01X858891Y150445D02*
X857109D01*
G01X857552Y149385D02*
X859331D01*
G01X859690Y151244D02*
X858891Y150445D01*
G01D02*
X857109D01*
G01X859331Y149385D02*
X860750Y150804D01*
G01X859690Y153816D02*
Y151244D01*
G01X860750Y150804D02*
Y154256D01*
G01X858821Y154685D02*
X859690Y153816D01*
G01X860750Y154256D02*
X859261Y155745D01*
G01X856462Y154685D02*
X858821D01*
G01X859261Y155745D02*
X856902D01*
G01X855140Y156007D02*
X856462Y154685D01*
G01X856902Y155745D02*
X856200Y156447D01*
G01X855140Y159553D02*
Y156007D01*
G01X896027Y95220D02*
Y96888D01*
G01X898794Y101158D02*
X894967Y97331D01*
G01X896027Y96888D02*
X899854Y100715D01*
G01X898794Y133065D02*
Y101158D01*
G01X899854Y100715D02*
Y115630D01*
G01X898794Y133065D02*
Y101158D01*
G01X899854Y118420D02*
Y119180D01*
G01X898794Y133065D02*
Y101158D01*
G01X899854Y121420D02*
Y122180D01*
G01X898794Y133065D02*
Y101158D01*
G01X899854Y124420D02*
Y125180D01*
G01X898794Y133065D02*
Y101158D01*
G01X899854Y127420D02*
Y132622D01*
G01X899112Y133383D02*
X898794Y133065D01*
G01X899854Y132622D02*
X900172Y132940D01*
G01X899112Y143876D02*
Y133383D01*
G01X900172Y132940D02*
Y144319D01*
G01X898340Y144648D02*
X899112Y143876D01*
G01X900172Y144319D02*
X898783Y145708D01*
G01X897401Y144648D02*
X898340D01*
G01X898783Y145708D02*
X897844D01*
G01X895912Y146137D02*
X897401Y144648D01*
G01X897844Y145708D02*
X896972Y146580D01*
G01X895912Y149519D02*
Y146137D01*
G01X896972Y146580D02*
Y149076D01*
G01X897401Y151008D02*
X895912Y149519D01*
G01X896972Y149076D02*
X897844Y149948D01*
G01X899240Y151008D02*
X897401D01*
G01X897844Y149948D02*
X899683D01*
G01X900112Y151880D02*
X899240Y151008D01*
G01X899683Y149948D02*
X901172Y151437D01*
G01X900112Y154376D02*
Y151880D01*
G01X901172Y151437D02*
Y154819D01*
G01X899240Y155248D02*
X900112Y154376D01*
G01X901172Y154819D02*
X899683Y156308D01*
G01X897401Y155248D02*
X899240D01*
G01X895912Y156737D02*
X897401Y155248D01*
G01X897844Y156308D02*
X896972Y157180D01*
G01X896027Y95220D02*
Y96888D01*
G01X898794Y101158D02*
X894967Y97331D01*
G01X896027Y96888D02*
X899854Y100715D01*
G01X898794Y133065D02*
Y101158D01*
G01X899854Y100715D02*
Y115630D01*
G01X898794Y133065D02*
Y101158D01*
G01X899854Y118420D02*
Y119180D01*
G01X898794Y133065D02*
Y101158D01*
G01X899854Y121420D02*
Y122180D01*
G01X898794Y133065D02*
Y101158D01*
G01X899854Y124420D02*
Y125180D01*
G01X898794Y133065D02*
Y101158D01*
G01X899854Y127420D02*
Y132622D01*
G01X899112Y133383D02*
X898794Y133065D01*
G01X899854Y132622D02*
X900172Y132940D01*
G01X899112Y143876D02*
Y133383D01*
G01X900172Y132940D02*
Y144319D01*
G01X898340Y144648D02*
X899112Y143876D01*
G01X900172Y144319D02*
X898783Y145708D01*
G01X897401Y144648D02*
X898340D01*
G01X898783Y145708D02*
X897844D01*
G01X895912Y146137D02*
X897401Y144648D01*
G01X897844Y145708D02*
X896972Y146580D01*
G01X895912Y149519D02*
Y146137D01*
G01X896972Y146580D02*
Y149076D01*
G01X897401Y151008D02*
X895912Y149519D01*
G01X896972Y149076D02*
X897844Y149948D01*
G01X899240Y151008D02*
X897401D01*
G01X897844Y149948D02*
X899683D01*
G01X900112Y151880D02*
X899240Y151008D01*
G01X899683Y149948D02*
X901172Y151437D01*
G01X900112Y154376D02*
Y151880D01*
G01X901172Y151437D02*
Y154819D01*
G01X899240Y155248D02*
X900112Y154376D01*
G01X901172Y154819D02*
X899683Y156308D01*
G01X897401Y155248D02*
X899240D01*
G01X895912Y156737D02*
X897401Y155248D01*
G01X897844Y156308D02*
X896972Y157180D01*
G01X863872Y147321D02*
Y168138D01*
G01X862812Y168578D02*
Y147764D01*
G01X862383Y145832D02*
X863872Y147321D01*
G01X862812Y147764D02*
X861940Y146892D01*
G01X861744Y145832D02*
X862383D01*
G01X861940Y146892D02*
X861301D01*
G01X860572Y144660D02*
X861744Y145832D01*
G01X861301Y146892D02*
X859512Y145103D01*
G01X860572Y142464D02*
Y144660D01*
G01X859512Y145103D02*
Y142021D01*
G01X861444Y141592D02*
X860572Y142464D01*
G01X859512Y142021D02*
X861001Y140532D01*
G01X862383Y141592D02*
X861444D01*
G01X861001Y140532D02*
X861940D01*
G01X863872Y140103D02*
X862383Y141592D01*
G01X861940Y140532D02*
X862812Y139660D01*
G01X863872Y136721D02*
Y140103D01*
G01X862812Y139660D02*
Y137164D01*
G01X862383Y135232D02*
X863872Y136721D01*
G01X862812Y137164D02*
X861940Y136292D01*
G01X861840Y135232D02*
X862383D01*
G01X861940Y136292D02*
X861397D01*
G01X860872Y134264D02*
X861840Y135232D01*
G01X861397Y136292D02*
X859812Y134707D01*
G01X860872Y132764D02*
Y134264D01*
G01X859812Y134707D02*
Y132324D01*
G01X863872Y129764D02*
X860872Y132764D01*
G01X859812Y132324D02*
X862812Y129324D01*
G01X863872Y125960D02*
Y129764D01*
G01X862812Y129324D02*
Y126400D01*
G01X861660Y123748D02*
X863872Y125960D01*
G01X862812Y126400D02*
X860600Y124188D01*
G01X861660Y121552D02*
Y123748D01*
G01X860600Y124188D02*
Y121112D01*
G01X863872Y119340D02*
X861660Y121552D01*
G01X860600Y121112D02*
X862812Y118900D01*
G01X863872Y114572D02*
Y119340D01*
G01X862812Y118900D02*
Y115012D01*
G01X863104Y113804D02*
X863872Y114572D01*
G01X862812Y115012D02*
X862044Y114244D01*
G01X863104Y97164D02*
Y98092D01*
G01Y100332D02*
Y101092D01*
G01Y103332D02*
Y104092D01*
G01Y106332D02*
Y107092D01*
G01Y109332D02*
Y110180D01*
G01Y112420D02*
Y113804D01*
G01X862044Y114244D02*
Y96721D01*
G01D02*
X863386Y95379D01*
G01X863872Y147321D02*
Y168138D01*
G01X862812Y168578D02*
Y147764D01*
G01X862383Y145832D02*
X863872Y147321D01*
G01X862812Y147764D02*
X861940Y146892D01*
G01X861744Y145832D02*
X862383D01*
G01X861940Y146892D02*
X861301D01*
G01X860572Y144660D02*
X861744Y145832D01*
G01X861301Y146892D02*
X859512Y145103D01*
G01X860572Y142464D02*
Y144660D01*
G01X859512Y145103D02*
Y142021D01*
G01X861444Y141592D02*
X860572Y142464D01*
G01X859512Y142021D02*
X861001Y140532D01*
G01X862383Y141592D02*
X861444D01*
G01X861001Y140532D02*
X861940D01*
G01X863872Y140103D02*
X862383Y141592D01*
G01X861940Y140532D02*
X862812Y139660D01*
G01X863872Y136721D02*
Y140103D01*
G01X862812Y139660D02*
Y137164D01*
G01X862383Y135232D02*
X863872Y136721D01*
G01X862812Y137164D02*
X861940Y136292D01*
G01X861840Y135232D02*
X862383D01*
G01X861940Y136292D02*
X861397D01*
G01X860872Y134264D02*
X861840Y135232D01*
G01X861397Y136292D02*
X859812Y134707D01*
G01X860872Y132764D02*
Y134264D01*
G01X859812Y134707D02*
Y132324D01*
G01X863872Y129764D02*
X860872Y132764D01*
G01X859812Y132324D02*
X862812Y129324D01*
G01X863872Y125960D02*
Y129764D01*
G01X862812Y129324D02*
Y126400D01*
G01X861660Y123748D02*
X863872Y125960D01*
G01X862812Y126400D02*
X860600Y124188D01*
G01X861660Y121552D02*
Y123748D01*
G01X860600Y124188D02*
Y121112D01*
G01X863872Y119340D02*
X861660Y121552D01*
G01X860600Y121112D02*
X862812Y118900D01*
G01X863872Y114572D02*
Y119340D01*
G01X862812Y118900D02*
Y115012D01*
G01X863104Y113804D02*
X863872Y114572D01*
G01X862812Y115012D02*
X862044Y114244D01*
G01X863104Y97164D02*
Y98092D01*
G01Y100332D02*
Y101092D01*
G01Y103332D02*
Y104092D01*
G01Y106332D02*
Y107092D01*
G01Y109332D02*
Y110180D01*
G01Y112420D02*
Y113804D01*
G01X862044Y114244D02*
Y96721D01*
G01D02*
X863386Y95379D01*
G01X905054Y99715D02*
Y113280D01*
G01Y115520D02*
Y116280D01*
G01Y118520D02*
Y119280D01*
G01Y121520D02*
Y122280D01*
G01Y124520D02*
Y125280D01*
G01Y127520D02*
Y161428D01*
G01X903994Y161868D02*
Y100158D01*
G01X901727Y96388D02*
X902701Y97362D01*
G01D02*
X903577D01*
G01X904285Y98946D02*
X905054Y99715D01*
G01X903994Y100158D02*
X900667Y96831D01*
G01X901727Y95520D02*
Y96388D01*
G01X900667Y96831D02*
Y94567D01*
G01X905054Y99715D02*
Y113280D01*
G01Y115520D02*
Y116280D01*
G01Y118520D02*
Y119280D01*
G01Y121520D02*
Y122280D01*
G01Y124520D02*
Y125280D01*
G01Y127520D02*
Y161428D01*
G01X903994Y161868D02*
Y100158D01*
G01X901727Y96388D02*
X902701Y97362D01*
G01D02*
X903577D01*
G01X904285Y98946D02*
X905054Y99715D01*
G01X903994Y100158D02*
X900667Y96831D01*
G01X901727Y95520D02*
Y96388D01*
G01X900667Y96831D02*
Y94567D01*
G01X855140Y159553D02*
Y156007D01*
G01X856902Y155745D02*
X856200Y156447D01*
G01X855140Y156007D02*
X856462Y154685D01*
G01X859261Y155745D02*
X856902D01*
G01X856462Y154685D02*
X858821D01*
G01X860750Y154256D02*
X859261Y155745D01*
G01X858821Y154685D02*
X859690Y153816D01*
G01X860750Y150804D02*
Y154256D01*
G01X859690Y153816D02*
Y151244D01*
G01X859331Y149385D02*
X860750Y150804D01*
G01X859690Y151244D02*
X858891Y150445D01*
G01X857552Y149385D02*
X859331D01*
G01D02*
X860750Y150804D01*
G01X858891Y150445D02*
X857109D01*
G01X856772Y148605D02*
X857552Y149385D01*
G01X857109Y150445D02*
X855712Y149048D01*
G01X856772Y131200D02*
Y148605D01*
G01X855712Y149048D02*
Y130757D01*
G01X858172Y129800D02*
X856772Y131200D01*
G01X855712Y130757D02*
X857112Y129357D01*
G01X858172Y96096D02*
Y97024D01*
G01Y99264D02*
Y100024D01*
G01Y102264D02*
Y103024D01*
G01Y105264D02*
Y106024D01*
G01Y108264D02*
Y129800D01*
G01X857112Y129357D02*
Y95653D01*
G01D02*
X858036Y94729D01*
G01X855140Y159553D02*
Y156007D01*
G01X856902Y155745D02*
X856200Y156447D01*
G01X855140Y156007D02*
X856462Y154685D01*
G01X859261Y155745D02*
X856902D01*
G01X856462Y154685D02*
X858821D01*
G01X860750Y154256D02*
X859261Y155745D01*
G01X858821Y154685D02*
X859690Y153816D01*
G01X860750Y150804D02*
Y154256D01*
G01X859690Y153816D02*
Y151244D01*
G01X859331Y149385D02*
X860750Y150804D01*
G01X859690Y151244D02*
X858891Y150445D01*
G01X857552Y149385D02*
X859331D01*
G01D02*
X860750Y150804D01*
G01X858891Y150445D02*
X857109D01*
G01X856772Y148605D02*
X857552Y149385D01*
G01X857109Y150445D02*
X855712Y149048D01*
G01X856772Y131200D02*
Y148605D01*
G01X855712Y149048D02*
Y130757D01*
G01X858172Y129800D02*
X856772Y131200D01*
G01X855712Y130757D02*
X857112Y129357D01*
G01X858172Y96096D02*
Y97024D01*
G01Y99264D02*
Y100024D01*
G01Y102264D02*
Y103024D01*
G01Y105264D02*
Y106024D01*
G01Y108264D02*
Y129800D01*
G01X857112Y129357D02*
Y95653D01*
G01D02*
X858036Y94729D01*
G01X897844Y156308D02*
X896972Y157180D01*
G01X895912Y156737D02*
X897401Y155248D01*
G01D02*
X899240D01*
G01X901172Y154819D02*
X899683Y156308D01*
G01X899240Y155248D02*
X900112Y154376D01*
G01X901172Y151437D02*
Y154819D01*
G01X900112Y154376D02*
Y151880D01*
G01X899683Y149948D02*
X901172Y151437D01*
G01X900112Y151880D02*
X899240Y151008D01*
G01X897844Y149948D02*
X899683D01*
G01X899240Y151008D02*
X897401D01*
G01X896972Y149076D02*
X897844Y149948D01*
G01X897401Y151008D02*
X895912Y149519D01*
G01X896972Y146580D02*
Y149076D01*
G01X895912Y149519D02*
Y146137D01*
G01X897844Y145708D02*
X896972Y146580D01*
G01X895912Y146137D02*
X897401Y144648D01*
G01X898783Y145708D02*
X897844D01*
G01X897401Y144648D02*
X898340D01*
G01X900172Y144319D02*
X898783Y145708D01*
G01X898340Y144648D02*
X899112Y143876D01*
G01X900172Y132940D02*
Y144319D01*
G01X899112Y143876D02*
Y133383D01*
G01X899854Y132622D02*
X900172Y132940D01*
G01X899112Y133383D02*
X898794Y133065D01*
G01X899854Y100715D02*
Y115630D01*
G01Y118420D02*
Y119180D01*
G01Y121420D02*
Y122180D01*
G01Y124420D02*
Y125180D01*
G01Y127420D02*
Y132622D01*
G01X898794Y133065D02*
Y101158D01*
G01X896027Y96888D02*
X899854Y100715D01*
G01X898794Y101158D02*
X894967Y97331D01*
G01X896027Y95220D02*
Y96888D01*
G01X897844Y156308D02*
X896972Y157180D01*
G01X895912Y156737D02*
X897401Y155248D01*
G01D02*
X899240D01*
G01X901172Y154819D02*
X899683Y156308D01*
G01X899240Y155248D02*
X900112Y154376D01*
G01X901172Y151437D02*
Y154819D01*
G01X900112Y154376D02*
Y151880D01*
G01X899683Y149948D02*
X901172Y151437D01*
G01X900112Y151880D02*
X899240Y151008D01*
G01X897844Y149948D02*
X899683D01*
G01X899240Y151008D02*
X897401D01*
G01X896972Y149076D02*
X897844Y149948D01*
G01X897401Y151008D02*
X895912Y149519D01*
G01X896972Y146580D02*
Y149076D01*
G01X895912Y149519D02*
Y146137D01*
G01X897844Y145708D02*
X896972Y146580D01*
G01X895912Y146137D02*
X897401Y144648D01*
G01X898783Y145708D02*
X897844D01*
G01X897401Y144648D02*
X898340D01*
G01X900172Y144319D02*
X898783Y145708D01*
G01X898340Y144648D02*
X899112Y143876D01*
G01X900172Y132940D02*
Y144319D01*
G01X899112Y143876D02*
Y133383D01*
G01X899854Y132622D02*
X900172Y132940D01*
G01X899112Y133383D02*
X898794Y133065D01*
G01X899854Y100715D02*
Y115630D01*
G01Y118420D02*
Y119180D01*
G01Y121420D02*
Y122180D01*
G01Y124420D02*
Y125180D01*
G01Y127420D02*
Y132622D01*
G01X898794Y133065D02*
Y101158D01*
G01X896027Y96888D02*
X899854Y100715D01*
G01X898794Y101158D02*
X894967Y97331D01*
G01X896027Y95220D02*
Y96888D01*
G01X862044Y96721D02*
X863386Y95379D01*
G01X862044Y114244D02*
Y96721D01*
G01X863104Y97164D02*
Y98092D01*
G01X862044Y114244D02*
Y96721D01*
G01X863104Y100332D02*
Y101092D01*
G01X862044Y114244D02*
Y96721D01*
G01X863104Y103332D02*
Y104092D01*
G01X862044Y114244D02*
Y96721D01*
G01X863104Y106332D02*
Y107092D01*
G01X862044Y114244D02*
Y96721D01*
G01X863104Y109332D02*
Y110180D01*
G01X862044Y114244D02*
Y96721D01*
G01X863104Y112420D02*
Y113804D01*
G01X862812Y115012D02*
X862044Y114244D01*
G01X863104Y113804D02*
X863872Y114572D01*
G01X862812Y118900D02*
Y115012D01*
G01X863872Y114572D02*
Y119340D01*
G01X860600Y121112D02*
X862812Y118900D01*
G01X863872Y119340D02*
X861660Y121552D01*
G01X860600Y124188D02*
Y121112D01*
G01X861660Y121552D02*
Y123748D01*
G01X862812Y126400D02*
X860600Y124188D01*
G01X861660Y123748D02*
X863872Y125960D01*
G01X862812Y129324D02*
Y126400D01*
G01X863872Y125960D02*
Y129764D01*
G01X859812Y132324D02*
X862812Y129324D01*
G01X863872Y129764D02*
X860872Y132764D01*
G01X859812Y134707D02*
Y132324D01*
G01X860872Y132764D02*
Y134264D01*
G01X861397Y136292D02*
X859812Y134707D01*
G01X860872Y134264D02*
X861840Y135232D01*
G01X861940Y136292D02*
X861397D01*
G01X861840Y135232D02*
X862383D01*
G01X862812Y137164D02*
X861940Y136292D01*
G01X862383Y135232D02*
X863872Y136721D01*
G01X862812Y139660D02*
Y137164D01*
G01X863872Y136721D02*
Y140103D01*
G01X861940Y140532D02*
X862812Y139660D01*
G01X863872Y140103D02*
X862383Y141592D01*
G01X861001Y140532D02*
X861940D01*
G01X862383Y141592D02*
X861444D01*
G01X859512Y142021D02*
X861001Y140532D01*
G01X861444Y141592D02*
X860572Y142464D01*
G01X859512Y145103D02*
Y142021D01*
G01X860572Y142464D02*
Y144660D01*
G01X861301Y146892D02*
X859512Y145103D01*
G01X860572Y144660D02*
X861744Y145832D01*
G01X861940Y146892D02*
X861301D01*
G01X861744Y145832D02*
X862383D01*
G01X862812Y147764D02*
X861940Y146892D01*
G01X862383Y145832D02*
X863872Y147321D01*
G01X862812Y168578D02*
Y147764D01*
G01X863872Y147321D02*
Y168138D01*
G01X862044Y96721D02*
X863386Y95379D01*
G01X862044Y114244D02*
Y96721D01*
G01X863104Y97164D02*
Y98092D01*
G01X862044Y114244D02*
Y96721D01*
G01X863104Y100332D02*
Y101092D01*
G01X862044Y114244D02*
Y96721D01*
G01X863104Y103332D02*
Y104092D01*
G01X862044Y114244D02*
Y96721D01*
G01X863104Y106332D02*
Y107092D01*
G01X862044Y114244D02*
Y96721D01*
G01X863104Y109332D02*
Y110180D01*
G01X862044Y114244D02*
Y96721D01*
G01X863104Y112420D02*
Y113804D01*
G01X862812Y115012D02*
X862044Y114244D01*
G01X863104Y113804D02*
X863872Y114572D01*
G01X862812Y118900D02*
Y115012D01*
G01X863872Y114572D02*
Y119340D01*
G01X860600Y121112D02*
X862812Y118900D01*
G01X863872Y119340D02*
X861660Y121552D01*
G01X860600Y124188D02*
Y121112D01*
G01X861660Y121552D02*
Y123748D01*
G01X862812Y126400D02*
X860600Y124188D01*
G01X861660Y123748D02*
X863872Y125960D01*
G01X862812Y129324D02*
Y126400D01*
G01X863872Y125960D02*
Y129764D01*
G01X859812Y132324D02*
X862812Y129324D01*
G01X863872Y129764D02*
X860872Y132764D01*
G01X859812Y134707D02*
Y132324D01*
G01X860872Y132764D02*
Y134264D01*
G01X861397Y136292D02*
X859812Y134707D01*
G01X860872Y134264D02*
X861840Y135232D01*
G01X861940Y136292D02*
X861397D01*
G01X861840Y135232D02*
X862383D01*
G01X862812Y137164D02*
X861940Y136292D01*
G01X862383Y135232D02*
X863872Y136721D01*
G01X862812Y139660D02*
Y137164D01*
G01X863872Y136721D02*
Y140103D01*
G01X861940Y140532D02*
X862812Y139660D01*
G01X863872Y140103D02*
X862383Y141592D01*
G01X861001Y140532D02*
X861940D01*
G01X862383Y141592D02*
X861444D01*
G01X859512Y142021D02*
X861001Y140532D01*
G01X861444Y141592D02*
X860572Y142464D01*
G01X859512Y145103D02*
Y142021D01*
G01X860572Y142464D02*
Y144660D01*
G01X861301Y146892D02*
X859512Y145103D01*
G01X860572Y144660D02*
X861744Y145832D01*
G01X861940Y146892D02*
X861301D01*
G01X861744Y145832D02*
X862383D01*
G01X862812Y147764D02*
X861940Y146892D01*
G01X862383Y145832D02*
X863872Y147321D01*
G01X862812Y168578D02*
Y147764D01*
G01X863872Y147321D02*
Y168138D01*
G01X900667Y96831D02*
Y94567D01*
G01X901727Y95520D02*
Y96388D01*
G01X903994Y100158D02*
X900667Y96831D01*
G01X901727Y96388D02*
X902701Y97362D01*
G01X903994Y100158D02*
X900667Y96831D01*
G01X902701Y97362D02*
X903577D01*
G01X903994Y100158D02*
X900667Y96831D01*
G01X904285Y98946D02*
X905054Y99715D01*
G01X903994Y161868D02*
Y100158D01*
G01X905054Y99715D02*
Y113280D01*
G01X903994Y161868D02*
Y100158D01*
G01X905054Y115520D02*
Y116280D01*
G01X903994Y161868D02*
Y100158D01*
G01X905054Y118520D02*
Y119280D01*
G01X903994Y161868D02*
Y100158D01*
G01X905054Y121520D02*
Y122280D01*
G01X903994Y161868D02*
Y100158D01*
G01X905054Y124520D02*
Y125280D01*
G01X903994Y161868D02*
Y100158D01*
G01X905054Y127520D02*
Y161428D01*
G01X900667Y96831D02*
Y94567D01*
G01X901727Y95520D02*
Y96388D01*
G01X903994Y100158D02*
X900667Y96831D01*
G01X901727Y96388D02*
X902701Y97362D01*
G01X903994Y100158D02*
X900667Y96831D01*
G01X902701Y97362D02*
X903577D01*
G01X903994Y100158D02*
X900667Y96831D01*
G01X904285Y98946D02*
X905054Y99715D01*
G01X903994Y161868D02*
Y100158D01*
G01X905054Y99715D02*
Y113280D01*
G01X903994Y161868D02*
Y100158D01*
G01X905054Y115520D02*
Y116280D01*
G01X903994Y161868D02*
Y100158D01*
G01X905054Y118520D02*
Y119280D01*
G01X903994Y161868D02*
Y100158D01*
G01X905054Y121520D02*
Y122280D01*
G01X903994Y161868D02*
Y100158D01*
G01X905054Y124520D02*
Y125280D01*
G01X903994Y161868D02*
Y100158D01*
G01X905054Y127520D02*
Y161428D01*
G01X856200Y156447D02*
Y159113D01*
G01X856632Y161045D02*
X855140Y159553D01*
G01X856200Y159113D02*
X857072Y159985D01*
G01X858140Y161045D02*
X856632D01*
G01X857072Y159985D02*
X858580D01*
G01X859012Y161917D02*
X858140Y161045D01*
G01X858580Y159985D02*
X860072Y161477D01*
G01X859012Y163488D02*
Y161917D01*
G01X860072Y161477D02*
Y163928D01*
G01X856620Y165880D02*
X859012Y163488D01*
G01X860072Y163928D02*
X857680Y166320D01*
G01X856620Y167620D02*
Y165880D01*
G01X857680Y166320D02*
Y167180D01*
G01X859012Y170012D02*
X856620Y167620D01*
G01X857680Y167180D02*
X860072Y169572D01*
G01X859012Y171561D02*
Y170012D01*
G01X860072Y169572D02*
Y171121D01*
G01X907226Y219775D02*
X859012Y171561D01*
G01X860072Y171121D02*
X878978Y190027D01*
G01X907226Y219775D02*
X859012Y171561D01*
G01X880323Y191372D02*
X881053Y192102D01*
G01X907226Y219775D02*
X859012Y171561D01*
G01X882398Y193447D02*
X883098Y194147D01*
G01X907226Y219775D02*
X859012Y171561D01*
G01X884442Y195491D02*
X885078Y196127D01*
G01X907226Y219775D02*
X859012Y171561D01*
G01X886423Y197472D02*
X887103Y198152D01*
G01X907226Y219775D02*
X859012Y171561D01*
G01X888448Y199497D02*
X889103Y200152D01*
G01X907226Y219775D02*
X859012Y171561D01*
G01X890448Y201497D02*
X891528Y202577D01*
G01X907226Y219775D02*
X859012Y171561D01*
G01X892873Y203922D02*
X893703Y204752D01*
G01X907226Y219775D02*
X859012Y171561D01*
G01X895048Y206097D02*
X895903Y206952D01*
G01X907226Y219775D02*
X859012Y171561D01*
G01X897248Y208297D02*
X898018Y209067D01*
G01X907226Y219775D02*
X859012Y171561D01*
G01X899362Y210411D02*
X899998Y211047D01*
G01X907226Y219775D02*
X859012Y171561D01*
G01X901342Y212391D02*
X901978Y213027D01*
G01X907226Y219775D02*
X859012Y171561D01*
G01X903323Y214372D02*
X904016Y215065D01*
G01X907226Y219775D02*
X859012Y171561D01*
G01X905360Y216409D02*
X905996Y217045D01*
G01X907226Y219775D02*
X859012Y171561D01*
G01X856200Y156447D02*
Y159113D01*
G01X856632Y161045D02*
X855140Y159553D01*
G01X856200Y159113D02*
X857072Y159985D01*
G01X858140Y161045D02*
X856632D01*
G01X857072Y159985D02*
X858580D01*
G01X859012Y161917D02*
X858140Y161045D01*
G01X858580Y159985D02*
X860072Y161477D01*
G01X859012Y163488D02*
Y161917D01*
G01X860072Y161477D02*
Y163928D01*
G01X856620Y165880D02*
X859012Y163488D01*
G01X860072Y163928D02*
X857680Y166320D01*
G01X856620Y167620D02*
Y165880D01*
G01X857680Y166320D02*
Y167180D01*
G01X859012Y170012D02*
X856620Y167620D01*
G01X857680Y167180D02*
X860072Y169572D01*
G01X859012Y171561D02*
Y170012D01*
G01X860072Y169572D02*
Y171121D01*
G01X907226Y219775D02*
X859012Y171561D01*
G01X860072Y171121D02*
X878978Y190027D01*
G01X907226Y219775D02*
X859012Y171561D01*
G01X880323Y191372D02*
X881053Y192102D01*
G01X907226Y219775D02*
X859012Y171561D01*
G01X882398Y193447D02*
X883098Y194147D01*
G01X907226Y219775D02*
X859012Y171561D01*
G01X884442Y195491D02*
X885078Y196127D01*
G01X907226Y219775D02*
X859012Y171561D01*
G01X886423Y197472D02*
X887103Y198152D01*
G01X907226Y219775D02*
X859012Y171561D01*
G01X888448Y199497D02*
X889103Y200152D01*
G01X907226Y219775D02*
X859012Y171561D01*
G01X890448Y201497D02*
X891528Y202577D01*
G01X907226Y219775D02*
X859012Y171561D01*
G01X892873Y203922D02*
X893703Y204752D01*
G01X907226Y219775D02*
X859012Y171561D01*
G01X895048Y206097D02*
X895903Y206952D01*
G01X907226Y219775D02*
X859012Y171561D01*
G01X897248Y208297D02*
X898018Y209067D01*
G01X907226Y219775D02*
X859012Y171561D01*
G01X899362Y210411D02*
X899998Y211047D01*
G01X907226Y219775D02*
X859012Y171561D01*
G01X901342Y212391D02*
X901978Y213027D01*
G01X907226Y219775D02*
X859012Y171561D01*
G01X903323Y214372D02*
X904016Y215065D01*
G01X907226Y219775D02*
X859012Y171561D01*
G01X905360Y216409D02*
X905996Y217045D01*
G01X907226Y219775D02*
X859012Y171561D01*
G01X899683Y156308D02*
X897844D01*
G01X895912Y160119D02*
Y156737D01*
G01X896972Y157180D02*
Y159676D01*
G01X897401Y161608D02*
X895912Y160119D01*
G01X896972Y159676D02*
X897844Y160548D01*
G01X899243Y161608D02*
X897401D01*
G01X897844Y160548D02*
X899683D01*
G01X900112Y162477D02*
X899243Y161608D01*
G01X899683Y160548D02*
X901172Y162037D01*
G01X900112Y165112D02*
Y162477D01*
G01X901172Y162037D02*
Y164672D01*
G01X929600Y194600D02*
X900112Y165112D01*
G01X901172Y164672D02*
X911878Y175378D01*
G01X929600Y194600D02*
X900112Y165112D01*
G01X929600Y194600D02*
X900112Y165112D01*
G01X929600Y194600D02*
X900112Y165112D01*
G01X929600Y194600D02*
X900112Y165112D01*
G01X929600Y194600D02*
X900112Y165112D01*
G01X929600Y194600D02*
X900112Y165112D01*
G01X929600Y194600D02*
X900112Y165112D01*
G01X929600Y194600D02*
X900112Y165112D01*
G01X929600Y194600D02*
X900112Y165112D01*
G01X899683Y156308D02*
X897844D01*
G01X895912Y160119D02*
Y156737D01*
G01X896972Y157180D02*
Y159676D01*
G01X897401Y161608D02*
X895912Y160119D01*
G01X896972Y159676D02*
X897844Y160548D01*
G01X899243Y161608D02*
X897401D01*
G01X897844Y160548D02*
X899683D01*
G01X900112Y162477D02*
X899243Y161608D01*
G01X899683Y160548D02*
X901172Y162037D01*
G01X900112Y165112D02*
Y162477D01*
G01X901172Y162037D02*
Y164672D01*
G01X929600Y194600D02*
X900112Y165112D01*
G01X901172Y164672D02*
X911878Y175378D01*
G01X929600Y194600D02*
X900112Y165112D01*
G01X929600Y194600D02*
X900112Y165112D01*
G01X929600Y194600D02*
X900112Y165112D01*
G01X929600Y194600D02*
X900112Y165112D01*
G01X929600Y194600D02*
X900112Y165112D01*
G01X929600Y194600D02*
X900112Y165112D01*
G01X929600Y194600D02*
X900112Y165112D01*
G01X929600Y194600D02*
X900112Y165112D01*
G01X929600Y194600D02*
X900112Y165112D01*
G01X863872Y168138D02*
X900455Y204721D01*
G01X901799Y206065D02*
X902435Y206701D01*
G01X903779Y208045D02*
X904415Y208681D01*
G01X905759Y210025D02*
X906395Y210661D01*
G01X907739Y212005D02*
X908915Y213181D01*
G01X912630Y218396D02*
X862812Y168578D01*
G01X863872Y168138D02*
X900455Y204721D01*
G01X901799Y206065D02*
X902435Y206701D01*
G01X903779Y208045D02*
X904415Y208681D01*
G01X905759Y210025D02*
X906395Y210661D01*
G01X907739Y212005D02*
X908915Y213181D01*
G01X912630Y218396D02*
X862812Y168578D01*
G01X905054Y161428D02*
X936483Y192857D01*
G01X935423Y193297D02*
X903994Y161868D01*
G01X905054Y161428D02*
X936483Y192857D01*
G01X935423Y193297D02*
X903994Y161868D01*
G01X860072Y171121D02*
X878978Y190027D01*
G01X880323Y191372D02*
X881053Y192102D01*
G01X882398Y193447D02*
X883098Y194147D01*
G01X884442Y195491D02*
X885078Y196127D01*
G01X886423Y197472D02*
X887103Y198152D01*
G01X888448Y199497D02*
X889103Y200152D01*
G01X890448Y201497D02*
X891528Y202577D01*
G01X892873Y203922D02*
X893703Y204752D01*
G01X895048Y206097D02*
X895903Y206952D01*
G01X897248Y208297D02*
X898018Y209067D01*
G01X899362Y210411D02*
X899998Y211047D01*
G01X901342Y212391D02*
X901978Y213027D01*
G01X903323Y214372D02*
X904016Y215065D01*
G01X905360Y216409D02*
X905996Y217045D01*
G01X907226Y219775D02*
X859012Y171561D01*
G01X860072Y169572D02*
Y171121D01*
G01X859012Y171561D02*
Y170012D01*
G01X857680Y167180D02*
X860072Y169572D01*
G01X859012Y170012D02*
X856620Y167620D01*
G01X857680Y166320D02*
Y167180D01*
G01X856620Y167620D02*
Y165880D01*
G01X860072Y163928D02*
X857680Y166320D01*
G01X856620Y165880D02*
X859012Y163488D01*
G01X860072Y161477D02*
Y163928D01*
G01X859012Y163488D02*
Y161917D01*
G01X858580Y159985D02*
X860072Y161477D01*
G01X859012Y161917D02*
X858140Y161045D01*
G01X857072Y159985D02*
X858580D01*
G01X858140Y161045D02*
X856632D01*
G01X856200Y159113D02*
X857072Y159985D01*
G01X856632Y161045D02*
X855140Y159553D01*
G01X856200Y156447D02*
Y159113D01*
G01X860072Y171121D02*
X878978Y190027D01*
G01X880323Y191372D02*
X881053Y192102D01*
G01X882398Y193447D02*
X883098Y194147D01*
G01X884442Y195491D02*
X885078Y196127D01*
G01X886423Y197472D02*
X887103Y198152D01*
G01X888448Y199497D02*
X889103Y200152D01*
G01X890448Y201497D02*
X891528Y202577D01*
G01X892873Y203922D02*
X893703Y204752D01*
G01X895048Y206097D02*
X895903Y206952D01*
G01X897248Y208297D02*
X898018Y209067D01*
G01X899362Y210411D02*
X899998Y211047D01*
G01X901342Y212391D02*
X901978Y213027D01*
G01X903323Y214372D02*
X904016Y215065D01*
G01X905360Y216409D02*
X905996Y217045D01*
G01X907226Y219775D02*
X859012Y171561D01*
G01X860072Y169572D02*
Y171121D01*
G01X859012Y171561D02*
Y170012D01*
G01X857680Y167180D02*
X860072Y169572D01*
G01X859012Y170012D02*
X856620Y167620D01*
G01X857680Y166320D02*
Y167180D01*
G01X856620Y167620D02*
Y165880D01*
G01X860072Y163928D02*
X857680Y166320D01*
G01X856620Y165880D02*
X859012Y163488D01*
G01X860072Y161477D02*
Y163928D01*
G01X859012Y163488D02*
Y161917D01*
G01X858580Y159985D02*
X860072Y161477D01*
G01X859012Y161917D02*
X858140Y161045D01*
G01X857072Y159985D02*
X858580D01*
G01X858140Y161045D02*
X856632D01*
G01X856200Y159113D02*
X857072Y159985D01*
G01X856632Y161045D02*
X855140Y159553D01*
G01X856200Y156447D02*
Y159113D01*
G01X901172Y164672D02*
X911878Y175378D01*
G01X929600Y194600D02*
X900112Y165112D01*
G01X901172Y162037D02*
Y164672D01*
G01X900112Y165112D02*
Y162477D01*
G01X899683Y160548D02*
X901172Y162037D01*
G01X900112Y162477D02*
X899243Y161608D01*
G01X897844Y160548D02*
X899683D01*
G01X899243Y161608D02*
X897401D01*
G01X896972Y159676D02*
X897844Y160548D01*
G01X897401Y161608D02*
X895912Y160119D01*
G01X896972Y157180D02*
Y159676D01*
G01X895912Y160119D02*
Y156737D01*
G01X899683Y156308D02*
X897844D01*
G01X901172Y164672D02*
X911878Y175378D01*
G01X929600Y194600D02*
X900112Y165112D01*
G01X901172Y162037D02*
Y164672D01*
G01X900112Y165112D02*
Y162477D01*
G01X899683Y160548D02*
X901172Y162037D01*
G01X900112Y162477D02*
X899243Y161608D01*
G01X897844Y160548D02*
X899683D01*
G01X899243Y161608D02*
X897401D01*
G01X896972Y159676D02*
X897844Y160548D01*
G01X897401Y161608D02*
X895912Y160119D01*
G01X896972Y157180D02*
Y159676D01*
G01X895912Y160119D02*
Y156737D01*
G01X899683Y156308D02*
X897844D01*
G01X912630Y218396D02*
X862812Y168578D01*
G01X863872Y168138D02*
X900455Y204721D01*
G01X912630Y218396D02*
X862812Y168578D01*
G01X901799Y206065D02*
X902435Y206701D01*
G01X912630Y218396D02*
X862812Y168578D01*
G01X903779Y208045D02*
X904415Y208681D01*
G01X912630Y218396D02*
X862812Y168578D01*
G01X905759Y210025D02*
X906395Y210661D01*
G01X912630Y218396D02*
X862812Y168578D01*
G01X907739Y212005D02*
X908915Y213181D01*
G01X912630Y218396D02*
X862812Y168578D01*
G01X912630Y218396D02*
X862812Y168578D01*
G01X912630Y218396D02*
X862812Y168578D01*
G01X863872Y168138D02*
X900455Y204721D01*
G01X912630Y218396D02*
X862812Y168578D01*
G01X901799Y206065D02*
X902435Y206701D01*
G01X912630Y218396D02*
X862812Y168578D01*
G01X903779Y208045D02*
X904415Y208681D01*
G01X912630Y218396D02*
X862812Y168578D01*
G01X905759Y210025D02*
X906395Y210661D01*
G01X912630Y218396D02*
X862812Y168578D01*
G01X907739Y212005D02*
X908915Y213181D01*
G01X912630Y218396D02*
X862812Y168578D01*
G01X912630Y218396D02*
X862812Y168578D01*
G01X935423Y193297D02*
X903994Y161868D01*
G01X905054Y161428D02*
X936483Y192857D01*
G01X935423Y193297D02*
X903994Y161868D01*
G01X905054Y161428D02*
X936483Y192857D01*
G01X909104Y255243D02*
X899915D01*
G01X900358Y254183D02*
X908984D01*
G01X909104Y255243D02*
X899915D01*
G01X900358Y254183D02*
X908984D01*
G01X900358D02*
X908984D01*
G01X909104Y255243D02*
X899915D01*
G01X900358Y254183D02*
X908984D01*
G01X909104Y255243D02*
X899915D01*
G01X901902Y250334D02*
X909454D01*
G01Y251394D02*
X901459D01*
G01X901902Y250334D02*
X909454D01*
G01Y251394D02*
X901459D01*
G01X909454D02*
X901459D01*
G01X901902Y250334D02*
X909454D01*
G01Y251394D02*
X901459D01*
G01X901902Y250334D02*
X909454D01*
G01X907340Y218389D02*
X907976Y219025D01*
G01X907340Y218389D02*
X907976Y219025D01*
G01X907340Y218389D02*
X907976Y219025D01*
G01X907340Y218389D02*
X907976Y219025D01*
G01X908455Y340096D02*
X904163D01*
G01X908620Y341156D02*
X904603D01*
G01X904163Y340096D02*
X853440Y390819D01*
G01X904603Y341156D02*
X854500Y391259D01*
G01X908455Y340096D02*
X904163D01*
G01X908620Y341156D02*
X904603D01*
G01X904163Y340096D02*
X853440Y390819D01*
G01X904603Y341156D02*
X854500Y391259D01*
G01X908620Y341156D02*
X904603D01*
G01X908455Y340096D02*
X904163D01*
G01X904603Y341156D02*
X854500Y391259D01*
G01X904163Y340096D02*
X853440Y390819D01*
G01X908620Y341156D02*
X904603D01*
G01X908455Y340096D02*
X904163D01*
G01X904603Y341156D02*
X854500Y391259D01*
G01X904163Y340096D02*
X853440Y390819D01*
G01D02*
Y396959D01*
G01X854500Y391259D02*
Y397399D01*
G01X853440Y390819D02*
Y396959D01*
G01X854500Y391259D02*
Y397399D01*
G01Y391259D02*
Y397399D01*
G01X853440Y390819D02*
Y396959D01*
G01X854500Y391259D02*
Y397399D01*
G01X853440Y390819D02*
Y396959D01*
G01X857700Y392226D02*
Y398500D01*
G01X856640Y398060D02*
Y391786D01*
G01X905049Y344877D02*
X857700Y392226D01*
G01X856640Y391786D02*
X904609Y343817D01*
G01X908262Y344877D02*
X905049D01*
G01X904609Y343817D02*
X908262D01*
G01X904609D02*
X908262D01*
G01Y344877D02*
X905049D01*
G01X856640Y391786D02*
X904609Y343817D01*
G01X905049Y344877D02*
X857700Y392226D01*
G01X856640Y398060D02*
Y391786D01*
G01X857700Y392226D02*
Y398500D01*
G01Y392226D02*
Y398500D01*
G01X856640Y398060D02*
Y391786D01*
G01X905049Y344877D02*
X857700Y392226D01*
G01X856640Y391786D02*
X904609Y343817D01*
G01X908262Y344877D02*
X905049D01*
G01X904609Y343817D02*
X908262D01*
G01X904609D02*
X908262D01*
G01Y344877D02*
X905049D01*
G01X856640Y391786D02*
X904609Y343817D01*
G01X905049Y344877D02*
X857700Y392226D01*
G01X856640Y398060D02*
Y391786D01*
G01X857700Y392226D02*
Y398500D01*
G01X875835Y402155D02*
X907189Y370801D01*
G01X907939Y371551D02*
X876895Y402595D01*
G01X875835Y411633D02*
Y402155D01*
G01X876895Y402595D02*
Y412073D01*
G01X904164Y380578D02*
X879840Y404904D01*
G01X878780Y404460D02*
X903413Y379826D01*
G01X876895Y402595D02*
Y412073D01*
G01X875835Y411633D02*
Y402155D01*
G01X907939Y371551D02*
X876895Y402595D01*
G01X875835Y402155D02*
X907189Y370801D01*
G01X878780Y404460D02*
X903413Y379826D01*
G01X904164Y380578D02*
X879840Y404904D01*
G01X875835Y402155D02*
X907189Y370801D01*
G01X907939Y371551D02*
X876895Y402595D01*
G01X875835Y411633D02*
Y402155D01*
G01X876895Y402595D02*
Y412073D01*
G01X904164Y380578D02*
X879840Y404904D01*
G01X878780Y404460D02*
X903413Y379826D01*
G01X876895Y402595D02*
Y412073D01*
G01X875835Y411633D02*
Y402155D01*
G01X907939Y371551D02*
X876895Y402595D01*
G01X875835Y402155D02*
X907189Y370801D01*
G01X878780Y404460D02*
X903413Y379826D01*
G01X904164Y380578D02*
X879840Y404904D01*
G01X853120Y434348D02*
X875835Y411633D01*
G01X876895Y412073D02*
X854180Y434788D01*
G01X853120Y448291D02*
Y444015D01*
G01Y441385D02*
Y434348D01*
G01X854180Y434788D02*
Y447848D01*
G01X856317Y451488D02*
X853120Y448291D01*
G01X854180Y447848D02*
X857377Y451045D01*
G01X856317Y454156D02*
Y451488D01*
G01X857377Y451045D02*
Y454596D01*
G01X854608Y455865D02*
X856317Y454156D01*
G01X857377Y454596D02*
X855668Y456305D01*
G01X854608Y458581D02*
Y455865D01*
G01X855668Y456305D02*
Y458141D01*
G01X856520Y460493D02*
X854608Y458581D01*
G01X855668Y458141D02*
X857580Y460053D01*
G01X856520Y503362D02*
Y460493D01*
G01X857580Y460053D02*
Y502922D01*
G01X861480Y449220D02*
Y500409D01*
G01Y449220D02*
Y500409D01*
G01Y449220D02*
Y500409D01*
G01Y449220D02*
Y500409D01*
G01Y449220D02*
Y500409D01*
G01Y449220D02*
Y500409D01*
G01Y449220D02*
Y500409D01*
G01Y449220D02*
Y500409D01*
G01X860420Y478157D02*
Y449660D01*
G01X858780Y446520D02*
X861480Y449220D01*
G01X860420Y449660D02*
X857720Y446960D01*
G01X858780Y444216D02*
Y446520D01*
G01X857720Y446960D02*
Y443776D01*
G01X859816Y443180D02*
X858780Y444216D01*
G01X857720Y443776D02*
X859376Y442120D01*
G01X866290Y443180D02*
X859816D01*
G01X859376Y442120D02*
X865847D01*
G01X867780Y441690D02*
X866290Y443180D01*
G01X865847Y442120D02*
X866720Y441247D01*
G01X867780Y439258D02*
Y441690D01*
G01X866720Y441247D02*
Y439698D01*
G01X866288Y437766D02*
X867780Y439258D01*
G01X866720Y439698D02*
X865848Y438826D01*
G01X859837Y437766D02*
X866288D01*
G01X865848Y438826D02*
X859397D01*
G01X858968Y436897D02*
X859837Y437766D01*
G01X859397Y438826D02*
X857908Y437337D01*
G01X858968Y435195D02*
Y436897D01*
G01X857908Y437337D02*
Y434755D01*
G01X859837Y434326D02*
X858968Y435195D01*
G01X857908Y434755D02*
X859397Y433266D01*
G01X866288Y434326D02*
X859837D01*
G01X859397Y433266D02*
X865848D01*
G01X867780Y432834D02*
X866288Y434326D01*
G01X865848Y433266D02*
X866720Y432394D01*
G01X867780Y426602D02*
Y432834D01*
G01X866720Y432394D02*
Y426162D01*
G01X879840Y414542D02*
X867780Y426602D01*
G01X866720Y426162D02*
X878780Y414102D01*
G01X879840Y404904D02*
Y414542D01*
G01X878780Y414102D02*
Y404460D01*
G01X857580Y460053D02*
Y502922D01*
G01X856520Y503362D02*
Y460493D01*
G01X855668Y458141D02*
X857580Y460053D01*
G01X856520Y460493D02*
X854608Y458581D01*
G01X855668Y456305D02*
Y458141D01*
G01X854608Y458581D02*
Y455865D01*
G01X857377Y454596D02*
X855668Y456305D01*
G01X854608Y455865D02*
X856317Y454156D01*
G01X857377Y451045D02*
Y454596D01*
G01X856317Y454156D02*
Y451488D01*
G01X854180Y447848D02*
X857377Y451045D01*
G01X856317Y451488D02*
X853120Y448291D01*
G01X854180Y434788D02*
Y447848D01*
G01X853120Y448291D02*
Y444015D01*
G01X854180Y434788D02*
Y447848D01*
G01X853120Y441385D02*
Y434348D01*
G01X876895Y412073D02*
X854180Y434788D01*
G01X853120Y434348D02*
X875835Y411633D01*
G01X878780Y414102D02*
Y404460D01*
G01X879840Y404904D02*
Y414542D01*
G01X866720Y426162D02*
X878780Y414102D01*
G01X879840Y414542D02*
X867780Y426602D01*
G01X866720Y432394D02*
Y426162D01*
G01X867780Y426602D02*
Y432834D01*
G01X865848Y433266D02*
X866720Y432394D01*
G01X867780Y432834D02*
X866288Y434326D01*
G01X859397Y433266D02*
X865848D01*
G01X866288Y434326D02*
X859837D01*
G01X857908Y434755D02*
X859397Y433266D01*
G01X859837Y434326D02*
X858968Y435195D01*
G01X857908Y437337D02*
Y434755D01*
G01X858968Y435195D02*
Y436897D01*
G01X859397Y438826D02*
X857908Y437337D01*
G01X858968Y436897D02*
X859837Y437766D01*
G01X865848Y438826D02*
X859397D01*
G01X859837Y437766D02*
X866288D01*
G01X866720Y439698D02*
X865848Y438826D01*
G01X866288Y437766D02*
X867780Y439258D01*
G01X866720Y441247D02*
Y439698D01*
G01X867780Y439258D02*
Y441690D01*
G01X865847Y442120D02*
X866720Y441247D01*
G01X867780Y441690D02*
X866290Y443180D01*
G01X859376Y442120D02*
X865847D01*
G01X866290Y443180D02*
X859816D01*
G01X857720Y443776D02*
X859376Y442120D01*
G01X859816Y443180D02*
X858780Y444216D01*
G01X857720Y446960D02*
Y443776D01*
G01X858780Y444216D02*
Y446520D01*
G01X860420Y449660D02*
X857720Y446960D01*
G01X858780Y446520D02*
X861480Y449220D01*
G01X860420Y478157D02*
Y449660D01*
G01X861480Y449220D02*
Y500409D01*
G01X918477Y404890D02*
X907659Y415708D01*
G01X918477Y404890D02*
X907659Y415708D01*
G01X911408Y413459D02*
X908719Y416148D01*
G01X907659Y415708D02*
Y429110D01*
G01X908719Y416148D02*
Y429550D01*
G01X907659Y429110D02*
X898756Y438013D01*
G01X908719Y429550D02*
X899816Y438453D01*
G01X898756Y438013D02*
Y503652D01*
G01X899816Y438453D02*
Y512305D01*
G01X913310Y430459D02*
X904842Y438927D01*
G01X912250Y430019D02*
X903782Y438487D01*
G01X904842Y438927D02*
Y441411D01*
G01X903782Y438487D02*
Y441851D01*
G01X904842Y441411D02*
X907180Y443749D01*
G01X903782Y441851D02*
X906120Y444189D01*
G01X907180Y443749D02*
Y445692D01*
G01X906120Y444189D02*
Y445252D01*
G01X907180Y445692D02*
X904272Y448600D01*
G01X906120Y445252D02*
X903212Y448160D01*
G01X904272Y448600D02*
Y449305D01*
G01X903212Y448160D02*
Y449745D01*
G01X904272Y449305D02*
X907080Y452113D01*
G01X903212Y449745D02*
X906020Y452553D01*
G01X907080Y452113D02*
Y454692D01*
G01X906020Y452553D02*
Y454249D01*
G01X907080Y454692D02*
X905591Y456181D01*
G01X906020Y454249D02*
X905148Y455121D01*
G01X905591Y456181D02*
X903775D01*
G01X905148Y455121D02*
X903335D01*
G01X905591Y456181D02*
X903775D01*
G01D02*
X903092Y456864D01*
G01X903335Y455121D02*
X902032Y456424D01*
G01X903092Y456864D02*
Y458566D01*
G01X902032Y456424D02*
Y459006D01*
G01X903092Y458566D02*
X904147Y459621D01*
G01X902032Y459006D02*
X903707Y460681D01*
G01X904147Y459621D02*
X905767D01*
G01X903707Y460681D02*
X905327D01*
G01X905767Y459621D02*
X907180Y461034D01*
G01X905327Y460681D02*
X906120Y461474D01*
G01X907180Y461034D02*
Y466385D01*
G01X906120Y461474D02*
Y462593D01*
G01X907180Y461034D02*
Y466385D01*
G01X911408Y413459D02*
X908719Y416148D01*
G01X918477Y404890D02*
X907659Y415708D01*
G01X908719Y416148D02*
Y429550D01*
G01X907659Y415708D02*
Y429110D01*
G01X908719Y429550D02*
X899816Y438453D01*
G01X907659Y429110D02*
X898756Y438013D01*
G01X899816Y438453D02*
Y512305D01*
G01X898756Y438013D02*
Y503652D01*
G01X899816Y438453D02*
Y512305D01*
G01Y438453D02*
Y512305D01*
G01X912250Y430019D02*
X903782Y438487D01*
G01X913310Y430459D02*
X904842Y438927D01*
G01X903782Y438487D02*
Y441851D01*
G01X904842Y438927D02*
Y441411D01*
G01X903782Y441851D02*
X906120Y444189D01*
G01X904842Y441411D02*
X907180Y443749D01*
G01X906120Y444189D02*
Y445252D01*
G01X907180Y443749D02*
Y445692D01*
G01X906120Y445252D02*
X903212Y448160D01*
G01X907180Y445692D02*
X904272Y448600D01*
G01X903212Y448160D02*
Y449745D01*
G01X904272Y448600D02*
Y449305D01*
G01X903212Y449745D02*
X906020Y452553D01*
G01X904272Y449305D02*
X907080Y452113D01*
G01X906020Y452553D02*
Y454249D01*
G01X907080Y452113D02*
Y454692D01*
G01X906020Y454249D02*
X905148Y455121D01*
G01X907080Y454692D02*
X905591Y456181D01*
G01X905148Y455121D02*
X903335D01*
G01D02*
X902032Y456424D01*
G01X905591Y456181D02*
X903775D01*
G01X903335Y455121D02*
X902032Y456424D01*
G01X903775Y456181D02*
X903092Y456864D01*
G01X902032Y456424D02*
Y459006D01*
G01X903092Y456864D02*
Y458566D01*
G01X902032Y459006D02*
X903707Y460681D01*
G01X903092Y458566D02*
X904147Y459621D01*
G01X903707Y460681D02*
X905327D01*
G01X904147Y459621D02*
X905767D01*
G01X905327Y460681D02*
X906120Y461474D01*
G01X905767Y459621D02*
X907180Y461034D01*
G01X906120Y461474D02*
Y462593D01*
G01X907180Y461034D02*
Y466385D01*
G01X853120Y434348D02*
X875835Y411633D01*
G01X876895Y412073D02*
X854180Y434788D01*
G01X853120Y448291D02*
Y444015D01*
G01Y441385D02*
Y434348D01*
G01X854180Y434788D02*
Y447848D01*
G01X856317Y451488D02*
X853120Y448291D01*
G01X854180Y447848D02*
X857377Y451045D01*
G01X856317Y454156D02*
Y451488D01*
G01X857377Y451045D02*
Y454596D01*
G01X854608Y455865D02*
X856317Y454156D01*
G01X857377Y454596D02*
X855668Y456305D01*
G01X854608Y458581D02*
Y455865D01*
G01X855668Y456305D02*
Y458141D01*
G01X856520Y460493D02*
X854608Y458581D01*
G01X855668Y458141D02*
X857580Y460053D01*
G01X856520Y503362D02*
Y460493D01*
G01X857580Y460053D02*
Y502922D01*
G01X918477Y404890D02*
X907659Y415708D01*
G01X918477Y404890D02*
X907659Y415708D01*
G01X911408Y413459D02*
X908719Y416148D01*
G01X907659Y415708D02*
Y429110D01*
G01X908719Y416148D02*
Y429550D01*
G01X907659Y429110D02*
X898756Y438013D01*
G01X908719Y429550D02*
X899816Y438453D01*
G01X898756Y438013D02*
Y503652D01*
G01X899816Y438453D02*
Y512305D01*
G01X861480Y449220D02*
Y500409D01*
G01Y449220D02*
Y500409D01*
G01Y449220D02*
Y500409D01*
G01Y449220D02*
Y500409D01*
G01Y449220D02*
Y500409D01*
G01Y449220D02*
Y500409D01*
G01Y449220D02*
Y500409D01*
G01Y449220D02*
Y500409D01*
G01X860420Y478157D02*
Y449660D01*
G01X858780Y446520D02*
X861480Y449220D01*
G01X860420Y449660D02*
X857720Y446960D01*
G01X858780Y444216D02*
Y446520D01*
G01X857720Y446960D02*
Y443776D01*
G01X859816Y443180D02*
X858780Y444216D01*
G01X857720Y443776D02*
X859376Y442120D01*
G01X866290Y443180D02*
X859816D01*
G01X859376Y442120D02*
X865847D01*
G01X867780Y441690D02*
X866290Y443180D01*
G01X865847Y442120D02*
X866720Y441247D01*
G01X867780Y439258D02*
Y441690D01*
G01X866720Y441247D02*
Y439698D01*
G01X866288Y437766D02*
X867780Y439258D01*
G01X866720Y439698D02*
X865848Y438826D01*
G01X859837Y437766D02*
X866288D01*
G01X865848Y438826D02*
X859397D01*
G01X858968Y436897D02*
X859837Y437766D01*
G01X859397Y438826D02*
X857908Y437337D01*
G01X858968Y435195D02*
Y436897D01*
G01X857908Y437337D02*
Y434755D01*
G01X859837Y434326D02*
X858968Y435195D01*
G01X857908Y434755D02*
X859397Y433266D01*
G01X866288Y434326D02*
X859837D01*
G01X859397Y433266D02*
X865848D01*
G01X867780Y432834D02*
X866288Y434326D01*
G01X865848Y433266D02*
X866720Y432394D01*
G01X867780Y426602D02*
Y432834D01*
G01X866720Y432394D02*
Y426162D01*
G01X879840Y414542D02*
X867780Y426602D01*
G01X866720Y426162D02*
X878780Y414102D01*
G01X879840Y404904D02*
Y414542D01*
G01X878780Y414102D02*
Y404460D01*
G01X913310Y430459D02*
X904842Y438927D01*
G01X912250Y430019D02*
X903782Y438487D01*
G01X904842Y438927D02*
Y441411D01*
G01X903782Y438487D02*
Y441851D01*
G01X904842Y441411D02*
X907180Y443749D01*
G01X903782Y441851D02*
X906120Y444189D01*
G01X907180Y443749D02*
Y445692D01*
G01X906120Y444189D02*
Y445252D01*
G01X907180Y445692D02*
X904272Y448600D01*
G01X906120Y445252D02*
X903212Y448160D01*
G01X904272Y448600D02*
Y449305D01*
G01X903212Y448160D02*
Y449745D01*
G01X904272Y449305D02*
X907080Y452113D01*
G01X903212Y449745D02*
X906020Y452553D01*
G01X907080Y452113D02*
Y454692D01*
G01X906020Y452553D02*
Y454249D01*
G01X907080Y454692D02*
X905591Y456181D01*
G01X906020Y454249D02*
X905148Y455121D01*
G01X905591Y456181D02*
X903775D01*
G01X905148Y455121D02*
X903335D01*
G01X905591Y456181D02*
X903775D01*
G01D02*
X903092Y456864D01*
G01X903335Y455121D02*
X902032Y456424D01*
G01X903092Y456864D02*
Y458566D01*
G01X902032Y456424D02*
Y459006D01*
G01X903092Y458566D02*
X904147Y459621D01*
G01X902032Y459006D02*
X903707Y460681D01*
G01X904147Y459621D02*
X905767D01*
G01X903707Y460681D02*
X905327D01*
G01X905767Y459621D02*
X907180Y461034D01*
G01X905327Y460681D02*
X906120Y461474D01*
G01X907180Y461034D02*
Y466385D01*
G01X906120Y461474D02*
Y462593D01*
G01X907180Y461034D02*
Y466385D01*
G01X857580Y460053D02*
Y502922D01*
G01X856520Y503362D02*
Y460493D01*
G01X855668Y458141D02*
X857580Y460053D01*
G01X856520Y460493D02*
X854608Y458581D01*
G01X855668Y456305D02*
Y458141D01*
G01X854608Y458581D02*
Y455865D01*
G01X857377Y454596D02*
X855668Y456305D01*
G01X854608Y455865D02*
X856317Y454156D01*
G01X857377Y451045D02*
Y454596D01*
G01X856317Y454156D02*
Y451488D01*
G01X854180Y447848D02*
X857377Y451045D01*
G01X856317Y451488D02*
X853120Y448291D01*
G01X854180Y434788D02*
Y447848D01*
G01X853120Y448291D02*
Y444015D01*
G01X854180Y434788D02*
Y447848D01*
G01X853120Y441385D02*
Y434348D01*
G01X876895Y412073D02*
X854180Y434788D01*
G01X853120Y434348D02*
X875835Y411633D01*
G01X911408Y413459D02*
X908719Y416148D01*
G01X918477Y404890D02*
X907659Y415708D01*
G01X908719Y416148D02*
Y429550D01*
G01X907659Y415708D02*
Y429110D01*
G01X908719Y429550D02*
X899816Y438453D01*
G01X907659Y429110D02*
X898756Y438013D01*
G01X899816Y438453D02*
Y512305D01*
G01X898756Y438013D02*
Y503652D01*
G01X899816Y438453D02*
Y512305D01*
G01Y438453D02*
Y512305D01*
G01X878780Y414102D02*
Y404460D01*
G01X879840Y404904D02*
Y414542D01*
G01X866720Y426162D02*
X878780Y414102D01*
G01X879840Y414542D02*
X867780Y426602D01*
G01X866720Y432394D02*
Y426162D01*
G01X867780Y426602D02*
Y432834D01*
G01X865848Y433266D02*
X866720Y432394D01*
G01X867780Y432834D02*
X866288Y434326D01*
G01X859397Y433266D02*
X865848D01*
G01X866288Y434326D02*
X859837D01*
G01X857908Y434755D02*
X859397Y433266D01*
G01X859837Y434326D02*
X858968Y435195D01*
G01X857908Y437337D02*
Y434755D01*
G01X858968Y435195D02*
Y436897D01*
G01X859397Y438826D02*
X857908Y437337D01*
G01X858968Y436897D02*
X859837Y437766D01*
G01X865848Y438826D02*
X859397D01*
G01X859837Y437766D02*
X866288D01*
G01X866720Y439698D02*
X865848Y438826D01*
G01X866288Y437766D02*
X867780Y439258D01*
G01X866720Y441247D02*
Y439698D01*
G01X867780Y439258D02*
Y441690D01*
G01X865847Y442120D02*
X866720Y441247D01*
G01X867780Y441690D02*
X866290Y443180D01*
G01X859376Y442120D02*
X865847D01*
G01X866290Y443180D02*
X859816D01*
G01X857720Y443776D02*
X859376Y442120D01*
G01X859816Y443180D02*
X858780Y444216D01*
G01X857720Y446960D02*
Y443776D01*
G01X858780Y444216D02*
Y446520D01*
G01X860420Y449660D02*
X857720Y446960D01*
G01X858780Y446520D02*
X861480Y449220D01*
G01X860420Y478157D02*
Y449660D01*
G01X861480Y449220D02*
Y500409D01*
G01X912250Y430019D02*
X903782Y438487D01*
G01X913310Y430459D02*
X904842Y438927D01*
G01X903782Y438487D02*
Y441851D01*
G01X904842Y438927D02*
Y441411D01*
G01X903782Y441851D02*
X906120Y444189D01*
G01X904842Y441411D02*
X907180Y443749D01*
G01X906120Y444189D02*
Y445252D01*
G01X907180Y443749D02*
Y445692D01*
G01X906120Y445252D02*
X903212Y448160D01*
G01X907180Y445692D02*
X904272Y448600D01*
G01X903212Y448160D02*
Y449745D01*
G01X904272Y448600D02*
Y449305D01*
G01X903212Y449745D02*
X906020Y452553D01*
G01X904272Y449305D02*
X907080Y452113D01*
G01X906020Y452553D02*
Y454249D01*
G01X907080Y452113D02*
Y454692D01*
G01X906020Y454249D02*
X905148Y455121D01*
G01X907080Y454692D02*
X905591Y456181D01*
G01X905148Y455121D02*
X903335D01*
G01D02*
X902032Y456424D01*
G01X905591Y456181D02*
X903775D01*
G01X903335Y455121D02*
X902032Y456424D01*
G01X903775Y456181D02*
X903092Y456864D01*
G01X902032Y456424D02*
Y459006D01*
G01X903092Y456864D02*
Y458566D01*
G01X902032Y459006D02*
X903707Y460681D01*
G01X903092Y458566D02*
X904147Y459621D01*
G01X903707Y460681D02*
X905327D01*
G01X904147Y459621D02*
X905767D01*
G01X905327Y460681D02*
X906120Y461474D01*
G01X905767Y459621D02*
X907180Y461034D01*
G01X906120Y461474D02*
Y462593D01*
G01X907180Y461034D02*
Y466385D01*
G01X858022Y532411D02*
Y514400D01*
G01X859082Y520290D02*
Y521660D01*
G01X858022Y532411D02*
Y514400D01*
G01X859082Y525340D02*
Y526760D01*
G01X862030Y508872D02*
X856520Y503362D01*
G01X857580Y502922D02*
X858506Y503848D01*
G01X862030Y508872D02*
X856520Y503362D01*
G01X860091Y505433D02*
X860798Y506140D01*
G01X862030Y508872D02*
X856520Y503362D01*
G01X862383Y507725D02*
X863090Y508432D01*
G01X862030Y511780D02*
Y508872D01*
G01X863090Y508432D02*
Y512220D01*
G01X861110Y512700D02*
X862030Y511780D01*
G01X863090Y512220D02*
X860010Y515300D01*
G01X863635Y526229D02*
X864406Y527000D01*
G01X863635Y520571D02*
Y521848D01*
G01Y525338D02*
Y526229D01*
G01X862575Y526670D02*
Y520130D01*
G01X864306Y519900D02*
X863635Y520571D01*
G01X862575Y520130D02*
X863405Y519300D01*
G01X868190Y512434D02*
X865110Y515514D01*
G01X866210Y512914D02*
X867130Y511994D01*
G01X868190Y507119D02*
Y512434D01*
G01X867130Y511994D02*
Y507562D01*
G01X861480Y500409D02*
X868190Y507119D01*
G01X867130Y507562D02*
X866083Y506515D01*
G01X861480Y500409D02*
X868190Y507119D01*
G01X866083Y506515D02*
X865205D01*
G01X861480Y500409D02*
X868190Y507119D01*
G01X864498Y504930D02*
X863762Y504194D01*
G01X861480Y500409D02*
X868190Y507119D01*
G01X863762Y504194D02*
X862884D01*
G01X861480Y500409D02*
X868190Y507119D01*
G01X862177Y502609D02*
X860420Y500852D01*
G01D02*
Y499652D01*
G01Y497412D02*
Y496412D01*
G01Y494172D02*
Y493172D01*
G01Y490932D02*
Y489932D01*
G01Y487692D02*
Y486692D01*
G01Y484452D02*
Y483452D01*
G01Y481212D02*
Y480053D01*
G01X859082Y520290D02*
Y521660D01*
G01Y525340D02*
Y526760D01*
G01X858022Y532411D02*
Y514400D01*
G01X863090Y512220D02*
X860010Y515300D01*
G01X861110Y512700D02*
X862030Y511780D01*
G01X863090Y508432D02*
Y512220D01*
G01X862030Y511780D02*
Y508872D01*
G01X857580Y502922D02*
X858506Y503848D01*
G01X860091Y505433D02*
X860798Y506140D01*
G01X862383Y507725D02*
X863090Y508432D01*
G01X862030Y508872D02*
X856520Y503362D01*
G01X862575Y520130D02*
X863405Y519300D01*
G01X864306Y519900D02*
X863635Y520571D01*
G01X862575Y526670D02*
Y520130D01*
G01X863635Y520571D02*
Y521848D01*
G01X862575Y526670D02*
Y520130D01*
G01X863635Y525338D02*
Y526229D01*
G01D02*
X864406Y527000D01*
G01X860420Y500852D02*
Y499652D01*
G01Y497412D02*
Y496412D01*
G01Y494172D02*
Y493172D01*
G01Y490932D02*
Y489932D01*
G01Y487692D02*
Y486692D01*
G01Y484452D02*
Y483452D01*
G01Y481212D02*
Y480053D01*
G01X867130Y507562D02*
X866083Y506515D01*
G01D02*
X865205D01*
G01X864498Y504930D02*
X863762Y504194D01*
G01D02*
X862884D01*
G01X862177Y502609D02*
X860420Y500852D01*
G01X861480Y500409D02*
X868190Y507119D01*
G01X867130Y511994D02*
Y507562D01*
G01X868190Y507119D02*
Y512434D01*
G01X866210Y512914D02*
X867130Y511994D01*
G01X868190Y512434D02*
X865110Y515514D01*
G01X894833Y514400D02*
Y532411D01*
G01X895893Y520290D02*
Y521660D01*
G01X894833Y514400D02*
Y532411D01*
G01X895893Y525340D02*
Y526760D01*
G01X898756Y505706D02*
Y506799D01*
G01Y509039D02*
Y511744D01*
G01X901117Y519900D02*
X900446Y520571D01*
G01X900216Y519300D02*
X899386Y520130D01*
G01X900446Y520571D02*
Y521848D01*
G01Y525338D02*
Y526229D01*
G01X899386Y520130D02*
Y526670D01*
G01X900446Y526229D02*
X901217Y527000D01*
G01X906120Y464833D02*
Y465945D01*
G01X907180Y466385D02*
X905301Y468264D01*
G01X906120Y465945D02*
X904241Y467824D01*
G01X905301Y468264D02*
Y512134D01*
G01X904241Y467824D02*
Y469246D01*
G01X905301Y468264D02*
Y512134D01*
G01X904241Y471486D02*
Y472486D01*
G01X905301Y468264D02*
Y512134D01*
G01X904241Y474726D02*
Y475726D01*
G01X905301Y468264D02*
Y512134D01*
G01X904241Y477966D02*
Y478966D01*
G01X905301Y468264D02*
Y512134D01*
G01X904241Y481206D02*
Y482206D01*
G01X905301Y468264D02*
Y512134D01*
G01X904241Y484446D02*
Y485446D01*
G01X905301Y468264D02*
Y512134D01*
G01X904241Y487686D02*
Y488686D01*
G01X905301Y468264D02*
Y512134D01*
G01X904241Y490926D02*
Y491939D01*
G01X905301Y468264D02*
Y512134D01*
G01X904241Y494153D02*
Y495312D01*
G01X905301Y468264D02*
Y512134D01*
G01X904241Y497524D02*
Y498406D01*
G01X905301Y468264D02*
Y512134D01*
G01X904241Y500646D02*
Y501646D01*
G01X905301Y468264D02*
Y512134D01*
G01X904241Y503886D02*
Y504886D01*
G01X905301Y468264D02*
Y512134D01*
G01X904241Y507126D02*
Y508126D01*
G01X905301Y468264D02*
Y512134D01*
G01X904241Y510366D02*
Y511694D01*
G01X905301Y512134D02*
X901921Y515514D01*
G01X904241Y511694D02*
X903021Y512914D01*
G01X905301Y512134D02*
X901921Y515514D01*
G01X903021Y512914D02*
X901921D01*
G01X895893Y520290D02*
Y521660D01*
G01Y525340D02*
Y526760D01*
G01X894833Y514400D02*
Y532411D01*
G01X898756Y505706D02*
Y506799D01*
G01Y509039D02*
Y511744D01*
G01X900216Y519300D02*
X899386Y520130D01*
G01X901117Y519900D02*
X900446Y520571D01*
G01X899386Y520130D02*
Y526670D01*
G01X900446Y520571D02*
Y521848D01*
G01X899386Y520130D02*
Y526670D01*
G01X900446Y525338D02*
Y526229D01*
G01D02*
X901217Y527000D01*
G01X906120Y464833D02*
Y465945D01*
G01D02*
X904241Y467824D01*
G01X907180Y466385D02*
X905301Y468264D01*
G01X904241Y467824D02*
Y469246D01*
G01Y471486D02*
Y472486D01*
G01Y474726D02*
Y475726D01*
G01Y477966D02*
Y478966D01*
G01Y481206D02*
Y482206D01*
G01Y484446D02*
Y485446D01*
G01Y487686D02*
Y488686D01*
G01Y490926D02*
Y491939D01*
G01Y494153D02*
Y495312D01*
G01Y497524D02*
Y498406D01*
G01Y500646D02*
Y501646D01*
G01Y503886D02*
Y504886D01*
G01Y507126D02*
Y508126D01*
G01Y510366D02*
Y511694D01*
G01X905301Y468264D02*
Y512134D01*
G01X904241Y511694D02*
X903021Y512914D01*
G01D02*
X901921D01*
G01X905301Y512134D02*
X901921Y515514D01*
G01X858022Y532411D02*
Y514400D01*
G01X859082Y520290D02*
Y521660D01*
G01X858022Y532411D02*
Y514400D01*
G01X859082Y525340D02*
Y526760D01*
G01X862030Y508872D02*
X856520Y503362D01*
G01X857580Y502922D02*
X858506Y503848D01*
G01X862030Y508872D02*
X856520Y503362D01*
G01X860091Y505433D02*
X860798Y506140D01*
G01X862030Y508872D02*
X856520Y503362D01*
G01X862383Y507725D02*
X863090Y508432D01*
G01X862030Y511780D02*
Y508872D01*
G01X863090Y508432D02*
Y512220D01*
G01X861110Y512700D02*
X862030Y511780D01*
G01X863090Y512220D02*
X860010Y515300D01*
G01X894833Y514400D02*
Y532411D01*
G01X895893Y520290D02*
Y521660D01*
G01X894833Y514400D02*
Y532411D01*
G01X895893Y525340D02*
Y526760D01*
G01X898756Y505706D02*
Y506799D01*
G01Y509039D02*
Y511744D01*
G01X863635Y526229D02*
X864406Y527000D01*
G01X863635Y520571D02*
Y521848D01*
G01Y525338D02*
Y526229D01*
G01X862575Y526670D02*
Y520130D01*
G01X864306Y519900D02*
X863635Y520571D01*
G01X862575Y520130D02*
X863405Y519300D01*
G01X868190Y512434D02*
X865110Y515514D01*
G01X866210Y512914D02*
X867130Y511994D01*
G01X868190Y507119D02*
Y512434D01*
G01X867130Y511994D02*
Y507562D01*
G01X861480Y500409D02*
X868190Y507119D01*
G01X867130Y507562D02*
X866083Y506515D01*
G01X861480Y500409D02*
X868190Y507119D01*
G01X866083Y506515D02*
X865205D01*
G01X861480Y500409D02*
X868190Y507119D01*
G01X864498Y504930D02*
X863762Y504194D01*
G01X861480Y500409D02*
X868190Y507119D01*
G01X863762Y504194D02*
X862884D01*
G01X861480Y500409D02*
X868190Y507119D01*
G01X862177Y502609D02*
X860420Y500852D01*
G01D02*
Y499652D01*
G01Y497412D02*
Y496412D01*
G01Y494172D02*
Y493172D01*
G01Y490932D02*
Y489932D01*
G01Y487692D02*
Y486692D01*
G01Y484452D02*
Y483452D01*
G01Y481212D02*
Y480053D01*
G01X901117Y519900D02*
X900446Y520571D01*
G01X900216Y519300D02*
X899386Y520130D01*
G01X900446Y520571D02*
Y521848D01*
G01Y525338D02*
Y526229D01*
G01X899386Y520130D02*
Y526670D01*
G01X900446Y526229D02*
X901217Y527000D01*
G01X906120Y464833D02*
Y465945D01*
G01X907180Y466385D02*
X905301Y468264D01*
G01X906120Y465945D02*
X904241Y467824D01*
G01X905301Y468264D02*
Y512134D01*
G01X904241Y467824D02*
Y469246D01*
G01X905301Y468264D02*
Y512134D01*
G01X904241Y471486D02*
Y472486D01*
G01X905301Y468264D02*
Y512134D01*
G01X904241Y474726D02*
Y475726D01*
G01X905301Y468264D02*
Y512134D01*
G01X904241Y477966D02*
Y478966D01*
G01X905301Y468264D02*
Y512134D01*
G01X904241Y481206D02*
Y482206D01*
G01X905301Y468264D02*
Y512134D01*
G01X904241Y484446D02*
Y485446D01*
G01X905301Y468264D02*
Y512134D01*
G01X904241Y487686D02*
Y488686D01*
G01X905301Y468264D02*
Y512134D01*
G01X904241Y490926D02*
Y491939D01*
G01X905301Y468264D02*
Y512134D01*
G01X904241Y494153D02*
Y495312D01*
G01X905301Y468264D02*
Y512134D01*
G01X904241Y497524D02*
Y498406D01*
G01X905301Y468264D02*
Y512134D01*
G01X904241Y500646D02*
Y501646D01*
G01X905301Y468264D02*
Y512134D01*
G01X904241Y503886D02*
Y504886D01*
G01X905301Y468264D02*
Y512134D01*
G01X904241Y507126D02*
Y508126D01*
G01X905301Y468264D02*
Y512134D01*
G01X904241Y510366D02*
Y511694D01*
G01X905301Y512134D02*
X901921Y515514D01*
G01X904241Y511694D02*
X903021Y512914D01*
G01X905301Y512134D02*
X901921Y515514D01*
G01X903021Y512914D02*
X901921D01*
G01X859082Y520290D02*
Y521660D01*
G01Y525340D02*
Y526760D01*
G01X858022Y532411D02*
Y514400D01*
G01X863090Y512220D02*
X860010Y515300D01*
G01X861110Y512700D02*
X862030Y511780D01*
G01X863090Y508432D02*
Y512220D01*
G01X862030Y511780D02*
Y508872D01*
G01X857580Y502922D02*
X858506Y503848D01*
G01X860091Y505433D02*
X860798Y506140D01*
G01X862383Y507725D02*
X863090Y508432D01*
G01X862030Y508872D02*
X856520Y503362D01*
G01X895893Y520290D02*
Y521660D01*
G01Y525340D02*
Y526760D01*
G01X894833Y514400D02*
Y532411D01*
G01X898756Y505706D02*
Y506799D01*
G01Y509039D02*
Y511744D01*
G01X862575Y520130D02*
X863405Y519300D01*
G01X864306Y519900D02*
X863635Y520571D01*
G01X862575Y526670D02*
Y520130D01*
G01X863635Y520571D02*
Y521848D01*
G01X862575Y526670D02*
Y520130D01*
G01X863635Y525338D02*
Y526229D01*
G01D02*
X864406Y527000D01*
G01X860420Y500852D02*
Y499652D01*
G01Y497412D02*
Y496412D01*
G01Y494172D02*
Y493172D01*
G01Y490932D02*
Y489932D01*
G01Y487692D02*
Y486692D01*
G01Y484452D02*
Y483452D01*
G01Y481212D02*
Y480053D01*
G01X867130Y507562D02*
X866083Y506515D01*
G01D02*
X865205D01*
G01X864498Y504930D02*
X863762Y504194D01*
G01D02*
X862884D01*
G01X862177Y502609D02*
X860420Y500852D01*
G01X861480Y500409D02*
X868190Y507119D01*
G01X867130Y511994D02*
Y507562D01*
G01X868190Y507119D02*
Y512434D01*
G01X866210Y512914D02*
X867130Y511994D01*
G01X868190Y512434D02*
X865110Y515514D01*
G01X900216Y519300D02*
X899386Y520130D01*
G01X901117Y519900D02*
X900446Y520571D01*
G01X899386Y520130D02*
Y526670D01*
G01X900446Y520571D02*
Y521848D01*
G01X899386Y520130D02*
Y526670D01*
G01X900446Y525338D02*
Y526229D01*
G01D02*
X901217Y527000D01*
G01X906120Y464833D02*
Y465945D01*
G01D02*
X904241Y467824D01*
G01X907180Y466385D02*
X905301Y468264D01*
G01X904241Y467824D02*
Y469246D01*
G01Y471486D02*
Y472486D01*
G01Y474726D02*
Y475726D01*
G01Y477966D02*
Y478966D01*
G01Y481206D02*
Y482206D01*
G01Y484446D02*
Y485446D01*
G01Y487686D02*
Y488686D01*
G01Y490926D02*
Y491939D01*
G01Y494153D02*
Y495312D01*
G01Y497524D02*
Y498406D01*
G01Y500646D02*
Y501646D01*
G01Y503886D02*
Y504886D01*
G01Y507126D02*
Y508126D01*
G01Y510366D02*
Y511694D01*
G01X905301Y468264D02*
Y512134D01*
G01X904241Y511694D02*
X903021Y512914D01*
G01D02*
X901921D01*
G01X905301Y512134D02*
X901921Y515514D01*
G01X863405Y527500D02*
X862575Y526670D01*
G01X863405Y527500D02*
X862575Y526670D01*
G01X899386D02*
X900216Y527500D01*
G01X899386Y526670D02*
X900216Y527500D01*
G01X863405D02*
X862575Y526670D01*
G01X899386D02*
X900216Y527500D01*
G01X863405D02*
X862575Y526670D01*
G01X899386D02*
X900216Y527500D01*
G01X931778Y98031D02*
Y89154D01*
G01X934967Y70380D02*
X934451D01*
G01X934428Y69320D02*
X935410D01*
G01X935678Y71091D02*
X934967Y70380D01*
G01X935410Y69320D02*
X936738Y70648D01*
G01X935678Y86353D02*
Y83820D01*
G01Y79680D02*
Y78720D01*
G01Y74380D02*
Y71091D01*
G01X936738Y70648D02*
Y86794D01*
G01X934731Y87300D02*
X935678Y86353D01*
G01X936738Y86794D02*
X933632Y89900D01*
G01X931778Y98031D02*
Y89154D01*
G01X934967Y70380D02*
X934451D01*
G01X934428Y69320D02*
X935410D01*
G01X935678Y71091D02*
X934967Y70380D01*
G01X935410Y69320D02*
X936738Y70648D01*
G01X935678Y86353D02*
Y83820D01*
G01Y79680D02*
Y78720D01*
G01Y74380D02*
Y71091D01*
G01X936738Y70648D02*
Y86794D01*
G01X934731Y87300D02*
X935678Y86353D01*
G01X936738Y86794D02*
X933632Y89900D01*
G01X941924Y86922D02*
X938732Y90114D01*
G01Y87515D02*
X939830D01*
G01X941924Y86922D02*
X938732Y90114D01*
G01X939830Y87515D02*
X940864Y86481D01*
G01X941924Y71532D02*
Y86922D01*
G01X940864Y86481D02*
Y83706D01*
G01X941924Y71532D02*
Y86922D01*
G01X940864Y79880D02*
Y78507D01*
G01X941924Y71532D02*
Y86922D01*
G01X940864Y74593D02*
Y71972D01*
G01X938732Y68340D02*
X941924Y71532D01*
G01X940864Y71972D02*
X939841Y70949D01*
G01X936978Y97308D02*
Y89268D01*
G01X941924Y86922D02*
X938732Y90114D01*
G01Y87515D02*
X939830D01*
G01X941924Y86922D02*
X938732Y90114D01*
G01X939830Y87515D02*
X940864Y86481D01*
G01X941924Y71532D02*
Y86922D01*
G01X940864Y86481D02*
Y83706D01*
G01X941924Y71532D02*
Y86922D01*
G01X940864Y79880D02*
Y78507D01*
G01X941924Y71532D02*
Y86922D01*
G01X940864Y74593D02*
Y71972D01*
G01X938732Y68340D02*
X941924Y71532D01*
G01X940864Y71972D02*
X939841Y70949D01*
G01X936978Y97308D02*
Y89268D01*
G01X936738Y86794D02*
X933632Y89900D01*
G01X934731Y87300D02*
X935678Y86353D01*
G01X936738Y70648D02*
Y86794D01*
G01X935678Y86353D02*
Y83820D01*
G01X936738Y70648D02*
Y86794D01*
G01X935678Y79680D02*
Y78720D01*
G01X936738Y70648D02*
Y86794D01*
G01X935678Y74380D02*
Y71091D01*
G01X935410Y69320D02*
X936738Y70648D01*
G01X935678Y71091D02*
X934967Y70380D01*
G01X934428Y69320D02*
X935410D01*
G01X934967Y70380D02*
X934451D01*
G01X931778Y98031D02*
Y89154D01*
G01X936738Y86794D02*
X933632Y89900D01*
G01X934731Y87300D02*
X935678Y86353D01*
G01X936738Y70648D02*
Y86794D01*
G01X935678Y86353D02*
Y83820D01*
G01X936738Y70648D02*
Y86794D01*
G01X935678Y79680D02*
Y78720D01*
G01X936738Y70648D02*
Y86794D01*
G01X935678Y74380D02*
Y71091D01*
G01X935410Y69320D02*
X936738Y70648D01*
G01X935678Y71091D02*
X934967Y70380D01*
G01X934428Y69320D02*
X935410D01*
G01X934967Y70380D02*
X934451D01*
G01X931778Y98031D02*
Y89154D01*
G01X940864Y71972D02*
X939841Y70949D01*
G01X938732Y68340D02*
X941924Y71532D01*
G01X940864Y86481D02*
Y83706D01*
G01Y79880D02*
Y78507D01*
G01Y74593D02*
Y71972D01*
G01X941924Y71532D02*
Y86922D01*
G01X938732Y87515D02*
X939830D01*
G01D02*
X940864Y86481D01*
G01X941924Y86922D02*
X938732Y90114D01*
G01X936978Y97308D02*
Y89268D01*
G01X940864Y71972D02*
X939841Y70949D01*
G01X938732Y68340D02*
X941924Y71532D01*
G01X940864Y86481D02*
Y83706D01*
G01Y79880D02*
Y78507D01*
G01Y74593D02*
Y71972D01*
G01X941924Y71532D02*
Y86922D01*
G01X938732Y87515D02*
X939830D01*
G01D02*
X940864Y86481D01*
G01X941924Y86922D02*
X938732Y90114D01*
G01X936978Y97308D02*
Y89268D01*
G01X932838Y95000D02*
Y97588D01*
G01X935594Y101847D02*
X931778Y98031D01*
G01X932838Y97588D02*
X936654Y101404D01*
G01X935594Y113926D02*
Y101847D01*
G01X936654Y101404D02*
Y102236D01*
G01X935594Y113926D02*
Y101847D01*
G01X936654Y104476D02*
Y113483D01*
G01X936512Y114844D02*
X935594Y113926D01*
G01X936654Y113483D02*
X937572Y114401D01*
G01X936512Y133307D02*
Y114844D01*
G01X937572Y114401D02*
Y115401D01*
G01X936512Y133307D02*
Y114844D01*
G01X937572Y117401D02*
Y118401D01*
G01X936512Y133307D02*
Y114844D01*
G01X937572Y120401D02*
Y121401D01*
G01X936512Y133307D02*
Y114844D01*
G01X937572Y123401D02*
Y128404D01*
G01X936512Y133307D02*
Y114844D01*
G01X937572Y131034D02*
Y132864D01*
G01X938041Y134836D02*
X936512Y133307D01*
G01X937572Y132864D02*
X938484Y133776D01*
G01X939901Y134836D02*
X938041D01*
G01X938484Y133776D02*
X940344D01*
G01X940712Y135647D02*
X939901Y134836D01*
G01X940344Y133776D02*
X941772Y135204D01*
G01X940712Y137986D02*
Y135647D01*
G01X941772Y135204D02*
Y138429D01*
G01X939840Y138858D02*
X940712Y137986D01*
G01X941772Y138429D02*
X940283Y139918D01*
G01X938004Y138858D02*
X939840D01*
G01X940283Y139918D02*
X938444D01*
G01X936240Y140622D02*
X938004Y138858D01*
G01X938444Y139918D02*
X937300Y141062D01*
G01X936240Y143454D02*
Y140622D01*
G01X937300Y141062D02*
Y143014D01*
G01X938004Y145218D02*
X936240Y143454D01*
G01X937300Y143014D02*
X938444Y144158D01*
G01X939843Y145218D02*
X938004D01*
G01X938444Y144158D02*
X940283D01*
G01X940712Y146087D02*
X939843Y145218D01*
G01X940283Y144158D02*
X941772Y145647D01*
G01X940712Y148586D02*
Y146087D01*
G01X941772Y145647D02*
Y149029D01*
G01X939840Y149458D02*
X940712Y148586D01*
G01X941772Y149029D02*
X940283Y150518D01*
G01X939174Y149458D02*
X939840D01*
G01X940283Y150518D02*
X939614D01*
G01X937900Y150732D02*
X939174Y149458D01*
G01X939614Y150518D02*
X938960Y151172D01*
G01X937900Y159934D02*
Y150732D01*
G01X938960Y151172D02*
Y153834D01*
G01X937900Y159934D02*
Y150732D01*
G01X932838Y95000D02*
Y97588D01*
G01X935594Y101847D02*
X931778Y98031D01*
G01X932838Y97588D02*
X936654Y101404D01*
G01X935594Y113926D02*
Y101847D01*
G01X936654Y101404D02*
Y102236D01*
G01X935594Y113926D02*
Y101847D01*
G01X936654Y104476D02*
Y113483D01*
G01X936512Y114844D02*
X935594Y113926D01*
G01X936654Y113483D02*
X937572Y114401D01*
G01X936512Y133307D02*
Y114844D01*
G01X937572Y114401D02*
Y115401D01*
G01X936512Y133307D02*
Y114844D01*
G01X937572Y117401D02*
Y118401D01*
G01X936512Y133307D02*
Y114844D01*
G01X937572Y120401D02*
Y121401D01*
G01X936512Y133307D02*
Y114844D01*
G01X937572Y123401D02*
Y128404D01*
G01X936512Y133307D02*
Y114844D01*
G01X937572Y131034D02*
Y132864D01*
G01X938041Y134836D02*
X936512Y133307D01*
G01X937572Y132864D02*
X938484Y133776D01*
G01X939901Y134836D02*
X938041D01*
G01X938484Y133776D02*
X940344D01*
G01X940712Y135647D02*
X939901Y134836D01*
G01X940344Y133776D02*
X941772Y135204D01*
G01X940712Y137986D02*
Y135647D01*
G01X941772Y135204D02*
Y138429D01*
G01X939840Y138858D02*
X940712Y137986D01*
G01X941772Y138429D02*
X940283Y139918D01*
G01X938004Y138858D02*
X939840D01*
G01X940283Y139918D02*
X938444D01*
G01X936240Y140622D02*
X938004Y138858D01*
G01X938444Y139918D02*
X937300Y141062D01*
G01X936240Y143454D02*
Y140622D01*
G01X937300Y141062D02*
Y143014D01*
G01X938004Y145218D02*
X936240Y143454D01*
G01X937300Y143014D02*
X938444Y144158D01*
G01X939843Y145218D02*
X938004D01*
G01X938444Y144158D02*
X940283D01*
G01X940712Y146087D02*
X939843Y145218D01*
G01X940283Y144158D02*
X941772Y145647D01*
G01X940712Y148586D02*
Y146087D01*
G01X941772Y145647D02*
Y149029D01*
G01X939840Y149458D02*
X940712Y148586D01*
G01X941772Y149029D02*
X940283Y150518D01*
G01X939174Y149458D02*
X939840D01*
G01X940283Y150518D02*
X939614D01*
G01X937900Y150732D02*
X939174Y149458D01*
G01X939614Y150518D02*
X938960Y151172D01*
G01X937900Y159934D02*
Y150732D01*
G01X938960Y151172D02*
Y153834D01*
G01X937900Y159934D02*
Y150732D01*
G01X945572Y133465D02*
Y161372D01*
G01X944512Y161812D02*
Y133908D01*
G01X942172Y130065D02*
X945572Y133465D01*
G01X944512Y133908D02*
X941112Y130508D01*
G01X942172Y113304D02*
Y130065D01*
G01X941112Y130508D02*
Y113747D01*
G01X941812Y112944D02*
X942172Y113304D01*
G01X941112Y113747D02*
X940752Y113387D01*
G01X941812Y100642D02*
Y103480D01*
G01Y105720D02*
Y112944D01*
G01X940752Y113387D02*
Y101085D01*
G01X938793Y97623D02*
X939669D01*
G01X940377Y99207D02*
X941812Y100642D01*
G01X940752Y101085D02*
X938043Y98376D01*
G01X938038Y96868D02*
X938793Y97623D01*
G01X938043Y98373D02*
X936978Y97308D01*
G01X938038Y95362D02*
Y96868D01*
G01X945572Y133465D02*
Y161372D01*
G01X944512Y161812D02*
Y133908D01*
G01X942172Y130065D02*
X945572Y133465D01*
G01X944512Y133908D02*
X941112Y130508D01*
G01X942172Y113304D02*
Y130065D01*
G01X941112Y130508D02*
Y113747D01*
G01X941812Y112944D02*
X942172Y113304D01*
G01X941112Y113747D02*
X940752Y113387D01*
G01X941812Y100642D02*
Y103480D01*
G01Y105720D02*
Y112944D01*
G01X940752Y113387D02*
Y101085D01*
G01X938793Y97623D02*
X939669D01*
G01X940377Y99207D02*
X941812Y100642D01*
G01X940752Y101085D02*
X938043Y98376D01*
G01X938038Y96868D02*
X938793Y97623D01*
G01X938043Y98373D02*
X936978Y97308D01*
G01X938038Y95362D02*
Y96868D01*
G01X938960Y151172D02*
Y153834D01*
G01X937900Y159934D02*
Y150732D01*
G01X939614Y150518D02*
X938960Y151172D01*
G01X937900Y150732D02*
X939174Y149458D01*
G01X940283Y150518D02*
X939614D01*
G01X939174Y149458D02*
X939840D01*
G01X941772Y149029D02*
X940283Y150518D01*
G01X939840Y149458D02*
X940712Y148586D01*
G01X941772Y145647D02*
Y149029D01*
G01X940712Y148586D02*
Y146087D01*
G01X940283Y144158D02*
X941772Y145647D01*
G01X940712Y146087D02*
X939843Y145218D01*
G01X938444Y144158D02*
X940283D01*
G01X939843Y145218D02*
X938004D01*
G01X937300Y143014D02*
X938444Y144158D01*
G01X938004Y145218D02*
X936240Y143454D01*
G01X937300Y141062D02*
Y143014D01*
G01X936240Y143454D02*
Y140622D01*
G01X938444Y139918D02*
X937300Y141062D01*
G01X936240Y140622D02*
X938004Y138858D01*
G01X940283Y139918D02*
X938444D01*
G01X938004Y138858D02*
X939840D01*
G01X941772Y138429D02*
X940283Y139918D01*
G01X939840Y138858D02*
X940712Y137986D01*
G01X941772Y135204D02*
Y138429D01*
G01X940712Y137986D02*
Y135647D01*
G01X940344Y133776D02*
X941772Y135204D01*
G01X940712Y135647D02*
X939901Y134836D01*
G01X938484Y133776D02*
X940344D01*
G01X939901Y134836D02*
X938041D01*
G01X937572Y132864D02*
X938484Y133776D01*
G01X938041Y134836D02*
X936512Y133307D01*
G01X937572Y114401D02*
Y115401D01*
G01Y117401D02*
Y118401D01*
G01Y120401D02*
Y121401D01*
G01Y123401D02*
Y128404D01*
G01Y131034D02*
Y132864D01*
G01X936512Y133307D02*
Y114844D01*
G01X936654Y113483D02*
X937572Y114401D01*
G01X936512Y114844D02*
X935594Y113926D01*
G01X936654Y101404D02*
Y102236D01*
G01Y104476D02*
Y113483D01*
G01X935594Y113926D02*
Y101847D01*
G01X932838Y97588D02*
X936654Y101404D01*
G01X935594Y101847D02*
X931778Y98031D01*
G01X932838Y95000D02*
Y97588D01*
G01X938960Y151172D02*
Y153834D01*
G01X937900Y159934D02*
Y150732D01*
G01X939614Y150518D02*
X938960Y151172D01*
G01X937900Y150732D02*
X939174Y149458D01*
G01X940283Y150518D02*
X939614D01*
G01X939174Y149458D02*
X939840D01*
G01X941772Y149029D02*
X940283Y150518D01*
G01X939840Y149458D02*
X940712Y148586D01*
G01X941772Y145647D02*
Y149029D01*
G01X940712Y148586D02*
Y146087D01*
G01X940283Y144158D02*
X941772Y145647D01*
G01X940712Y146087D02*
X939843Y145218D01*
G01X938444Y144158D02*
X940283D01*
G01X939843Y145218D02*
X938004D01*
G01X937300Y143014D02*
X938444Y144158D01*
G01X938004Y145218D02*
X936240Y143454D01*
G01X937300Y141062D02*
Y143014D01*
G01X936240Y143454D02*
Y140622D01*
G01X938444Y139918D02*
X937300Y141062D01*
G01X936240Y140622D02*
X938004Y138858D01*
G01X940283Y139918D02*
X938444D01*
G01X938004Y138858D02*
X939840D01*
G01X941772Y138429D02*
X940283Y139918D01*
G01X939840Y138858D02*
X940712Y137986D01*
G01X941772Y135204D02*
Y138429D01*
G01X940712Y137986D02*
Y135647D01*
G01X940344Y133776D02*
X941772Y135204D01*
G01X940712Y135647D02*
X939901Y134836D01*
G01X938484Y133776D02*
X940344D01*
G01X939901Y134836D02*
X938041D01*
G01X937572Y132864D02*
X938484Y133776D01*
G01X938041Y134836D02*
X936512Y133307D01*
G01X937572Y114401D02*
Y115401D01*
G01Y117401D02*
Y118401D01*
G01Y120401D02*
Y121401D01*
G01Y123401D02*
Y128404D01*
G01Y131034D02*
Y132864D01*
G01X936512Y133307D02*
Y114844D01*
G01X936654Y113483D02*
X937572Y114401D01*
G01X936512Y114844D02*
X935594Y113926D01*
G01X936654Y101404D02*
Y102236D01*
G01Y104476D02*
Y113483D01*
G01X935594Y113926D02*
Y101847D01*
G01X932838Y97588D02*
X936654Y101404D01*
G01X935594Y101847D02*
X931778Y98031D01*
G01X932838Y95000D02*
Y97588D01*
G01X938038Y95362D02*
Y96868D01*
G01X938043Y98373D02*
X936978Y97308D01*
G01X938038Y96868D02*
X938793Y97623D01*
G01X940752Y101085D02*
X938043Y98376D01*
G01X938793Y97623D02*
X939669D01*
G01X940752Y101085D02*
X938043Y98376D01*
G01X940377Y99207D02*
X941812Y100642D01*
G01X940752Y113387D02*
Y101085D01*
G01X941812Y100642D02*
Y103480D01*
G01X940752Y113387D02*
Y101085D01*
G01X941812Y105720D02*
Y112944D01*
G01X941112Y113747D02*
X940752Y113387D01*
G01X941812Y112944D02*
X942172Y113304D01*
G01X941112Y130508D02*
Y113747D01*
G01X942172Y113304D02*
Y130065D01*
G01X944512Y133908D02*
X941112Y130508D01*
G01X942172Y130065D02*
X945572Y133465D01*
G01X944512Y161812D02*
Y133908D01*
G01X945572Y133465D02*
Y161372D01*
G01X938038Y95362D02*
Y96868D01*
G01X938043Y98373D02*
X936978Y97308D01*
G01X938038Y96868D02*
X938793Y97623D01*
G01X940752Y101085D02*
X938043Y98376D01*
G01X938793Y97623D02*
X939669D01*
G01X940752Y101085D02*
X938043Y98376D01*
G01X940377Y99207D02*
X941812Y100642D01*
G01X940752Y113387D02*
Y101085D01*
G01X941812Y100642D02*
Y103480D01*
G01X940752Y113387D02*
Y101085D01*
G01X941812Y105720D02*
Y112944D01*
G01X941112Y113747D02*
X940752Y113387D01*
G01X941812Y112944D02*
X942172Y113304D01*
G01X941112Y130508D02*
Y113747D01*
G01X942172Y113304D02*
Y130065D01*
G01X944512Y133908D02*
X941112Y130508D01*
G01X942172Y130065D02*
X945572Y133465D01*
G01X944512Y161812D02*
Y133908D01*
G01X945572Y133465D02*
Y161372D01*
G01X913222Y176722D02*
X913978Y177478D01*
G01X915322Y178822D02*
X915998Y179498D01*
G01X917342Y180842D02*
X917978Y181478D01*
G01X919322Y182822D02*
X919993Y183493D01*
G01X921337Y184837D02*
X921973Y185473D01*
G01X923317Y186817D02*
X923953Y187453D01*
G01X925297Y188797D02*
X926053Y189553D01*
G01X927397Y190897D02*
X928476Y191976D01*
G01X929820Y193320D02*
X930456Y193956D01*
G01X913222Y176722D02*
X913978Y177478D01*
G01X915322Y178822D02*
X915998Y179498D01*
G01X917342Y180842D02*
X917978Y181478D01*
G01X919322Y182822D02*
X919993Y183493D01*
G01X921337Y184837D02*
X921973Y185473D01*
G01X923317Y186817D02*
X923953Y187453D01*
G01X925297Y188797D02*
X926053Y189553D01*
G01X927397Y190897D02*
X928476Y191976D01*
G01X929820Y193320D02*
X930456Y193956D01*
G01X913070Y217336D02*
X915069D01*
G01X910259Y214525D02*
X910895Y215161D01*
G01X912239Y216505D02*
X913070Y217336D01*
G01D02*
X915069D01*
G01X910259Y214525D02*
X910895Y215161D01*
G01X912239Y216505D02*
X913070Y217336D01*
G01X936483Y192857D02*
Y194683D01*
G01X935423D02*
Y193297D01*
G01X936483Y192857D02*
Y194683D01*
G01X935423D02*
Y193297D01*
G01X913222Y176722D02*
X913978Y177478D01*
G01X915322Y178822D02*
X915998Y179498D01*
G01X917342Y180842D02*
X917978Y181478D01*
G01X919322Y182822D02*
X919993Y183493D01*
G01X921337Y184837D02*
X921973Y185473D01*
G01X923317Y186817D02*
X923953Y187453D01*
G01X925297Y188797D02*
X926053Y189553D01*
G01X927397Y190897D02*
X928476Y191976D01*
G01X929820Y193320D02*
X930456Y193956D01*
G01X913222Y176722D02*
X913978Y177478D01*
G01X915322Y178822D02*
X915998Y179498D01*
G01X917342Y180842D02*
X917978Y181478D01*
G01X919322Y182822D02*
X919993Y183493D01*
G01X921337Y184837D02*
X921973Y185473D01*
G01X923317Y186817D02*
X923953Y187453D01*
G01X925297Y188797D02*
X926053Y189553D01*
G01X927397Y190897D02*
X928476Y191976D01*
G01X929820Y193320D02*
X930456Y193956D01*
G01X910259Y214525D02*
X910895Y215161D01*
G01X912239Y216505D02*
X913070Y217336D01*
G01D02*
X915069D01*
G01X910259Y214525D02*
X910895Y215161D01*
G01X912239Y216505D02*
X913070Y217336D01*
G01D02*
X915069D01*
G01X935423Y194683D02*
Y193297D01*
G01X936483Y192857D02*
Y194683D01*
G01X935423D02*
Y193297D01*
G01X936483Y192857D02*
Y194683D01*
G01X938960Y156464D02*
Y159494D01*
G01X964140Y186174D02*
X937900Y159934D01*
G01X938960Y159494D02*
X943122Y163656D01*
G01X964140Y186174D02*
X937900Y159934D01*
G01X944982Y165516D02*
X946276Y166810D01*
G01X964140Y186174D02*
X937900Y159934D01*
G01X948136Y168670D02*
X949430Y169964D01*
G01X964140Y186174D02*
X937900Y159934D01*
G01X951290Y171824D02*
X952584Y173118D01*
G01X964140Y186174D02*
X937900Y159934D01*
G01X954444Y174978D02*
X955738Y176272D01*
G01X964140Y186174D02*
X937900Y159934D01*
G01X957598Y178132D02*
X958892Y179426D01*
G01X964140Y186174D02*
X937900Y159934D01*
G01X960752Y181286D02*
X962046Y182580D01*
G01X964140Y186174D02*
X937900Y159934D01*
G01X963906Y184440D02*
X965200Y185734D01*
G01X964140Y188900D02*
Y186174D01*
G01X965200Y185734D02*
Y188900D01*
G01X938960Y156464D02*
Y159494D01*
G01X964140Y186174D02*
X937900Y159934D01*
G01X938960Y159494D02*
X943122Y163656D01*
G01X964140Y186174D02*
X937900Y159934D01*
G01X944982Y165516D02*
X946276Y166810D01*
G01X964140Y186174D02*
X937900Y159934D01*
G01X948136Y168670D02*
X949430Y169964D01*
G01X964140Y186174D02*
X937900Y159934D01*
G01X951290Y171824D02*
X952584Y173118D01*
G01X964140Y186174D02*
X937900Y159934D01*
G01X954444Y174978D02*
X955738Y176272D01*
G01X964140Y186174D02*
X937900Y159934D01*
G01X957598Y178132D02*
X958892Y179426D01*
G01X964140Y186174D02*
X937900Y159934D01*
G01X960752Y181286D02*
X962046Y182580D01*
G01X964140Y186174D02*
X937900Y159934D01*
G01X963906Y184440D02*
X965200Y185734D01*
G01X964140Y188900D02*
Y186174D01*
G01X965200Y185734D02*
Y188900D01*
G01X970800Y190563D02*
Y192965D01*
G01X969740Y192943D02*
Y190774D01*
G01X967998Y183798D02*
X970800Y190563D01*
G01X969740Y190774D02*
X967099Y184399D01*
G01X945572Y161372D02*
X953154Y168954D01*
G01X955014Y170814D02*
X956308Y172108D01*
G01X958168Y173968D02*
X959462Y175262D01*
G01X961322Y177122D02*
X967998Y183798D01*
G01X967099Y184399D02*
X944512Y161812D01*
G01X970800Y190563D02*
Y192965D01*
G01X969740Y192943D02*
Y190774D01*
G01X967998Y183798D02*
X970800Y190563D01*
G01X969740Y190774D02*
X967099Y184399D01*
G01X945572Y161372D02*
X953154Y168954D01*
G01X955014Y170814D02*
X956308Y172108D01*
G01X958168Y173968D02*
X959462Y175262D01*
G01X961322Y177122D02*
X967998Y183798D01*
G01X967099Y184399D02*
X944512Y161812D01*
G01X965200Y185734D02*
Y188900D01*
G01X964140D02*
Y186174D01*
G01X938960Y159494D02*
X943122Y163656D01*
G01X944982Y165516D02*
X946276Y166810D01*
G01X948136Y168670D02*
X949430Y169964D01*
G01X951290Y171824D02*
X952584Y173118D01*
G01X954444Y174978D02*
X955738Y176272D01*
G01X957598Y178132D02*
X958892Y179426D01*
G01X960752Y181286D02*
X962046Y182580D01*
G01X963906Y184440D02*
X965200Y185734D01*
G01X964140Y186174D02*
X937900Y159934D01*
G01X938960Y156464D02*
Y159494D01*
G01X965200Y185734D02*
Y188900D01*
G01X964140D02*
Y186174D01*
G01X938960Y159494D02*
X943122Y163656D01*
G01X944982Y165516D02*
X946276Y166810D01*
G01X948136Y168670D02*
X949430Y169964D01*
G01X951290Y171824D02*
X952584Y173118D01*
G01X954444Y174978D02*
X955738Y176272D01*
G01X957598Y178132D02*
X958892Y179426D01*
G01X960752Y181286D02*
X962046Y182580D01*
G01X963906Y184440D02*
X965200Y185734D01*
G01X964140Y186174D02*
X937900Y159934D01*
G01X938960Y156464D02*
Y159494D01*
G01X967099Y184399D02*
X944512Y161812D01*
G01X945572Y161372D02*
X953154Y168954D01*
G01X967099Y184399D02*
X944512Y161812D01*
G01X955014Y170814D02*
X956308Y172108D01*
G01X967099Y184399D02*
X944512Y161812D01*
G01X958168Y173968D02*
X959462Y175262D01*
G01X967099Y184399D02*
X944512Y161812D01*
G01X961322Y177122D02*
X967998Y183798D01*
G01X969740Y190774D02*
X967099Y184399D01*
G01X967998Y183798D02*
X970800Y190563D01*
G01X969740Y192943D02*
Y190774D01*
G01X970800Y190563D02*
Y192965D01*
G01X967099Y184399D02*
X944512Y161812D01*
G01X945572Y161372D02*
X953154Y168954D01*
G01X967099Y184399D02*
X944512Y161812D01*
G01X955014Y170814D02*
X956308Y172108D01*
G01X967099Y184399D02*
X944512Y161812D01*
G01X958168Y173968D02*
X959462Y175262D01*
G01X967099Y184399D02*
X944512Y161812D01*
G01X961322Y177122D02*
X967998Y183798D01*
G01X969740Y190774D02*
X967099Y184399D01*
G01X967998Y183798D02*
X970800Y190563D01*
G01X969740Y192943D02*
Y190774D01*
G01X970800Y190563D02*
Y192965D01*
G01X915069Y218396D02*
X912630D01*
G01X915069D02*
X912630D01*
G01X915069D02*
X912630D01*
G01X915069D02*
X912630D01*
G01X919227Y405641D02*
X911408Y413459D01*
G01X916955Y413165D02*
X913310Y416810D01*
G01X916204Y412416D02*
X912250Y416370D01*
G01X913310Y416810D02*
Y430459D01*
G01X912250Y416370D02*
Y430019D01*
G01X919227Y405641D02*
X911408Y413459D01*
G01X916204Y412416D02*
X912250Y416370D01*
G01X916955Y413165D02*
X913310Y416810D01*
G01X912250Y416370D02*
Y430019D01*
G01X913310Y416810D02*
Y430459D01*
G01X919227Y405641D02*
X911408Y413459D01*
G01X916955Y413165D02*
X913310Y416810D01*
G01X916204Y412416D02*
X912250Y416370D01*
G01X913310Y416810D02*
Y430459D01*
G01X912250Y416370D02*
Y430019D01*
G01X919227Y405641D02*
X911408Y413459D01*
G01X916204Y412416D02*
X912250Y416370D01*
G01X916955Y413165D02*
X913310Y416810D01*
G01X912250Y416370D02*
Y430019D01*
G01X913310Y416810D02*
Y430459D01*
G01X967871Y410996D02*
Y404437D01*
G01X968931D02*
Y411439D01*
G01X941920Y436947D02*
X967871Y410996D01*
G01X968931Y411439D02*
X942980Y437390D01*
G01X941920Y479709D02*
Y436947D01*
G01X942980Y437390D02*
Y480152D01*
G01X947592Y446440D02*
Y481637D01*
G01Y446440D02*
Y481637D01*
G01Y446440D02*
Y481637D01*
G01Y446440D02*
Y481637D01*
G01Y446440D02*
Y481637D01*
G01X946532Y468237D02*
Y446000D01*
G01X948252Y445780D02*
X947592Y446440D01*
G01X946532Y446000D02*
X947812Y444720D01*
G01X951618Y445780D02*
X948252D01*
G01X947812Y444720D02*
X951178D01*
G01X953080Y444318D02*
X951618Y445780D01*
G01X951178Y444720D02*
X952020Y443878D01*
G01X953080Y441725D02*
Y444318D01*
G01X952020Y443878D02*
Y442165D01*
G01X951588Y440233D02*
X953080Y441725D01*
G01X952020Y442165D02*
X951148Y441293D01*
G01X949803Y440233D02*
X951588D01*
G01X951148Y441293D02*
X949363D01*
G01X948931Y439361D02*
X949803Y440233D01*
G01X949363Y441293D02*
X947871Y439801D01*
G01X948931Y437662D02*
Y439361D01*
G01X947871Y439801D02*
Y437222D01*
G01X949800Y436793D02*
X948931Y437662D01*
G01X947871Y437222D02*
X949360Y435733D01*
G01X952419Y436793D02*
X949800D01*
G01X949360Y435733D02*
X951979D01*
G01X953908Y435304D02*
X952419Y436793D01*
G01X951979Y435733D02*
X952848Y434864D01*
G01X953908Y431861D02*
Y435304D01*
G01X952848Y434864D02*
Y431419D01*
G01X972894Y412875D02*
X953908Y431861D01*
G01X952850Y431419D02*
X971834Y412435D01*
G01X942980Y437390D02*
Y480152D01*
G01X941920Y479709D02*
Y436947D01*
G01X968931Y411439D02*
X942980Y437390D01*
G01X941920Y436947D02*
X967871Y410996D01*
G01X968931Y404437D02*
Y411439D01*
G01X967871Y410996D02*
Y404437D01*
G01X952850Y431419D02*
X971834Y412435D01*
G01X972894Y412875D02*
X953908Y431861D01*
G01X952848Y434864D02*
Y431419D01*
G01X953908Y431861D02*
Y435304D01*
G01X951979Y435733D02*
X952848Y434864D01*
G01X953908Y435304D02*
X952419Y436793D01*
G01X949360Y435733D02*
X951979D01*
G01X952419Y436793D02*
X949800D01*
G01X947871Y437222D02*
X949360Y435733D01*
G01X949800Y436793D02*
X948931Y437662D01*
G01X947871Y439801D02*
Y437222D01*
G01X948931Y437662D02*
Y439361D01*
G01X949363Y441293D02*
X947871Y439801D01*
G01X948931Y439361D02*
X949803Y440233D01*
G01X951148Y441293D02*
X949363D01*
G01X949803Y440233D02*
X951588D01*
G01X952020Y442165D02*
X951148Y441293D01*
G01X951588Y440233D02*
X953080Y441725D01*
G01X952020Y443878D02*
Y442165D01*
G01X953080Y441725D02*
Y444318D01*
G01X951178Y444720D02*
X952020Y443878D01*
G01X953080Y444318D02*
X951618Y445780D01*
G01X947812Y444720D02*
X951178D01*
G01X951618Y445780D02*
X948252D01*
G01X946532Y446000D02*
X947812Y444720D01*
G01X948252Y445780D02*
X947592Y446440D01*
G01X946532Y468237D02*
Y446000D01*
G01X947592Y446440D02*
Y481637D01*
G01X967871Y410996D02*
Y404437D01*
G01X968931D02*
Y411439D01*
G01X941920Y436947D02*
X967871Y410996D01*
G01X968931Y411439D02*
X942980Y437390D01*
G01X941920Y479709D02*
Y436947D01*
G01X942980Y437390D02*
Y480152D01*
G01X947592Y446440D02*
Y481637D01*
G01Y446440D02*
Y481637D01*
G01Y446440D02*
Y481637D01*
G01Y446440D02*
Y481637D01*
G01Y446440D02*
Y481637D01*
G01X946532Y468237D02*
Y446000D01*
G01X948252Y445780D02*
X947592Y446440D01*
G01X946532Y446000D02*
X947812Y444720D01*
G01X951618Y445780D02*
X948252D01*
G01X947812Y444720D02*
X951178D01*
G01X953080Y444318D02*
X951618Y445780D01*
G01X951178Y444720D02*
X952020Y443878D01*
G01X953080Y441725D02*
Y444318D01*
G01X952020Y443878D02*
Y442165D01*
G01X951588Y440233D02*
X953080Y441725D01*
G01X952020Y442165D02*
X951148Y441293D01*
G01X949803Y440233D02*
X951588D01*
G01X951148Y441293D02*
X949363D01*
G01X948931Y439361D02*
X949803Y440233D01*
G01X949363Y441293D02*
X947871Y439801D01*
G01X948931Y437662D02*
Y439361D01*
G01X947871Y439801D02*
Y437222D01*
G01X949800Y436793D02*
X948931Y437662D01*
G01X947871Y437222D02*
X949360Y435733D01*
G01X952419Y436793D02*
X949800D01*
G01X949360Y435733D02*
X951979D01*
G01X953908Y435304D02*
X952419Y436793D01*
G01X951979Y435733D02*
X952848Y434864D01*
G01X953908Y431861D02*
Y435304D01*
G01X952848Y434864D02*
Y431419D01*
G01X972894Y412875D02*
X953908Y431861D01*
G01X952850Y431419D02*
X971834Y412435D01*
G01X942980Y437390D02*
Y480152D01*
G01X941920Y479709D02*
Y436947D01*
G01X968931Y411439D02*
X942980Y437390D01*
G01X941920Y436947D02*
X967871Y410996D01*
G01X968931Y404437D02*
Y411439D01*
G01X967871Y410996D02*
Y404437D01*
G01X952850Y431419D02*
X971834Y412435D01*
G01X972894Y412875D02*
X953908Y431861D01*
G01X952848Y434864D02*
Y431419D01*
G01X953908Y431861D02*
Y435304D01*
G01X951979Y435733D02*
X952848Y434864D01*
G01X953908Y435304D02*
X952419Y436793D01*
G01X949360Y435733D02*
X951979D01*
G01X952419Y436793D02*
X949800D01*
G01X947871Y437222D02*
X949360Y435733D01*
G01X949800Y436793D02*
X948931Y437662D01*
G01X947871Y439801D02*
Y437222D01*
G01X948931Y437662D02*
Y439361D01*
G01X949363Y441293D02*
X947871Y439801D01*
G01X948931Y439361D02*
X949803Y440233D01*
G01X951148Y441293D02*
X949363D01*
G01X949803Y440233D02*
X951588D01*
G01X952020Y442165D02*
X951148Y441293D01*
G01X951588Y440233D02*
X953080Y441725D01*
G01X952020Y443878D02*
Y442165D01*
G01X953080Y441725D02*
Y444318D01*
G01X951178Y444720D02*
X952020Y443878D01*
G01X953080Y444318D02*
X951618Y445780D01*
G01X947812Y444720D02*
X951178D01*
G01X951618Y445780D02*
X948252D01*
G01X946532Y446000D02*
X947812Y444720D01*
G01X948252Y445780D02*
X947592Y446440D01*
G01X946532Y468237D02*
Y446000D01*
G01X947592Y446440D02*
Y481637D01*
G01X931644Y532411D02*
Y514400D01*
G01X932704Y520290D02*
Y521660D01*
G01X931644Y532411D02*
Y514400D01*
G01X932704Y525340D02*
Y526760D01*
G01X935652Y485977D02*
X941920Y479709D01*
G01X942980Y480152D02*
X936712Y486420D01*
G01X935652Y511808D02*
Y508824D01*
G01Y506484D02*
Y505484D01*
G01Y503144D02*
Y485977D01*
G01X936712Y486420D02*
Y512249D01*
G01X934760Y512700D02*
X935652Y511808D01*
G01X936712Y512249D02*
X933661Y515300D01*
G01X937257Y526229D02*
X938028Y527000D01*
G01X937257Y520571D02*
Y521848D01*
G01Y525338D02*
Y526229D01*
G01X936197Y526670D02*
Y520130D01*
G01X937928Y519900D02*
X937257Y520571D01*
G01X936197Y520130D02*
X937027Y519300D01*
G01X942112Y512134D02*
X938732Y515514D01*
G01Y512914D02*
X939832D01*
G01X942112Y512134D02*
X938732Y515514D01*
G01X939832Y512914D02*
X941052Y511694D01*
G01X942112Y487117D02*
Y512134D01*
G01X941052Y511694D02*
Y509967D01*
G01X942112Y487117D02*
Y512134D01*
G01X941052Y507727D02*
Y506727D01*
G01X942112Y487117D02*
Y512134D01*
G01X941052Y504487D02*
Y503487D01*
G01X942112Y487117D02*
Y512134D01*
G01X941052Y501247D02*
Y500154D01*
G01X942112Y487117D02*
Y512134D01*
G01X941052Y498100D02*
Y496915D01*
G01X942112Y487117D02*
Y512134D01*
G01X941052Y494885D02*
Y493715D01*
G01X942112Y487117D02*
Y512134D01*
G01X941052Y491633D02*
Y490527D01*
G01X942112Y487117D02*
Y512134D01*
G01X941052Y488287D02*
Y486677D01*
G01X947592Y481637D02*
X942112Y487117D01*
G01X941052Y486677D02*
X941759Y485970D01*
G01X947592Y481637D02*
X942112Y487117D01*
G01X943344Y484385D02*
X944051Y483678D01*
G01X947592Y481637D02*
X942112Y487117D01*
G01X945636Y482093D02*
X946532Y481197D01*
G01D02*
Y480197D01*
G01Y477957D02*
Y476957D01*
G01Y474717D02*
Y473717D01*
G01Y471477D02*
Y470477D01*
G01X932704Y520290D02*
Y521660D01*
G01Y525340D02*
Y526760D01*
G01X931644Y532411D02*
Y514400D01*
G01X936712Y512249D02*
X933661Y515300D01*
G01X934760Y512700D02*
X935652Y511808D01*
G01X936712Y486420D02*
Y512249D01*
G01X935652Y511808D02*
Y508824D01*
G01X936712Y486420D02*
Y512249D01*
G01X935652Y506484D02*
Y505484D01*
G01X936712Y486420D02*
Y512249D01*
G01X935652Y503144D02*
Y485977D01*
G01X942980Y480152D02*
X936712Y486420D01*
G01X935652Y485977D02*
X941920Y479709D01*
G01X936197Y520130D02*
X937027Y519300D01*
G01X937928Y519900D02*
X937257Y520571D01*
G01X936197Y526670D02*
Y520130D01*
G01X937257Y520571D02*
Y521848D01*
G01X936197Y526670D02*
Y520130D01*
G01X937257Y525338D02*
Y526229D01*
G01D02*
X938028Y527000D01*
G01X946532Y481197D02*
Y480197D01*
G01Y477957D02*
Y476957D01*
G01Y474717D02*
Y473717D01*
G01Y471477D02*
Y470477D01*
G01X941052Y486677D02*
X941759Y485970D01*
G01X943344Y484385D02*
X944051Y483678D01*
G01X945636Y482093D02*
X946532Y481197D01*
G01X947592Y481637D02*
X942112Y487117D01*
G01X941052Y511694D02*
Y509967D01*
G01Y507727D02*
Y506727D01*
G01Y504487D02*
Y503487D01*
G01Y501247D02*
Y500154D01*
G01Y498100D02*
Y496915D01*
G01Y494885D02*
Y493715D01*
G01Y491633D02*
Y490527D01*
G01Y488287D02*
Y486677D01*
G01X942112Y487117D02*
Y512134D01*
G01X938732Y512914D02*
X939832D01*
G01D02*
X941052Y511694D01*
G01X942112Y512134D02*
X938732Y515514D01*
G01X931644Y532411D02*
Y514400D01*
G01X932704Y520290D02*
Y521660D01*
G01X931644Y532411D02*
Y514400D01*
G01X932704Y525340D02*
Y526760D01*
G01X935652Y485977D02*
X941920Y479709D01*
G01X942980Y480152D02*
X936712Y486420D01*
G01X935652Y511808D02*
Y508824D01*
G01Y506484D02*
Y505484D01*
G01Y503144D02*
Y485977D01*
G01X936712Y486420D02*
Y512249D01*
G01X934760Y512700D02*
X935652Y511808D01*
G01X936712Y512249D02*
X933661Y515300D01*
G01X937257Y526229D02*
X938028Y527000D01*
G01X937257Y520571D02*
Y521848D01*
G01Y525338D02*
Y526229D01*
G01X936197Y526670D02*
Y520130D01*
G01X937928Y519900D02*
X937257Y520571D01*
G01X936197Y520130D02*
X937027Y519300D01*
G01X942112Y512134D02*
X938732Y515514D01*
G01Y512914D02*
X939832D01*
G01X942112Y512134D02*
X938732Y515514D01*
G01X939832Y512914D02*
X941052Y511694D01*
G01X942112Y487117D02*
Y512134D01*
G01X941052Y511694D02*
Y509967D01*
G01X942112Y487117D02*
Y512134D01*
G01X941052Y507727D02*
Y506727D01*
G01X942112Y487117D02*
Y512134D01*
G01X941052Y504487D02*
Y503487D01*
G01X942112Y487117D02*
Y512134D01*
G01X941052Y501247D02*
Y500154D01*
G01X942112Y487117D02*
Y512134D01*
G01X941052Y498100D02*
Y496915D01*
G01X942112Y487117D02*
Y512134D01*
G01X941052Y494885D02*
Y493715D01*
G01X942112Y487117D02*
Y512134D01*
G01X941052Y491633D02*
Y490527D01*
G01X942112Y487117D02*
Y512134D01*
G01X941052Y488287D02*
Y486677D01*
G01X947592Y481637D02*
X942112Y487117D01*
G01X941052Y486677D02*
X941759Y485970D01*
G01X947592Y481637D02*
X942112Y487117D01*
G01X943344Y484385D02*
X944051Y483678D01*
G01X947592Y481637D02*
X942112Y487117D01*
G01X945636Y482093D02*
X946532Y481197D01*
G01D02*
Y480197D01*
G01Y477957D02*
Y476957D01*
G01Y474717D02*
Y473717D01*
G01Y471477D02*
Y470477D01*
G01X932704Y520290D02*
Y521660D01*
G01Y525340D02*
Y526760D01*
G01X931644Y532411D02*
Y514400D01*
G01X936712Y512249D02*
X933661Y515300D01*
G01X934760Y512700D02*
X935652Y511808D01*
G01X936712Y486420D02*
Y512249D01*
G01X935652Y511808D02*
Y508824D01*
G01X936712Y486420D02*
Y512249D01*
G01X935652Y506484D02*
Y505484D01*
G01X936712Y486420D02*
Y512249D01*
G01X935652Y503144D02*
Y485977D01*
G01X942980Y480152D02*
X936712Y486420D01*
G01X935652Y485977D02*
X941920Y479709D01*
G01X936197Y520130D02*
X937027Y519300D01*
G01X937928Y519900D02*
X937257Y520571D01*
G01X936197Y526670D02*
Y520130D01*
G01X937257Y520571D02*
Y521848D01*
G01X936197Y526670D02*
Y520130D01*
G01X937257Y525338D02*
Y526229D01*
G01D02*
X938028Y527000D01*
G01X946532Y481197D02*
Y480197D01*
G01Y477957D02*
Y476957D01*
G01Y474717D02*
Y473717D01*
G01Y471477D02*
Y470477D01*
G01X941052Y486677D02*
X941759Y485970D01*
G01X943344Y484385D02*
X944051Y483678D01*
G01X945636Y482093D02*
X946532Y481197D01*
G01X947592Y481637D02*
X942112Y487117D01*
G01X941052Y511694D02*
Y509967D01*
G01Y507727D02*
Y506727D01*
G01Y504487D02*
Y503487D01*
G01Y501247D02*
Y500154D01*
G01Y498100D02*
Y496915D01*
G01Y494885D02*
Y493715D01*
G01Y491633D02*
Y490527D01*
G01Y488287D02*
Y486677D01*
G01X942112Y487117D02*
Y512134D01*
G01X938732Y512914D02*
X939832D01*
G01D02*
X941052Y511694D01*
G01X942112Y512134D02*
X938732Y515514D01*
G01X937027Y527500D02*
X936197Y526670D01*
G01X937027Y527500D02*
X936197Y526670D01*
G01X937027Y527500D02*
X936197Y526670D01*
G01X937027Y527500D02*
X936197Y526670D01*
G01X1032400Y39260D02*
Y7541D01*
G01X1033460Y38820D02*
Y7101D01*
G01X1032400Y7541D02*
X1029359Y4500D01*
G01X1033460Y7101D02*
X1029799Y3440D01*
G01X1029359Y4500D02*
X1025400D01*
G01X1029799Y3440D02*
X1025840D01*
G01X1025400Y4500D02*
X1022900Y2000D01*
G01X1025840Y3440D02*
X1023960Y1560D01*
G01X1022900Y2000D02*
Y-2407D01*
G01X1023960Y1560D02*
Y-2847D01*
G01X1022900Y-2407D02*
X1019702Y-5605D01*
G01X1023960Y-2847D02*
X1020142Y-6665D01*
G01X1019702Y-5605D02*
X1013413D01*
G01X1020142Y-6665D02*
X1013853D01*
G01X1013413Y-5605D02*
X1011894Y-7124D01*
G01X1013853Y-6665D02*
X1012954Y-7564D01*
G01X1011894Y-7124D02*
Y-8718D01*
G01X1012954Y-7564D02*
Y-8567D01*
G01X1023420Y41520D02*
Y24336D01*
G01X1024480Y41080D02*
Y23896D01*
G01X1023420Y24336D02*
X1019964Y20880D01*
G01X1024480Y23896D02*
X1020404Y19820D01*
G01X1019964Y20880D02*
X1014218D01*
G01X1020404Y19820D02*
X1014658D01*
G01X1014218Y20880D02*
X1013098Y19760D01*
G01X1014658Y19820D02*
X1014158Y19320D01*
G01X1013098Y19760D02*
Y17842D01*
G01X1014158Y19320D02*
Y17803D01*
G01X1011894Y-790D02*
Y1231D01*
G01X1012954Y-639D02*
Y1671D01*
G01X1011894Y1231D02*
X1011198Y1927D01*
G01X1012954Y1671D02*
X1011638Y2987D01*
G01X1011198Y1927D02*
X1007804D01*
G01X1011638Y2987D02*
X1008244D01*
G01X1007804Y1927D02*
X1006594Y3137D01*
G01X1008244Y2987D02*
X1007654Y3577D01*
G01X1006594Y3137D02*
Y5916D01*
G01X1007654Y3577D02*
Y5476D01*
G01X1006594Y5916D02*
X1007867Y7189D01*
G01X1007654Y5476D02*
X1008307Y6129D01*
G01X1007867Y7189D02*
X1015797D01*
G01X1008307Y6129D02*
X1015357D01*
G01X1015797Y7189D02*
X1017193Y5793D01*
G01X1015357Y6129D02*
X1016133Y5353D01*
G01X1017193Y5793D02*
Y1665D01*
G01X1016133Y5353D02*
Y1225D01*
G01X1017193Y1665D02*
X1017806Y1052D01*
G01X1016133Y1225D02*
X1017366Y-8D01*
G01X1017806Y1052D02*
X1019250D01*
G01X1017366Y-8D02*
X1019690D01*
G01X1019250Y1052D02*
X1019862Y1664D01*
G01X1019690Y-8D02*
X1020922Y1224D01*
G01X1019862Y1664D02*
Y5277D01*
G01X1020922Y1224D02*
Y4837D01*
G01X1019862Y5277D02*
X1024494Y9909D01*
G01X1020922Y4837D02*
X1024934Y8849D01*
G01X1024494Y9909D02*
X1025962D01*
G01X1024934Y8849D02*
X1026402D01*
G01X1024494Y9909D02*
X1025962D01*
G01D02*
X1027394Y11341D01*
G01X1026402Y8849D02*
X1028454Y10901D01*
G01X1027394Y11341D02*
Y41394D01*
G01X1028454Y10901D02*
Y40954D01*
G01X1019920Y43320D02*
Y26807D01*
G01X1020980Y42880D02*
Y26367D01*
G01X1019920Y26807D02*
X1018493Y25380D01*
G01X1020980Y26367D02*
X1018933Y24320D01*
G01X1018493Y25380D02*
X1013342D01*
G01X1018933Y24320D02*
X1013782D01*
G01X1013342Y25380D02*
X1009505Y21543D01*
G01X1013782Y24320D02*
X1010565Y21103D01*
G01X1009505Y21543D02*
Y15083D01*
G01X1010565Y21103D02*
Y15523D01*
G01X1009505Y15083D02*
X1011894Y12694D01*
G01X1010565Y15523D02*
X1012954Y13134D01*
G01X1011894Y12694D02*
Y10182D01*
G01X1012954Y13134D02*
Y10333D01*
G01X1033460Y38820D02*
Y7101D01*
G01X1032400Y39260D02*
Y7541D01*
G01X1033460Y7101D02*
X1029799Y3440D01*
G01X1032400Y7541D02*
X1029359Y4500D01*
G01X1029799Y3440D02*
X1025840D01*
G01X1029359Y4500D02*
X1025400D01*
G01X1025840Y3440D02*
X1023960Y1560D01*
G01X1025400Y4500D02*
X1022900Y2000D01*
G01X1023960Y1560D02*
Y-2847D01*
G01X1022900Y2000D02*
Y-2407D01*
G01X1023960Y-2847D02*
X1020142Y-6665D01*
G01X1022900Y-2407D02*
X1019702Y-5605D01*
G01X1020142Y-6665D02*
X1013853D01*
G01X1019702Y-5605D02*
X1013413D01*
G01X1013853Y-6665D02*
X1012954Y-7564D01*
G01X1013413Y-5605D02*
X1011894Y-7124D01*
G01X1012954Y-7564D02*
Y-8567D01*
G01X1011894Y-7124D02*
Y-8718D01*
G01X1024480Y41080D02*
Y23896D01*
G01X1023420Y41520D02*
Y24336D01*
G01X1024480Y23896D02*
X1020404Y19820D01*
G01X1023420Y24336D02*
X1019964Y20880D01*
G01X1020404Y19820D02*
X1014658D01*
G01X1019964Y20880D02*
X1014218D01*
G01X1014658Y19820D02*
X1014158Y19320D01*
G01X1014218Y20880D02*
X1013098Y19760D01*
G01X1014158Y19320D02*
Y17803D01*
G01X1013098Y19760D02*
Y17842D01*
G01X1012954Y-639D02*
Y1671D01*
G01X1011894Y-790D02*
Y1231D01*
G01X1012954Y1671D02*
X1011638Y2987D01*
G01X1011894Y1231D02*
X1011198Y1927D01*
G01X1011638Y2987D02*
X1008244D01*
G01X1011198Y1927D02*
X1007804D01*
G01X1008244Y2987D02*
X1007654Y3577D01*
G01X1007804Y1927D02*
X1006594Y3137D01*
G01X1007654Y3577D02*
Y5476D01*
G01X1006594Y3137D02*
Y5916D01*
G01X1007654Y5476D02*
X1008307Y6129D01*
G01X1006594Y5916D02*
X1007867Y7189D01*
G01X1008307Y6129D02*
X1015357D01*
G01X1007867Y7189D02*
X1015797D01*
G01X1015357Y6129D02*
X1016133Y5353D01*
G01X1015797Y7189D02*
X1017193Y5793D01*
G01X1016133Y5353D02*
Y1225D01*
G01X1017193Y5793D02*
Y1665D01*
G01X1016133Y1225D02*
X1017366Y-8D01*
G01X1017193Y1665D02*
X1017806Y1052D01*
G01X1017366Y-8D02*
X1019690D01*
G01X1017806Y1052D02*
X1019250D01*
G01X1019690Y-8D02*
X1020922Y1224D01*
G01X1019250Y1052D02*
X1019862Y1664D01*
G01X1020922Y1224D02*
Y4837D01*
G01X1019862Y1664D02*
Y5277D01*
G01X1020922Y4837D02*
X1024934Y8849D01*
G01X1019862Y5277D02*
X1024494Y9909D01*
G01X1024934Y8849D02*
X1026402D01*
G01D02*
X1028454Y10901D01*
G01X1024494Y9909D02*
X1025962D01*
G01X1026402Y8849D02*
X1028454Y10901D01*
G01X1025962Y9909D02*
X1027394Y11341D01*
G01X1028454Y10901D02*
Y40954D01*
G01X1027394Y11341D02*
Y41394D01*
G01X1020980Y42880D02*
Y26367D01*
G01X1019920Y43320D02*
Y26807D01*
G01X1020980Y26367D02*
X1018933Y24320D01*
G01X1019920Y26807D02*
X1018493Y25380D01*
G01X1018933Y24320D02*
X1013782D01*
G01X1018493Y25380D02*
X1013342D01*
G01X1013782Y24320D02*
X1010565Y21103D01*
G01X1013342Y25380D02*
X1009505Y21543D01*
G01X1010565Y21103D02*
Y15523D01*
G01X1009505Y21543D02*
Y15083D01*
G01X1010565Y15523D02*
X1012954Y13134D01*
G01X1009505Y15083D02*
X1011894Y12694D01*
G01X1012954Y13134D02*
Y10333D01*
G01X1011894Y12694D02*
Y10182D01*
G01X1031120Y104160D02*
Y80280D01*
G01X1032180Y104600D02*
Y80720D01*
G01X1031120Y80280D02*
X1032340Y79060D01*
G01X1032180Y80720D02*
X1033400Y79500D01*
G01X1032340Y79060D02*
Y46060D01*
G01X1033400Y79500D02*
Y46500D01*
G01X1032340Y46060D02*
X1033600Y44800D01*
G01X1033400Y46500D02*
X1034660Y45240D01*
G01X1033600Y40460D02*
X1032400Y39260D01*
G01X1034660Y40020D02*
X1033460Y38820D01*
G01X1020326Y188688D02*
Y84617D01*
G01X1021386Y188688D02*
Y84177D01*
G01X1020326Y84617D02*
X1019716Y84007D01*
G01X1021386Y84177D02*
X1020156Y82947D01*
G01X1019716Y84007D02*
X1016570D01*
G01X1020156Y82947D02*
X1017010D01*
G01X1016570Y84007D02*
X1015369Y82806D01*
G01X1017010Y82947D02*
X1016429Y82366D01*
G01X1015369Y82806D02*
Y80536D01*
G01X1016429Y82366D02*
Y80976D01*
G01X1015369Y80536D02*
X1016628Y79277D01*
G01X1016429Y80976D02*
X1017068Y80337D01*
G01X1016628Y79277D02*
X1019716D01*
G01X1017068Y80337D02*
X1020156D01*
G01X1019716Y79277D02*
X1020326Y78667D01*
G01X1020156Y80337D02*
X1021386Y79107D01*
G01X1020326Y78667D02*
Y61774D01*
G01X1021386Y79107D02*
Y62214D01*
G01X1020326Y61774D02*
X1023420Y58680D01*
G01X1021386Y62214D02*
X1024480Y59120D01*
G01X1023420Y58680D02*
Y54130D01*
G01X1024480Y59120D02*
Y54570D01*
G01X1023420Y54130D02*
X1025640Y51910D01*
G01X1024480Y54570D02*
X1026700Y52350D01*
G01X1025640Y51910D02*
Y43740D01*
G01X1026700Y52350D02*
Y43300D01*
G01X1025640Y43740D02*
X1023420Y41520D01*
G01X1026700Y43300D02*
X1024480Y41080D01*
G01X1027394Y41394D02*
X1028440Y42440D01*
G01X1028454Y40954D02*
X1029500Y42000D01*
G01X1028440Y42440D02*
Y54160D01*
G01X1029500Y42000D02*
Y54600D01*
G01X1028440Y54160D02*
X1027394Y55206D01*
G01X1029500Y54600D02*
X1028454Y55646D01*
G01X1027394Y55206D02*
Y102183D01*
G01X1028454Y55646D02*
Y102623D01*
G01X1009278Y95307D02*
Y85693D01*
G01X1010338Y94867D02*
Y86133D01*
G01X1009278Y85693D02*
X1010940Y84031D01*
G01X1010338Y86133D02*
X1012000Y84471D01*
G01X1010940Y84031D02*
Y71660D01*
G01X1012000Y84471D02*
Y72100D01*
G01X1010940Y71660D02*
X1013600Y69000D01*
G01X1012000Y72100D02*
X1014660Y69440D01*
G01X1013600Y69000D02*
Y62400D01*
G01X1014660Y69440D02*
Y62840D01*
G01X1013600Y62400D02*
X1019920Y56080D01*
G01X1014660Y62840D02*
X1020980Y56520D01*
G01X1019920Y56080D02*
Y53330D01*
G01X1020980Y56520D02*
Y53770D01*
G01X1019920Y53330D02*
X1022540Y50710D01*
G01X1020980Y53770D02*
X1023600Y51150D01*
G01X1022540Y50710D02*
Y45940D01*
G01X1023600Y51150D02*
Y45500D01*
G01X1022540Y45940D02*
X1019920Y43320D01*
G01X1023600Y45500D02*
X1020980Y42880D01*
G01X1032180Y104600D02*
Y80720D01*
G01X1031120Y104160D02*
Y80280D01*
G01X1032180Y80720D02*
X1033400Y79500D01*
G01X1031120Y80280D02*
X1032340Y79060D01*
G01X1033400Y79500D02*
Y46500D01*
G01X1032340Y79060D02*
Y46060D01*
G01X1033400Y46500D02*
X1034660Y45240D01*
G01X1032340Y46060D02*
X1033600Y44800D01*
G01X1034660Y40020D02*
X1033460Y38820D01*
G01X1033600Y40460D02*
X1032400Y39260D01*
G01X1021386Y188688D02*
Y84177D01*
G01X1020326Y188688D02*
Y84617D01*
G01X1021386Y84177D02*
X1020156Y82947D01*
G01X1020326Y84617D02*
X1019716Y84007D01*
G01X1020156Y82947D02*
X1017010D01*
G01X1019716Y84007D02*
X1016570D01*
G01X1017010Y82947D02*
X1016429Y82366D01*
G01X1016570Y84007D02*
X1015369Y82806D01*
G01X1016429Y82366D02*
Y80976D01*
G01X1015369Y82806D02*
Y80536D01*
G01X1016429Y80976D02*
X1017068Y80337D01*
G01X1015369Y80536D02*
X1016628Y79277D01*
G01X1017068Y80337D02*
X1020156D01*
G01X1016628Y79277D02*
X1019716D01*
G01X1020156Y80337D02*
X1021386Y79107D01*
G01X1019716Y79277D02*
X1020326Y78667D01*
G01X1021386Y79107D02*
Y62214D01*
G01X1020326Y78667D02*
Y61774D01*
G01X1021386Y62214D02*
X1024480Y59120D01*
G01X1020326Y61774D02*
X1023420Y58680D01*
G01X1024480Y59120D02*
Y54570D01*
G01X1023420Y58680D02*
Y54130D01*
G01X1024480Y54570D02*
X1026700Y52350D01*
G01X1023420Y54130D02*
X1025640Y51910D01*
G01X1026700Y52350D02*
Y43300D01*
G01X1025640Y51910D02*
Y43740D01*
G01X1026700Y43300D02*
X1024480Y41080D01*
G01X1025640Y43740D02*
X1023420Y41520D01*
G01X1028454Y40954D02*
X1029500Y42000D01*
G01X1027394Y41394D02*
X1028440Y42440D01*
G01X1029500Y42000D02*
Y54600D01*
G01X1028440Y42440D02*
Y54160D01*
G01X1029500Y54600D02*
X1028454Y55646D01*
G01X1028440Y54160D02*
X1027394Y55206D01*
G01X1028454Y55646D02*
Y102623D01*
G01X1027394Y55206D02*
Y102183D01*
G01X1010338Y94867D02*
Y86133D01*
G01X1009278Y95307D02*
Y85693D01*
G01X1010338Y86133D02*
X1012000Y84471D01*
G01X1009278Y85693D02*
X1010940Y84031D01*
G01X1012000Y84471D02*
Y72100D01*
G01X1010940Y84031D02*
Y71660D01*
G01X1012000Y72100D02*
X1014660Y69440D01*
G01X1010940Y71660D02*
X1013600Y69000D01*
G01X1014660Y69440D02*
Y62840D01*
G01X1013600Y69000D02*
Y62400D01*
G01X1014660Y62840D02*
X1020980Y56520D01*
G01X1013600Y62400D02*
X1019920Y56080D01*
G01X1020980Y56520D02*
Y53770D01*
G01X1019920Y56080D02*
Y53330D01*
G01X1020980Y53770D02*
X1023600Y51150D01*
G01X1019920Y53330D02*
X1022540Y50710D01*
G01X1023600Y51150D02*
Y45500D01*
G01X1022540Y50710D02*
Y45940D01*
G01X1023600Y45500D02*
X1020980Y42880D01*
G01X1022540Y45940D02*
X1019920Y43320D01*
G01X1026976Y189302D02*
Y108304D01*
G01X1028036Y189302D02*
Y108744D01*
G01X1026976Y108304D02*
X1031120Y104160D01*
G01X1028036Y108744D02*
X1032180Y104600D01*
G01X1027394Y102183D02*
X1023676Y105901D01*
G01X1028454Y102623D02*
X1024736Y106341D01*
G01X1023676Y105901D02*
Y189367D01*
G01X1024736Y106341D02*
Y189209D01*
G01X1017026Y196219D02*
Y103055D01*
G01X1018086Y196219D02*
Y102615D01*
G01X1017026Y103055D02*
X1009278Y95307D01*
G01X1018086Y102615D02*
X1010338Y94867D01*
G01X1028036Y189302D02*
Y108744D01*
G01X1026976Y189302D02*
Y108304D01*
G01X1028036Y108744D02*
X1032180Y104600D01*
G01X1026976Y108304D02*
X1031120Y104160D01*
G01X1028454Y102623D02*
X1024736Y106341D01*
G01X1027394Y102183D02*
X1023676Y105901D01*
G01X1024736Y106341D02*
Y189209D01*
G01X1023676Y105901D02*
Y189367D01*
G01X1018086Y196219D02*
Y102615D01*
G01X1017026Y196219D02*
Y103055D01*
G01X1018086Y102615D02*
X1010338Y94867D01*
G01X1017026Y103055D02*
X1009278Y95307D01*
G01X1022080Y401501D02*
Y404948D01*
G01X1021020Y401381D02*
Y405391D01*
G01X1015384Y401397D02*
Y407652D01*
G01X1014324Y401277D02*
Y408095D01*
G01X1025480Y401579D02*
Y403648D01*
G01X1024420Y401699D02*
Y404091D01*
G01X1018755Y401923D02*
Y406326D01*
G01X1017695Y401923D02*
Y406766D01*
G01X1021020Y401381D02*
Y405391D01*
G01X1022080Y401501D02*
Y404948D01*
G01X1014324Y401277D02*
Y408095D01*
G01X1015384Y401397D02*
Y407652D01*
G01X1024420Y401699D02*
Y404091D01*
G01X1025480Y401579D02*
Y403648D01*
G01X1017695Y401923D02*
Y406766D01*
G01X1018755Y401923D02*
Y406326D01*
G01X972894Y407587D02*
Y412875D01*
G01X971834Y412435D02*
Y407587D01*
G01Y412435D02*
Y407587D01*
G01X972894D02*
Y412875D01*
G01Y407587D02*
Y412875D01*
G01X971834Y412435D02*
Y407587D01*
G01Y412435D02*
Y407587D01*
G01X972894D02*
Y412875D01*
G01X1022080Y404948D02*
X1023180Y406048D01*
G01X1021020Y405391D02*
X1022120Y406491D01*
G01X1023180Y406048D02*
Y495808D01*
G01X1022120Y406491D02*
Y496248D01*
G01X1015384Y407652D02*
X1016580Y408848D01*
G01X1014324Y408095D02*
X1015520Y409291D01*
G01X1016580Y408848D02*
Y499048D01*
G01X1015520Y409291D02*
Y499488D01*
G01X1025480Y403648D02*
X1026680Y404848D01*
G01X1024420Y404091D02*
X1025620Y405291D01*
G01X1026680Y404848D02*
Y494448D01*
G01X1025620Y405291D02*
Y494888D01*
G01X1018755Y406326D02*
X1019877Y407448D01*
G01X1017695Y406766D02*
X1018820Y407891D01*
G01X1019880Y407449D02*
Y497551D01*
G01X1018820Y407891D02*
Y497991D01*
G01X1021020Y405391D02*
X1022120Y406491D01*
G01X1022080Y404948D02*
X1023180Y406048D01*
G01X1022120Y406491D02*
Y496248D01*
G01X1023180Y406048D02*
Y495808D01*
G01X1014324Y408095D02*
X1015520Y409291D01*
G01X1015384Y407652D02*
X1016580Y408848D01*
G01X1015520Y409291D02*
Y499488D01*
G01X1016580Y408848D02*
Y499048D01*
G01X1024420Y404091D02*
X1025620Y405291D01*
G01X1025480Y403648D02*
X1026680Y404848D01*
G01X1025620Y405291D02*
Y494888D01*
G01X1026680Y404848D02*
Y494448D01*
G01X1017695Y406766D02*
X1018820Y407891D01*
G01X1018755Y406326D02*
X1019877Y407448D01*
G01X1018820Y407891D02*
Y497991D01*
G01X1019880Y407449D02*
Y497551D01*
G01X1023180Y495808D02*
X1027368Y499996D01*
G01X1022120Y496248D02*
X1026308Y500436D01*
G01X1027368Y499996D02*
Y510444D01*
G01X1026308Y500436D02*
Y510884D01*
G01X1027368Y510444D02*
X1029267Y512343D01*
G01X1026308Y510884D02*
X1028207Y512783D01*
G01X1029267Y512343D02*
Y595903D01*
G01X1028207Y512783D02*
Y520701D01*
G01X1029267Y512343D02*
Y595903D01*
G01X1028207Y523427D02*
Y525257D01*
G01X1029267Y512343D02*
Y595903D01*
G01Y512343D02*
Y595903D01*
G01Y512343D02*
Y595903D01*
G01Y512343D02*
Y595903D01*
G01Y512343D02*
Y595903D01*
G01Y512343D02*
Y595903D01*
G01X1016580Y499048D02*
X1019400Y501868D01*
G01X1015520Y499488D02*
X1018340Y502308D01*
G01X1019400Y501868D02*
Y511377D01*
G01Y513889D02*
Y515808D01*
G01Y518534D02*
Y520364D01*
G01Y523090D02*
Y524920D01*
G01X1018340Y502308D02*
Y525360D01*
G01X1019400Y524920D02*
X1020680Y526200D01*
G01X1018340Y525360D02*
X1019620Y526640D01*
G01X1020680Y526200D02*
Y530236D01*
G01X1026680Y494448D02*
X1031273Y499041D01*
G01X1025620Y494888D02*
X1030213Y499481D01*
G01X1031273Y499041D02*
Y508653D01*
G01X1030213Y499481D02*
Y509093D01*
G01X1031273Y508653D02*
X1032741Y510121D01*
G01X1030213Y509093D02*
X1031681Y510561D01*
G01X1032741Y510121D02*
Y553539D01*
G01X1031681Y510561D02*
Y533775D01*
G01X1032741Y510121D02*
Y553539D01*
G01Y510121D02*
Y553539D01*
G01Y510121D02*
Y553539D01*
G01Y510121D02*
Y553539D01*
G01X1019880Y497551D02*
X1023000Y500671D01*
G01X1018820Y497991D02*
X1021940Y501111D01*
G01X1023000Y500671D02*
Y523120D01*
G01X1021940Y501111D02*
Y502941D01*
G01X1023000Y500671D02*
Y523120D01*
G01X1021940Y505667D02*
Y507497D01*
G01X1023000Y500671D02*
Y523120D01*
G01X1021940Y510223D02*
Y523560D01*
G01X1023000Y523120D02*
X1024453Y524573D01*
G01X1021940Y523560D02*
X1023393Y525013D01*
G01X1024453Y524573D02*
Y547252D01*
G01X1023393Y525013D02*
Y526843D01*
G01X1024453Y524573D02*
Y547252D01*
G01X1022120Y496248D02*
X1026308Y500436D01*
G01X1023180Y495808D02*
X1027368Y499996D01*
G01X1026308Y500436D02*
Y510884D01*
G01X1027368Y499996D02*
Y510444D01*
G01X1026308Y510884D02*
X1028207Y512783D01*
G01X1027368Y510444D02*
X1029267Y512343D01*
G01X1028207Y512783D02*
Y520701D01*
G01Y523427D02*
Y525257D01*
G01X1029267Y512343D02*
Y595903D01*
G01X1015520Y499488D02*
X1018340Y502308D01*
G01X1016580Y499048D02*
X1019400Y501868D01*
G01X1018340Y502308D02*
Y525360D01*
G01X1019400Y501868D02*
Y511377D01*
G01X1018340Y502308D02*
Y525360D01*
G01X1019400Y513889D02*
Y515808D01*
G01X1018340Y502308D02*
Y525360D01*
G01X1019400Y518534D02*
Y520364D01*
G01X1018340Y502308D02*
Y525360D01*
G01X1019400Y523090D02*
Y524920D01*
G01X1018340Y525360D02*
X1019620Y526640D01*
G01X1019400Y524920D02*
X1020680Y526200D01*
G01D02*
Y530236D01*
G01X1025620Y494888D02*
X1030213Y499481D01*
G01X1026680Y494448D02*
X1031273Y499041D01*
G01X1030213Y499481D02*
Y509093D01*
G01X1031273Y499041D02*
Y508653D01*
G01X1030213Y509093D02*
X1031681Y510561D01*
G01X1031273Y508653D02*
X1032741Y510121D01*
G01X1031681Y510561D02*
Y533775D01*
G01X1032741Y510121D02*
Y553539D01*
G01X1018820Y497991D02*
X1021940Y501111D01*
G01X1019880Y497551D02*
X1023000Y500671D01*
G01X1021940Y501111D02*
Y502941D01*
G01Y505667D02*
Y507497D01*
G01Y510223D02*
Y523560D01*
G01X1023000Y500671D02*
Y523120D01*
G01X1021940Y523560D02*
X1023393Y525013D01*
G01X1023000Y523120D02*
X1024453Y524573D01*
G01X1023393Y525013D02*
Y526843D01*
G01X1024453Y524573D02*
Y547252D01*
G01X1028207Y527983D02*
Y529813D01*
G01Y532539D02*
Y534369D01*
G01Y537095D02*
Y572588D01*
G01Y575314D02*
Y586351D01*
G01X1020680Y532962D02*
Y534792D01*
G01Y537518D02*
Y539348D01*
G01Y542074D02*
Y543904D01*
G01Y546630D02*
Y548460D01*
G01X1019620Y526640D02*
Y548900D01*
G01X1020680Y548460D02*
X1022600Y550380D01*
G01X1019620Y548900D02*
X1021540Y550820D01*
G01X1022600Y550380D02*
Y558300D01*
G01X1021540Y550820D02*
Y557860D01*
G01X1022600Y558300D02*
X1020680Y560220D01*
G01X1021540Y557860D02*
X1019620Y559780D01*
G01X1020680Y560220D02*
Y564199D01*
G01Y566925D02*
Y568809D01*
G01Y571427D02*
Y575053D01*
G01X1019620Y559780D02*
Y574613D01*
G01X1020680Y575053D02*
X1018276Y577457D01*
G01X1016981Y579189D02*
X1016544D01*
G01D02*
X1014561Y581172D01*
G01X1019620Y574613D02*
X1014121Y580112D01*
G01X1014561Y581172D02*
X1011070D01*
G01X1014121Y580112D02*
X1010630D01*
G01X1011070Y581172D02*
X1009421Y582821D01*
G01X1010630Y580112D02*
X1008361Y582381D01*
G01X1009421Y582821D02*
Y596658D01*
G01X1008361Y582381D02*
Y597098D01*
G01X1031681Y536501D02*
Y538331D01*
G01Y541057D02*
Y542887D01*
G01Y545613D02*
Y547443D01*
G01Y550169D02*
Y553099D01*
G01X1032741Y553539D02*
X1032300Y553980D01*
G01X1031681Y553099D02*
X1031240Y553540D01*
G01X1032300Y553980D02*
Y559600D01*
G01X1031240Y553540D02*
Y560040D01*
G01X1032300Y559600D02*
X1032633Y559933D01*
G01X1031240Y560040D02*
X1031573Y560373D01*
G01X1032633Y559933D02*
Y607229D01*
G01X1031573Y560373D02*
Y597677D01*
G01X1032633Y559933D02*
Y607229D01*
G01Y559933D02*
Y607229D01*
G01X1023393Y529569D02*
Y547692D01*
G01X1024453Y547252D02*
X1026400Y549199D01*
G01X1023393Y547692D02*
X1025340Y549639D01*
G01X1026400Y549199D02*
Y571100D01*
G01X1025340Y549639D02*
Y553991D01*
G01X1026400Y549199D02*
Y571100D01*
G01X1025340Y556717D02*
Y558547D01*
G01X1026400Y549199D02*
Y571100D01*
G01X1025340Y561273D02*
Y566104D01*
G01X1026400Y549199D02*
Y571100D01*
G01X1025340Y568830D02*
Y570660D01*
G01X1026400Y571100D02*
X1024700Y572800D01*
G01X1025340Y570660D02*
X1023640Y572360D01*
G01X1024700Y572800D02*
Y587869D01*
G01X1023640Y572360D02*
Y577847D01*
G01X1024700Y572800D02*
Y587869D01*
G01X1023640Y580573D02*
Y582403D01*
G01X1024700Y572800D02*
Y587869D01*
G01X1023640Y585129D02*
Y587429D01*
G01X1024700Y587869D02*
X1022109Y590460D01*
G01X1023640Y587429D02*
X1021669Y589400D01*
G01X1014200D02*
X1012978Y588178D01*
G01X1011918Y588618D02*
Y586506D01*
G01X1012978Y588178D02*
Y586609D01*
G01X1028207Y527983D02*
Y529813D01*
G01Y532539D02*
Y534369D01*
G01Y537095D02*
Y572588D01*
G01Y575314D02*
Y586351D01*
G01X1019620Y526640D02*
Y548900D01*
G01Y526640D02*
Y548900D01*
G01X1020680Y532962D02*
Y534792D01*
G01X1019620Y526640D02*
Y548900D01*
G01X1020680Y537518D02*
Y539348D01*
G01X1019620Y526640D02*
Y548900D01*
G01X1020680Y542074D02*
Y543904D01*
G01X1019620Y526640D02*
Y548900D01*
G01X1020680Y546630D02*
Y548460D01*
G01X1019620Y548900D02*
X1021540Y550820D01*
G01X1020680Y548460D02*
X1022600Y550380D01*
G01X1021540Y550820D02*
Y557860D01*
G01X1022600Y550380D02*
Y558300D01*
G01X1021540Y557860D02*
X1019620Y559780D01*
G01X1022600Y558300D02*
X1020680Y560220D01*
G01X1019620Y559780D02*
Y574613D01*
G01X1020680Y560220D02*
Y564199D01*
G01X1019620Y559780D02*
Y574613D01*
G01X1020680Y566925D02*
Y568809D01*
G01X1019620Y559780D02*
Y574613D01*
G01X1020680Y571427D02*
Y575053D01*
G01X1019620Y574613D02*
X1014121Y580112D01*
G01X1020680Y575053D02*
X1018276Y577457D01*
G01X1019620Y574613D02*
X1014121Y580112D01*
G01X1016981Y579189D02*
X1016544D01*
G01X1019620Y574613D02*
X1014121Y580112D01*
G01X1016544Y579189D02*
X1014561Y581172D01*
G01X1014121Y580112D02*
X1010630D01*
G01X1014561Y581172D02*
X1011070D01*
G01X1010630Y580112D02*
X1008361Y582381D01*
G01X1011070Y581172D02*
X1009421Y582821D01*
G01X1008361Y582381D02*
Y597098D01*
G01X1009421Y582821D02*
Y596658D01*
G01X1031681Y536501D02*
Y538331D01*
G01Y541057D02*
Y542887D01*
G01Y545613D02*
Y547443D01*
G01Y550169D02*
Y553099D01*
G01D02*
X1031240Y553540D01*
G01X1032741Y553539D02*
X1032300Y553980D01*
G01X1031240Y553540D02*
Y560040D01*
G01X1032300Y553980D02*
Y559600D01*
G01X1031240Y560040D02*
X1031573Y560373D01*
G01X1032300Y559600D02*
X1032633Y559933D01*
G01X1031573Y560373D02*
Y597677D01*
G01X1032633Y559933D02*
Y607229D01*
G01X1023393Y529569D02*
Y547692D01*
G01D02*
X1025340Y549639D01*
G01X1024453Y547252D02*
X1026400Y549199D01*
G01X1025340Y549639D02*
Y553991D01*
G01Y556717D02*
Y558547D01*
G01Y561273D02*
Y566104D01*
G01Y568830D02*
Y570660D01*
G01X1026400Y549199D02*
Y571100D01*
G01X1025340Y570660D02*
X1023640Y572360D01*
G01X1026400Y571100D02*
X1024700Y572800D01*
G01X1023640Y572360D02*
Y577847D01*
G01Y580573D02*
Y582403D01*
G01Y585129D02*
Y587429D01*
G01X1024700Y572800D02*
Y587869D01*
G01X1023640Y587429D02*
X1021669Y589400D01*
G01X1024700Y587869D02*
X1022109Y590460D01*
G01X1014200Y589400D02*
X1012978Y588178D01*
G01D02*
Y586609D01*
G01X1011918Y588618D02*
Y586506D01*
G01X1028207Y589077D02*
Y590907D01*
G01Y593633D02*
Y595463D01*
G01X1029267Y595903D02*
X1027377Y597793D01*
G01X1028207Y595463D02*
X1026937Y596733D01*
G01X1027377Y597793D02*
X1017133D01*
G01X1026937Y596733D02*
X1021160D01*
G01X1027377Y597793D02*
X1017133D01*
G01X1018648Y596733D02*
X1016693D01*
G01X1017133Y597793D02*
X1016521Y598405D01*
G01X1016693Y596733D02*
X1015461Y597965D01*
G01X1016521Y598405D02*
Y600397D01*
G01X1015461Y597965D02*
Y600837D01*
G01X1016521Y600397D02*
X1017133Y601009D01*
G01X1015461Y600837D02*
X1016693Y602069D01*
G01X1017133Y601009D02*
X1024212D01*
G01X1016693Y602069D02*
X1018631D01*
G01X1017133Y601009D02*
X1024212D01*
G01X1021141Y602069D02*
X1023772D01*
G01X1024212Y601009D02*
X1025894Y602691D01*
G01X1023772Y602069D02*
X1024834Y603131D01*
G01X1025894Y602691D02*
Y607117D01*
G01X1024834Y603131D02*
Y606677D01*
G01X1025894Y607117D02*
X1024082Y608929D01*
G01X1024834Y606677D02*
X1023642Y607869D01*
G01X1024082Y608929D02*
X1013471D01*
G01X1023642Y607869D02*
X1019562D01*
G01X1024082Y608929D02*
X1013471D01*
G01X1016908Y607869D02*
X1013911D01*
G01X1013471Y608929D02*
X1011926Y607384D01*
G01X1013911Y607869D02*
X1012986Y606944D01*
G01X1011926Y607384D02*
Y605714D01*
G01X1012986Y606944D02*
Y605801D01*
G01X1009421Y596658D02*
X1009921Y597158D01*
G01X1008361Y597098D02*
X1009481Y598218D01*
G01X1009921Y597158D02*
X1011220D01*
G01X1009481Y598218D02*
X1011660D01*
G01X1011220Y597158D02*
X1012705Y595673D01*
G01X1011660Y598218D02*
X1013765Y596113D01*
G01X1012705Y595673D02*
Y594775D01*
G01X1013765Y596113D02*
Y594796D01*
G01X1031573Y600403D02*
Y602233D01*
G01Y604959D02*
Y606789D01*
G01X1032633Y607229D02*
X1022820Y617042D01*
G01X1031573Y606789D02*
X1028824Y609538D01*
G01X1032633Y607229D02*
X1022820Y617042D01*
G01X1026896Y611466D02*
X1025602Y612760D01*
G01X1032633Y607229D02*
X1022820Y617042D01*
G01X1023674Y614688D02*
X1022380Y615982D01*
G01X1022820Y617042D02*
X1013528D01*
G01X1022380Y615982D02*
X1019461D01*
G01X1022820Y617042D02*
X1013528D01*
G01X1016879Y615982D02*
X1013968D01*
G01X1013528Y617042D02*
X1011820Y615334D01*
G01X1013968Y615982D02*
X1012880Y614894D01*
G01X1011820Y615334D02*
Y613236D01*
G01X1012880Y614894D02*
Y613535D01*
G01X1022109Y590460D02*
X1013760D01*
G01X1021669Y589400D02*
X1018990D01*
G01X1022109Y590460D02*
X1013760D01*
G01X1016264Y589400D02*
X1014200D01*
G01X1013760Y590460D02*
X1011918Y588618D01*
G01X1028207Y589077D02*
Y590907D01*
G01Y593633D02*
Y595463D01*
G01D02*
X1026937Y596733D01*
G01X1029267Y595903D02*
X1027377Y597793D01*
G01X1026937Y596733D02*
X1021160D01*
G01X1018648D02*
X1016693D01*
G01X1027377Y597793D02*
X1017133D01*
G01X1016693Y596733D02*
X1015461Y597965D01*
G01X1017133Y597793D02*
X1016521Y598405D01*
G01X1015461Y597965D02*
Y600837D01*
G01X1016521Y598405D02*
Y600397D01*
G01X1015461Y600837D02*
X1016693Y602069D01*
G01X1016521Y600397D02*
X1017133Y601009D01*
G01X1016693Y602069D02*
X1018631D01*
G01X1021141D02*
X1023772D01*
G01X1017133Y601009D02*
X1024212D01*
G01X1023772Y602069D02*
X1024834Y603131D01*
G01X1024212Y601009D02*
X1025894Y602691D01*
G01X1024834Y603131D02*
Y606677D01*
G01X1025894Y602691D02*
Y607117D01*
G01X1024834Y606677D02*
X1023642Y607869D01*
G01X1025894Y607117D02*
X1024082Y608929D01*
G01X1023642Y607869D02*
X1019562D01*
G01X1016908D02*
X1013911D01*
G01X1024082Y608929D02*
X1013471D01*
G01X1013911Y607869D02*
X1012986Y606944D01*
G01X1013471Y608929D02*
X1011926Y607384D01*
G01X1012986Y606944D02*
Y605801D01*
G01X1011926Y607384D02*
Y605714D01*
G01X1008361Y597098D02*
X1009481Y598218D01*
G01X1009421Y596658D02*
X1009921Y597158D01*
G01X1009481Y598218D02*
X1011660D01*
G01X1009921Y597158D02*
X1011220D01*
G01X1011660Y598218D02*
X1013765Y596113D01*
G01X1011220Y597158D02*
X1012705Y595673D01*
G01X1013765Y596113D02*
Y594796D01*
G01X1012705Y595673D02*
Y594775D01*
G01X1031573Y600403D02*
Y602233D01*
G01Y604959D02*
Y606789D01*
G01D02*
X1028824Y609538D01*
G01X1026896Y611466D02*
X1025602Y612760D01*
G01X1023674Y614688D02*
X1022380Y615982D01*
G01X1032633Y607229D02*
X1022820Y617042D01*
G01X1022380Y615982D02*
X1019461D01*
G01X1016879D02*
X1013968D01*
G01X1022820Y617042D02*
X1013528D01*
G01X1013968Y615982D02*
X1012880Y614894D01*
G01X1013528Y617042D02*
X1011820Y615334D01*
G01X1012880Y614894D02*
Y613535D01*
G01X1011820Y615334D02*
Y613236D01*
G01X1021669Y589400D02*
X1018990D01*
G01X1016264D02*
X1014200D01*
G01X1022109Y590460D02*
X1013760D01*
G01D02*
X1011918Y588618D01*
G01X1033600Y44800D02*
Y40460D01*
G01X1034660Y45240D02*
Y40020D01*
G01Y45240D02*
Y40020D01*
G01X1033600Y44800D02*
Y40460D01*
G01X1078240Y183575D02*
Y141960D01*
G01Y183575D02*
Y141960D01*
G01Y183575D02*
Y141960D01*
G01Y183575D02*
Y141960D01*
G01Y183575D02*
Y141960D01*
G01Y183575D02*
Y141960D01*
G01Y183575D02*
Y141960D01*
G01Y183575D02*
Y141960D01*
G01Y183575D02*
Y141960D01*
G01Y183575D02*
Y141960D01*
G01X1079300Y156950D02*
Y155550D01*
G01X1078240Y183575D02*
Y141960D01*
G01X1079300Y153650D02*
Y152550D01*
G01X1078240Y183575D02*
Y141960D01*
G01X1079300Y150650D02*
Y142400D01*
G01X1078240Y141960D02*
X1080778Y139422D01*
G01X1079300Y142400D02*
X1081218Y140482D01*
G01X1078240Y141960D02*
X1080778Y139422D01*
G01D02*
X1082520D01*
G01X1081218Y140482D02*
X1082080D01*
G01X1082520Y139422D02*
X1083469Y140371D01*
G01D02*
X1084329D01*
G01X1082080Y140482D02*
X1083029Y141431D01*
G01X1083469Y140371D02*
X1084329D01*
G01X1083029Y141431D02*
X1084769D01*
G01X1084329Y140371D02*
X1085317Y139383D01*
G01X1084769Y141431D02*
X1086377Y139823D01*
G01X1085317Y139383D02*
Y138523D01*
G01X1086377Y139823D02*
Y138083D01*
G01X1085317Y138523D02*
X1084368Y137574D01*
G01X1086377Y138083D02*
X1085428Y137134D01*
G01X1084368Y137574D02*
Y135832D01*
G01X1085428Y137134D02*
Y136272D01*
G01X1084368Y135832D02*
X1085972Y134228D01*
G01X1085428Y136272D02*
X1086412Y135288D01*
G01X1085972Y134228D02*
X1087714D01*
G01X1086412Y135288D02*
X1087274D01*
G01X1087714Y134228D02*
X1088663Y135177D01*
G01X1087274Y135288D02*
X1088223Y136237D01*
G01X1088663Y135177D02*
X1089523D01*
G01X1088223Y136237D02*
X1089963D01*
G01X1089523Y135177D02*
X1090511Y134189D01*
G01X1089963Y136237D02*
X1091571Y134629D01*
G01X1090511Y134189D02*
Y133329D01*
G01X1091571Y134629D02*
Y132889D01*
G01X1090511Y133329D02*
X1089562Y132380D01*
G01X1091571Y132889D02*
X1090622Y131940D01*
G01X1089562Y132380D02*
Y130638D01*
G01X1090622Y131940D02*
Y131078D01*
G01X1089562Y130638D02*
X1092530Y127670D01*
G01X1090622Y131078D02*
X1092970Y128730D01*
G01X1092530Y127670D02*
X1094272D01*
G01X1092970Y128730D02*
X1093832D01*
G01X1094272Y127670D02*
X1094971Y128369D01*
G01X1093832Y128730D02*
X1094531Y129429D01*
G01X1094971Y128369D02*
X1095831D01*
G01X1094531Y129429D02*
X1096271D01*
G01X1094971Y128369D02*
X1095831D01*
G01X1083223Y185287D02*
Y148376D01*
G01X1082163Y185287D02*
Y147936D01*
G01X1083223Y148376D02*
X1115339Y116260D01*
G01X1082163Y147936D02*
X1114899Y115200D01*
G01X1079300Y156950D02*
Y155550D01*
G01Y153650D02*
Y152550D01*
G01Y150650D02*
Y142400D01*
G01X1078240Y183575D02*
Y141960D01*
G01X1079300Y142400D02*
X1081218Y140482D01*
G01D02*
X1082080D01*
G01X1078240Y141960D02*
X1080778Y139422D01*
G01X1081218Y140482D02*
X1082080D01*
G01X1080778Y139422D02*
X1082520D01*
G01X1082080Y140482D02*
X1083029Y141431D01*
G01X1082520Y139422D02*
X1083469Y140371D01*
G01X1082080Y140482D02*
X1083029Y141431D01*
G01D02*
X1084769D01*
G01X1083469Y140371D02*
X1084329D01*
G01X1084769Y141431D02*
X1086377Y139823D01*
G01X1084329Y140371D02*
X1085317Y139383D01*
G01X1086377Y139823D02*
Y138083D01*
G01X1085317Y139383D02*
Y138523D01*
G01X1086377Y138083D02*
X1085428Y137134D01*
G01X1085317Y138523D02*
X1084368Y137574D01*
G01X1085428Y137134D02*
Y136272D01*
G01X1084368Y137574D02*
Y135832D01*
G01X1085428Y136272D02*
X1086412Y135288D01*
G01X1084368Y135832D02*
X1085972Y134228D01*
G01X1086412Y135288D02*
X1087274D01*
G01X1085972Y134228D02*
X1087714D01*
G01X1087274Y135288D02*
X1088223Y136237D01*
G01X1087714Y134228D02*
X1088663Y135177D01*
G01X1088223Y136237D02*
X1089963D01*
G01X1088663Y135177D02*
X1089523D01*
G01X1089963Y136237D02*
X1091571Y134629D01*
G01X1089523Y135177D02*
X1090511Y134189D01*
G01X1091571Y134629D02*
Y132889D01*
G01X1090511Y134189D02*
Y133329D01*
G01X1091571Y132889D02*
X1090622Y131940D01*
G01X1090511Y133329D02*
X1089562Y132380D01*
G01X1090622Y131940D02*
Y131078D01*
G01X1089562Y132380D02*
Y130638D01*
G01X1090622Y131078D02*
X1092970Y128730D01*
G01X1089562Y130638D02*
X1092530Y127670D01*
G01X1092970Y128730D02*
X1093832D01*
G01X1092530Y127670D02*
X1094272D01*
G01X1093832Y128730D02*
X1094531Y129429D01*
G01X1094272Y127670D02*
X1094971Y128369D01*
G01X1094531Y129429D02*
X1096271D01*
G01X1094971Y128369D02*
X1095831D01*
G01X1082163Y185287D02*
Y147936D01*
G01X1083223Y185287D02*
Y148376D01*
G01X1082163Y147936D02*
X1114899Y115200D01*
G01X1083223Y148376D02*
X1115339Y116260D01*
G01X1078240Y183575D02*
Y141960D01*
G01Y183575D02*
Y141960D01*
G01Y183575D02*
Y141960D01*
G01Y183575D02*
Y141960D01*
G01Y183575D02*
Y141960D01*
G01Y183575D02*
Y141960D01*
G01Y183575D02*
Y141960D01*
G01Y183575D02*
Y141960D01*
G01Y183575D02*
Y141960D01*
G01Y183575D02*
Y141960D01*
G01X1079300Y156950D02*
Y155550D01*
G01X1078240Y183575D02*
Y141960D01*
G01X1079300Y153650D02*
Y152550D01*
G01X1078240Y183575D02*
Y141960D01*
G01X1079300Y150650D02*
Y142400D01*
G01X1078240Y141960D02*
X1080778Y139422D01*
G01X1079300Y142400D02*
X1081218Y140482D01*
G01X1078240Y141960D02*
X1080778Y139422D01*
G01D02*
X1082520D01*
G01X1081218Y140482D02*
X1082080D01*
G01X1082520Y139422D02*
X1083469Y140371D01*
G01D02*
X1084329D01*
G01X1082080Y140482D02*
X1083029Y141431D01*
G01X1083469Y140371D02*
X1084329D01*
G01X1083029Y141431D02*
X1084769D01*
G01X1084329Y140371D02*
X1085317Y139383D01*
G01X1084769Y141431D02*
X1086377Y139823D01*
G01X1085317Y139383D02*
Y138523D01*
G01X1086377Y139823D02*
Y138083D01*
G01X1085317Y138523D02*
X1084368Y137574D01*
G01X1086377Y138083D02*
X1085428Y137134D01*
G01X1084368Y137574D02*
Y135832D01*
G01X1085428Y137134D02*
Y136272D01*
G01X1084368Y135832D02*
X1085972Y134228D01*
G01X1085428Y136272D02*
X1086412Y135288D01*
G01X1085972Y134228D02*
X1087714D01*
G01X1086412Y135288D02*
X1087274D01*
G01X1087714Y134228D02*
X1088663Y135177D01*
G01X1087274Y135288D02*
X1088223Y136237D01*
G01X1088663Y135177D02*
X1089523D01*
G01X1088223Y136237D02*
X1089963D01*
G01X1089523Y135177D02*
X1090511Y134189D01*
G01X1089963Y136237D02*
X1091571Y134629D01*
G01X1090511Y134189D02*
Y133329D01*
G01X1091571Y134629D02*
Y132889D01*
G01X1090511Y133329D02*
X1089562Y132380D01*
G01X1091571Y132889D02*
X1090622Y131940D01*
G01X1089562Y132380D02*
Y130638D01*
G01X1090622Y131940D02*
Y131078D01*
G01X1089562Y130638D02*
X1092530Y127670D01*
G01X1090622Y131078D02*
X1092970Y128730D01*
G01X1092530Y127670D02*
X1094272D01*
G01X1092970Y128730D02*
X1093832D01*
G01X1094272Y127670D02*
X1094971Y128369D01*
G01X1093832Y128730D02*
X1094531Y129429D01*
G01X1094971Y128369D02*
X1095831D01*
G01X1094531Y129429D02*
X1096271D01*
G01X1094971Y128369D02*
X1095831D01*
G01X1083223Y185287D02*
Y148376D01*
G01X1082163Y185287D02*
Y147936D01*
G01X1083223Y148376D02*
X1115339Y116260D01*
G01X1082163Y147936D02*
X1114899Y115200D01*
G01X1079300Y156950D02*
Y155550D01*
G01Y153650D02*
Y152550D01*
G01Y150650D02*
Y142400D01*
G01X1078240Y183575D02*
Y141960D01*
G01X1079300Y142400D02*
X1081218Y140482D01*
G01D02*
X1082080D01*
G01X1078240Y141960D02*
X1080778Y139422D01*
G01X1081218Y140482D02*
X1082080D01*
G01X1080778Y139422D02*
X1082520D01*
G01X1082080Y140482D02*
X1083029Y141431D01*
G01X1082520Y139422D02*
X1083469Y140371D01*
G01X1082080Y140482D02*
X1083029Y141431D01*
G01D02*
X1084769D01*
G01X1083469Y140371D02*
X1084329D01*
G01X1084769Y141431D02*
X1086377Y139823D01*
G01X1084329Y140371D02*
X1085317Y139383D01*
G01X1086377Y139823D02*
Y138083D01*
G01X1085317Y139383D02*
Y138523D01*
G01X1086377Y138083D02*
X1085428Y137134D01*
G01X1085317Y138523D02*
X1084368Y137574D01*
G01X1085428Y137134D02*
Y136272D01*
G01X1084368Y137574D02*
Y135832D01*
G01X1085428Y136272D02*
X1086412Y135288D01*
G01X1084368Y135832D02*
X1085972Y134228D01*
G01X1086412Y135288D02*
X1087274D01*
G01X1085972Y134228D02*
X1087714D01*
G01X1087274Y135288D02*
X1088223Y136237D01*
G01X1087714Y134228D02*
X1088663Y135177D01*
G01X1088223Y136237D02*
X1089963D01*
G01X1088663Y135177D02*
X1089523D01*
G01X1089963Y136237D02*
X1091571Y134629D01*
G01X1089523Y135177D02*
X1090511Y134189D01*
G01X1091571Y134629D02*
Y132889D01*
G01X1090511Y134189D02*
Y133329D01*
G01X1091571Y132889D02*
X1090622Y131940D01*
G01X1090511Y133329D02*
X1089562Y132380D01*
G01X1090622Y131940D02*
Y131078D01*
G01X1089562Y132380D02*
Y130638D01*
G01X1090622Y131078D02*
X1092970Y128730D01*
G01X1089562Y130638D02*
X1092530Y127670D01*
G01X1092970Y128730D02*
X1093832D01*
G01X1092530Y127670D02*
X1094272D01*
G01X1093832Y128730D02*
X1094531Y129429D01*
G01X1094272Y127670D02*
X1094971Y128369D01*
G01X1094531Y129429D02*
X1096271D01*
G01X1094971Y128369D02*
X1095831D01*
G01X1082163Y185287D02*
Y147936D01*
G01X1083223Y185287D02*
Y148376D01*
G01X1082163Y147936D02*
X1114899Y115200D01*
G01X1083223Y148376D02*
X1115339Y116260D01*
G01X1079005Y185287D02*
Y184340D01*
G01X1080065Y185287D02*
Y183900D01*
G01X1079005Y184340D02*
X1078240Y183575D01*
G01X1080065Y183900D02*
X1079300Y183135D01*
G01D02*
Y182050D01*
G01Y180150D02*
Y179150D01*
G01Y177250D02*
Y176250D01*
G01Y174350D02*
Y173350D01*
G01Y171450D02*
Y170450D01*
G01Y168550D02*
Y167550D01*
G01Y165650D02*
Y164650D01*
G01Y162750D02*
Y161752D01*
G01Y159850D02*
Y158850D01*
G01X1080065Y185287D02*
Y183900D01*
G01X1079005Y185287D02*
Y184340D01*
G01X1080065Y183900D02*
X1079300Y183135D01*
G01X1079005Y184340D02*
X1078240Y183575D01*
G01X1079300Y183135D02*
Y182050D01*
G01Y180150D02*
Y179150D01*
G01Y177250D02*
Y176250D01*
G01Y174350D02*
Y173350D01*
G01Y171450D02*
Y170450D01*
G01Y168550D02*
Y167550D01*
G01Y165650D02*
Y164650D01*
G01Y162750D02*
Y161752D01*
G01Y159850D02*
Y158850D01*
G01X1079005Y185287D02*
Y184340D01*
G01X1080065Y185287D02*
Y183900D01*
G01X1079005Y184340D02*
X1078240Y183575D01*
G01X1080065Y183900D02*
X1079300Y183135D01*
G01D02*
Y182050D01*
G01Y180150D02*
Y179150D01*
G01Y177250D02*
Y176250D01*
G01Y174350D02*
Y173350D01*
G01Y171450D02*
Y170450D01*
G01Y168550D02*
Y167550D01*
G01Y165650D02*
Y164650D01*
G01Y162750D02*
Y161752D01*
G01Y159850D02*
Y158850D01*
G01X1080065Y185287D02*
Y183900D01*
G01X1079005Y185287D02*
Y184340D01*
G01X1080065Y183900D02*
X1079300Y183135D01*
G01X1079005Y184340D02*
X1078240Y183575D01*
G01X1079300Y183135D02*
Y182050D01*
G01Y180150D02*
Y179150D01*
G01Y177250D02*
Y176250D01*
G01Y174350D02*
Y173350D01*
G01Y171450D02*
Y170450D01*
G01Y168550D02*
Y167550D01*
G01Y165650D02*
Y164650D01*
G01Y162750D02*
Y161752D01*
G01Y159850D02*
Y158850D01*
G01X1081251Y418187D02*
Y454919D01*
G01X1082311Y418187D02*
Y454479D01*
G01X1081251Y454919D02*
X1119024Y492692D01*
G01X1082311Y454479D02*
X1119464Y491632D01*
G01X1089511Y418487D02*
Y444592D01*
G01X1088451Y418487D02*
Y444152D01*
G01X1089511Y444592D02*
X1088281Y445822D01*
G01X1088451Y444152D02*
X1087841Y444762D01*
G01X1089511Y444592D02*
X1088281Y445822D01*
G01D02*
X1087109D01*
G01X1087841Y444762D02*
X1086669D01*
G01X1087109Y445822D02*
X1086521Y446410D01*
G01X1086669Y444762D02*
X1085461Y445970D01*
G01X1086521Y446410D02*
Y447800D01*
G01X1085461Y445970D02*
Y448240D01*
G01X1086521Y447800D02*
X1087153Y448432D01*
G01X1085461Y448240D02*
X1086713Y449492D01*
G01X1087153Y448432D02*
X1088281D01*
G01D02*
X1089511Y449662D01*
G01X1086713Y449492D02*
X1087841D01*
G01X1088281Y448432D02*
X1089511Y449662D01*
G01X1087841Y449492D02*
X1088451Y450102D01*
G01X1089511Y449662D02*
Y455935D01*
G01X1088451Y450102D02*
Y456375D01*
G01X1089511Y455935D02*
X1121040Y487464D01*
G01X1088451Y456375D02*
X1120600Y488524D01*
G01X1082311Y418187D02*
Y454479D01*
G01X1081251Y418187D02*
Y454919D01*
G01X1082311Y454479D02*
X1119464Y491632D01*
G01X1081251Y454919D02*
X1119024Y492692D01*
G01X1088451Y418487D02*
Y444152D01*
G01X1089511Y418487D02*
Y444592D01*
G01X1088451Y444152D02*
X1087841Y444762D01*
G01D02*
X1086669D01*
G01X1089511Y444592D02*
X1088281Y445822D01*
G01X1087841Y444762D02*
X1086669D01*
G01X1088281Y445822D02*
X1087109D01*
G01X1086669Y444762D02*
X1085461Y445970D01*
G01X1087109Y445822D02*
X1086521Y446410D01*
G01X1085461Y445970D02*
Y448240D01*
G01X1086521Y446410D02*
Y447800D01*
G01X1085461Y448240D02*
X1086713Y449492D01*
G01X1086521Y447800D02*
X1087153Y448432D01*
G01X1086713Y449492D02*
X1087841D01*
G01X1087153Y448432D02*
X1088281D01*
G01X1086713Y449492D02*
X1087841D01*
G01D02*
X1088451Y450102D01*
G01X1088281Y448432D02*
X1089511Y449662D01*
G01X1088451Y450102D02*
Y456375D01*
G01X1089511Y449662D02*
Y455935D01*
G01X1088451Y456375D02*
X1120600Y488524D01*
G01X1089511Y455935D02*
X1121040Y487464D01*
G01X1081251Y418187D02*
Y454919D01*
G01X1082311Y418187D02*
Y454479D01*
G01X1081251Y454919D02*
X1119024Y492692D01*
G01X1082311Y454479D02*
X1119464Y491632D01*
G01X1089511Y418487D02*
Y444592D01*
G01X1088451Y418487D02*
Y444152D01*
G01X1089511Y444592D02*
X1088281Y445822D01*
G01X1088451Y444152D02*
X1087841Y444762D01*
G01X1089511Y444592D02*
X1088281Y445822D01*
G01D02*
X1087109D01*
G01X1087841Y444762D02*
X1086669D01*
G01X1087109Y445822D02*
X1086521Y446410D01*
G01X1086669Y444762D02*
X1085461Y445970D01*
G01X1086521Y446410D02*
Y447800D01*
G01X1085461Y445970D02*
Y448240D01*
G01X1086521Y447800D02*
X1087153Y448432D01*
G01X1085461Y448240D02*
X1086713Y449492D01*
G01X1087153Y448432D02*
X1088281D01*
G01D02*
X1089511Y449662D01*
G01X1086713Y449492D02*
X1087841D01*
G01X1088281Y448432D02*
X1089511Y449662D01*
G01X1087841Y449492D02*
X1088451Y450102D01*
G01X1089511Y449662D02*
Y455935D01*
G01X1088451Y450102D02*
Y456375D01*
G01X1089511Y455935D02*
X1121040Y487464D01*
G01X1088451Y456375D02*
X1120600Y488524D01*
G01X1082311Y418187D02*
Y454479D01*
G01X1081251Y418187D02*
Y454919D01*
G01X1082311Y454479D02*
X1119464Y491632D01*
G01X1081251Y454919D02*
X1119024Y492692D01*
G01X1088451Y418487D02*
Y444152D01*
G01X1089511Y418487D02*
Y444592D01*
G01X1088451Y444152D02*
X1087841Y444762D01*
G01D02*
X1086669D01*
G01X1089511Y444592D02*
X1088281Y445822D01*
G01X1087841Y444762D02*
X1086669D01*
G01X1088281Y445822D02*
X1087109D01*
G01X1086669Y444762D02*
X1085461Y445970D01*
G01X1087109Y445822D02*
X1086521Y446410D01*
G01X1085461Y445970D02*
Y448240D01*
G01X1086521Y446410D02*
Y447800D01*
G01X1085461Y448240D02*
X1086713Y449492D01*
G01X1086521Y447800D02*
X1087153Y448432D01*
G01X1086713Y449492D02*
X1087841D01*
G01X1087153Y448432D02*
X1088281D01*
G01X1086713Y449492D02*
X1087841D01*
G01D02*
X1088451Y450102D01*
G01X1088281Y448432D02*
X1089511Y449662D01*
G01X1088451Y450102D02*
Y456375D01*
G01X1089511Y449662D02*
Y455935D01*
G01X1088451Y456375D02*
X1120600Y488524D01*
G01X1089511Y455935D02*
X1121040Y487464D01*
G01X1152249Y87300D02*
X1153198Y86351D01*
G01X1151152Y89900D02*
X1154258Y86794D01*
G01X1153198Y86351D02*
Y83820D01*
G01Y79680D02*
Y78720D01*
G01Y74380D02*
Y71091D01*
G01X1154258Y86794D02*
Y70648D01*
G01X1153198Y71091D02*
X1152487Y70380D01*
G01D02*
X1151971D01*
G01X1154258Y70648D02*
X1152930Y69320D01*
G01X1152487Y70380D02*
X1151971D01*
G01X1152930Y69320D02*
X1151948D01*
G01X1149178Y99190D02*
Y89274D01*
G01Y99190D02*
Y89274D01*
G01X1156252Y90114D02*
X1159444Y86922D01*
G01X1156252Y87515D02*
X1157350D01*
G01X1156252Y90114D02*
X1159444Y86922D01*
G01Y71532D02*
X1156252Y68340D01*
G01X1154498Y97234D02*
Y89268D01*
G01X1151152Y89900D02*
X1154258Y86794D01*
G01X1152249Y87300D02*
X1153198Y86351D01*
G01X1154258Y86794D02*
Y70648D01*
G01X1153198Y86351D02*
Y83820D01*
G01X1154258Y86794D02*
Y70648D01*
G01X1153198Y79680D02*
Y78720D01*
G01X1154258Y86794D02*
Y70648D01*
G01X1153198Y74380D02*
Y71091D01*
G01X1154258Y70648D02*
X1152930Y69320D01*
G01X1153198Y71091D02*
X1152487Y70380D01*
G01X1154258Y70648D02*
X1152930Y69320D01*
G01D02*
X1151948D01*
G01X1152487Y70380D02*
X1151971D01*
G01X1149178Y99190D02*
Y89274D01*
G01X1156252Y87515D02*
X1157350D01*
G01X1156252Y90114D02*
X1159444Y86922D01*
G01Y71532D02*
X1156252Y68340D01*
G01X1154498Y97234D02*
Y89268D01*
G01X1115439Y87300D02*
X1116386Y86353D01*
G01X1114340Y89900D02*
X1117446Y86794D01*
G01X1116386Y86353D02*
Y83820D01*
G01Y79680D02*
Y78720D01*
G01Y74380D02*
Y71091D01*
G01X1117446Y86794D02*
Y70648D01*
G01X1116386Y71091D02*
X1115675Y70380D01*
G01X1117446Y70648D02*
X1116118Y69320D01*
G01X1115675Y70380D02*
X1115159D01*
G01X1116118Y69320D02*
X1115136D01*
G01X1152249Y87300D02*
X1153198Y86351D01*
G01X1151152Y89900D02*
X1154258Y86794D01*
G01X1153198Y86351D02*
Y83820D01*
G01Y79680D02*
Y78720D01*
G01Y74380D02*
Y71091D01*
G01X1154258Y86794D02*
Y70648D01*
G01X1153198Y71091D02*
X1152487Y70380D01*
G01D02*
X1151971D01*
G01X1154258Y70648D02*
X1152930Y69320D01*
G01X1152487Y70380D02*
X1151971D01*
G01X1152930Y69320D02*
X1151948D01*
G01X1149178Y99190D02*
Y89274D01*
G01Y99190D02*
Y89274D01*
G01X1119440Y90114D02*
X1122632Y86922D01*
G01X1119440Y87515D02*
X1120538D01*
G01X1119440Y90114D02*
X1122632Y86922D01*
G01X1120538Y87515D02*
X1121572Y86481D01*
G01X1122632Y86922D02*
Y71532D01*
G01X1121572Y86481D02*
Y83706D01*
G01X1122632Y86922D02*
Y71532D01*
G01X1121572Y79880D02*
Y78507D01*
G01X1122632Y86922D02*
Y71532D01*
G01X1121572Y74593D02*
Y71972D01*
G01X1122632Y71532D02*
X1119440Y68340D01*
G01X1121572Y71972D02*
X1120549Y70949D01*
G01X1156252Y90114D02*
X1159444Y86922D01*
G01X1156252Y87515D02*
X1157350D01*
G01X1156252Y90114D02*
X1159444Y86922D01*
G01Y71532D02*
X1156252Y68340D01*
G01X1154498Y97234D02*
Y89268D01*
G01X1114340Y89900D02*
X1117446Y86794D01*
G01X1115439Y87300D02*
X1116386Y86353D01*
G01X1117446Y86794D02*
Y70648D01*
G01X1116386Y86353D02*
Y83820D01*
G01X1117446Y86794D02*
Y70648D01*
G01X1116386Y79680D02*
Y78720D01*
G01X1117446Y86794D02*
Y70648D01*
G01X1116386Y74380D02*
Y71091D01*
G01X1117446Y70648D02*
X1116118Y69320D01*
G01X1116386Y71091D02*
X1115675Y70380D01*
G01X1116118Y69320D02*
X1115136D01*
G01X1115675Y70380D02*
X1115159D01*
G01X1151152Y89900D02*
X1154258Y86794D01*
G01X1152249Y87300D02*
X1153198Y86351D01*
G01X1154258Y86794D02*
Y70648D01*
G01X1153198Y86351D02*
Y83820D01*
G01X1154258Y86794D02*
Y70648D01*
G01X1153198Y79680D02*
Y78720D01*
G01X1154258Y86794D02*
Y70648D01*
G01X1153198Y74380D02*
Y71091D01*
G01X1154258Y70648D02*
X1152930Y69320D01*
G01X1153198Y71091D02*
X1152487Y70380D01*
G01X1154258Y70648D02*
X1152930Y69320D01*
G01D02*
X1151948D01*
G01X1152487Y70380D02*
X1151971D01*
G01X1149178Y99190D02*
Y89274D01*
G01X1119440Y87515D02*
X1120538D01*
G01D02*
X1121572Y86481D01*
G01X1119440Y90114D02*
X1122632Y86922D01*
G01X1121572Y86481D02*
Y83706D01*
G01Y79880D02*
Y78507D01*
G01Y74593D02*
Y71972D01*
G01X1122632Y86922D02*
Y71532D01*
G01X1121572Y71972D02*
X1120549Y70949D01*
G01X1122632Y71532D02*
X1119440Y68340D01*
G01X1156252Y87515D02*
X1157350D01*
G01X1156252Y90114D02*
X1159444Y86922D01*
G01Y71532D02*
X1156252Y68340D01*
G01X1154498Y97234D02*
Y89268D01*
G01X1095831Y128369D02*
X1096819Y127381D01*
G01X1096271Y129429D02*
X1097879Y127821D01*
G01X1096819Y127381D02*
Y126521D01*
G01X1097879Y127821D02*
Y126081D01*
G01X1096819Y126521D02*
X1096120Y125822D01*
G01X1097879Y126081D02*
X1097180Y125382D01*
G01X1096120Y125822D02*
Y124080D01*
G01X1097180Y125382D02*
Y124520D01*
G01X1096120Y124080D02*
X1097724Y122476D01*
G01X1097180Y124520D02*
X1098164Y123536D01*
G01X1097724Y122476D02*
X1099466D01*
G01X1098164Y123536D02*
X1099026D01*
G01X1099466Y122476D02*
X1100165Y123175D01*
G01X1099026Y123536D02*
X1099725Y124235D01*
G01X1100165Y123175D02*
X1101025D01*
G01X1099725Y124235D02*
X1101465D01*
G01X1101025Y123175D02*
X1102013Y122187D01*
G01X1101465Y124235D02*
X1103073Y122627D01*
G01X1102013Y122187D02*
Y121327D01*
G01X1103073Y122627D02*
Y120887D01*
G01X1102013Y121327D02*
X1101314Y120628D01*
G01X1103073Y120887D02*
X1102374Y120188D01*
G01X1101314Y120628D02*
Y118886D01*
G01X1102374Y120188D02*
Y119326D01*
G01X1101314Y118886D02*
X1111600Y108600D01*
G01X1102374Y119326D02*
X1112040Y109660D01*
G01X1111600Y108600D02*
X1116140D01*
G01X1112040Y109660D02*
X1115700D01*
G01X1116140Y108600D02*
X1117180Y109640D01*
G01X1115700Y109660D02*
X1116740Y110700D01*
G01X1117180Y109640D02*
X1123320D01*
G01X1116740Y110700D02*
X1123760D01*
G01X1123320Y109640D02*
X1124360Y108600D01*
G01X1123760Y110700D02*
X1124800Y109660D01*
G01X1124360Y108600D02*
X1129301D01*
G01X1124800Y109660D02*
X1129741D01*
G01X1129301Y108600D02*
X1136601Y101300D01*
G01X1129741Y109660D02*
X1131378Y108023D01*
G01X1129301Y108600D02*
X1136601Y101300D01*
G01X1132723Y106678D02*
X1137041Y102360D01*
G01X1136601Y101300D02*
X1147068D01*
G01X1137041Y102360D02*
X1139550D01*
G01X1136601Y101300D02*
X1147068D01*
G01X1141450Y102360D02*
X1147508D01*
G01X1147068Y101300D02*
X1149178Y99190D01*
G01X1147508Y102360D02*
X1150238Y99630D01*
G01D02*
Y97800D01*
G01Y95900D02*
Y94900D01*
G01X1115339Y116260D02*
X1152269D01*
G01X1114899Y115200D02*
X1151829D01*
G01X1152269Y116260D02*
X1154180Y114349D01*
G01X1151829Y115200D02*
X1153120Y113909D01*
G01X1154180Y114349D02*
Y102220D01*
G01Y99980D02*
Y99052D01*
G01X1153120Y113909D02*
Y98612D01*
G01X1154180Y99052D02*
X1155558Y97674D01*
G01X1153120Y98612D02*
X1154498Y97234D01*
G01X1155558Y97674D02*
Y95542D01*
G01X1096271Y129429D02*
X1097879Y127821D01*
G01X1096271Y129429D02*
X1097879Y127821D01*
G01X1095831Y128369D02*
X1096819Y127381D01*
G01X1097879Y127821D02*
Y126081D01*
G01X1096819Y127381D02*
Y126521D01*
G01X1097879Y126081D02*
X1097180Y125382D01*
G01X1096819Y126521D02*
X1096120Y125822D01*
G01X1097180Y125382D02*
Y124520D01*
G01X1096120Y125822D02*
Y124080D01*
G01X1097180Y124520D02*
X1098164Y123536D01*
G01X1096120Y124080D02*
X1097724Y122476D01*
G01X1098164Y123536D02*
X1099026D01*
G01X1097724Y122476D02*
X1099466D01*
G01X1099026Y123536D02*
X1099725Y124235D01*
G01X1099466Y122476D02*
X1100165Y123175D01*
G01X1099725Y124235D02*
X1101465D01*
G01X1100165Y123175D02*
X1101025D01*
G01X1101465Y124235D02*
X1103073Y122627D01*
G01X1101025Y123175D02*
X1102013Y122187D01*
G01X1103073Y122627D02*
Y120887D01*
G01X1102013Y122187D02*
Y121327D01*
G01X1103073Y120887D02*
X1102374Y120188D01*
G01X1102013Y121327D02*
X1101314Y120628D01*
G01X1102374Y120188D02*
Y119326D01*
G01X1101314Y120628D02*
Y118886D01*
G01X1102374Y119326D02*
X1112040Y109660D01*
G01X1101314Y118886D02*
X1111600Y108600D01*
G01X1112040Y109660D02*
X1115700D01*
G01X1111600Y108600D02*
X1116140D01*
G01X1115700Y109660D02*
X1116740Y110700D01*
G01X1116140Y108600D02*
X1117180Y109640D01*
G01X1116740Y110700D02*
X1123760D01*
G01X1117180Y109640D02*
X1123320D01*
G01X1123760Y110700D02*
X1124800Y109660D01*
G01X1123320Y109640D02*
X1124360Y108600D01*
G01X1124800Y109660D02*
X1129741D01*
G01X1124360Y108600D02*
X1129301D01*
G01X1129741Y109660D02*
X1131378Y108023D01*
G01X1132723Y106678D02*
X1137041Y102360D01*
G01X1129301Y108600D02*
X1136601Y101300D01*
G01X1137041Y102360D02*
X1139550D01*
G01X1141450D02*
X1147508D01*
G01X1136601Y101300D02*
X1147068D01*
G01X1147508Y102360D02*
X1150238Y99630D01*
G01X1147068Y101300D02*
X1149178Y99190D01*
G01X1150238Y99630D02*
Y97800D01*
G01Y95900D02*
Y94900D01*
G01X1114899Y115200D02*
X1151829D01*
G01X1115339Y116260D02*
X1152269D01*
G01X1151829Y115200D02*
X1153120Y113909D01*
G01X1152269Y116260D02*
X1154180Y114349D01*
G01X1153120Y113909D02*
Y98612D01*
G01X1154180Y114349D02*
Y102220D01*
G01X1153120Y113909D02*
Y98612D01*
G01X1154180Y99980D02*
Y99052D01*
G01X1153120Y98612D02*
X1154498Y97234D01*
G01X1154180Y99052D02*
X1155558Y97674D01*
G01D02*
Y95542D01*
G01X1095831Y128369D02*
X1096819Y127381D01*
G01X1096271Y129429D02*
X1097879Y127821D01*
G01X1096819Y127381D02*
Y126521D01*
G01X1097879Y127821D02*
Y126081D01*
G01X1096819Y126521D02*
X1096120Y125822D01*
G01X1097879Y126081D02*
X1097180Y125382D01*
G01X1096120Y125822D02*
Y124080D01*
G01X1097180Y125382D02*
Y124520D01*
G01X1096120Y124080D02*
X1097724Y122476D01*
G01X1097180Y124520D02*
X1098164Y123536D01*
G01X1097724Y122476D02*
X1099466D01*
G01X1098164Y123536D02*
X1099026D01*
G01X1099466Y122476D02*
X1100165Y123175D01*
G01X1099026Y123536D02*
X1099725Y124235D01*
G01X1100165Y123175D02*
X1101025D01*
G01X1099725Y124235D02*
X1101465D01*
G01X1101025Y123175D02*
X1102013Y122187D01*
G01X1101465Y124235D02*
X1103073Y122627D01*
G01X1102013Y122187D02*
Y121327D01*
G01X1103073Y122627D02*
Y120887D01*
G01X1102013Y121327D02*
X1101314Y120628D01*
G01X1103073Y120887D02*
X1102374Y120188D01*
G01X1101314Y120628D02*
Y118886D01*
G01X1102374Y120188D02*
Y119326D01*
G01X1101314Y118886D02*
X1111600Y108600D01*
G01X1102374Y119326D02*
X1112040Y109660D01*
G01X1111600Y108600D02*
X1116140D01*
G01X1112040Y109660D02*
X1115700D01*
G01X1116140Y108600D02*
X1117180Y109640D01*
G01X1115700Y109660D02*
X1116740Y110700D01*
G01X1117180Y109640D02*
X1123320D01*
G01X1116740Y110700D02*
X1123760D01*
G01X1123320Y109640D02*
X1124360Y108600D01*
G01X1123760Y110700D02*
X1124800Y109660D01*
G01X1124360Y108600D02*
X1129301D01*
G01X1124800Y109660D02*
X1129741D01*
G01X1129301Y108600D02*
X1136601Y101300D01*
G01X1129741Y109660D02*
X1131378Y108023D01*
G01X1129301Y108600D02*
X1136601Y101300D01*
G01X1132723Y106678D02*
X1137041Y102360D01*
G01X1136601Y101300D02*
X1147068D01*
G01X1137041Y102360D02*
X1139550D01*
G01X1136601Y101300D02*
X1147068D01*
G01X1141450Y102360D02*
X1147508D01*
G01X1147068Y101300D02*
X1149178Y99190D01*
G01X1147508Y102360D02*
X1150238Y99630D01*
G01D02*
Y97800D01*
G01Y95900D02*
Y94900D01*
G01X1115339Y116260D02*
X1152269D01*
G01X1114899Y115200D02*
X1151829D01*
G01X1152269Y116260D02*
X1154180Y114349D01*
G01X1151829Y115200D02*
X1153120Y113909D01*
G01X1154180Y114349D02*
Y102220D01*
G01Y99980D02*
Y99052D01*
G01X1153120Y113909D02*
Y98612D01*
G01X1154180Y99052D02*
X1155558Y97674D01*
G01X1153120Y98612D02*
X1154498Y97234D01*
G01X1155558Y97674D02*
Y95542D01*
G01X1096271Y129429D02*
X1097879Y127821D01*
G01X1096271Y129429D02*
X1097879Y127821D01*
G01X1095831Y128369D02*
X1096819Y127381D01*
G01X1097879Y127821D02*
Y126081D01*
G01X1096819Y127381D02*
Y126521D01*
G01X1097879Y126081D02*
X1097180Y125382D01*
G01X1096819Y126521D02*
X1096120Y125822D01*
G01X1097180Y125382D02*
Y124520D01*
G01X1096120Y125822D02*
Y124080D01*
G01X1097180Y124520D02*
X1098164Y123536D01*
G01X1096120Y124080D02*
X1097724Y122476D01*
G01X1098164Y123536D02*
X1099026D01*
G01X1097724Y122476D02*
X1099466D01*
G01X1099026Y123536D02*
X1099725Y124235D01*
G01X1099466Y122476D02*
X1100165Y123175D01*
G01X1099725Y124235D02*
X1101465D01*
G01X1100165Y123175D02*
X1101025D01*
G01X1101465Y124235D02*
X1103073Y122627D01*
G01X1101025Y123175D02*
X1102013Y122187D01*
G01X1103073Y122627D02*
Y120887D01*
G01X1102013Y122187D02*
Y121327D01*
G01X1103073Y120887D02*
X1102374Y120188D01*
G01X1102013Y121327D02*
X1101314Y120628D01*
G01X1102374Y120188D02*
Y119326D01*
G01X1101314Y120628D02*
Y118886D01*
G01X1102374Y119326D02*
X1112040Y109660D01*
G01X1101314Y118886D02*
X1111600Y108600D01*
G01X1112040Y109660D02*
X1115700D01*
G01X1111600Y108600D02*
X1116140D01*
G01X1115700Y109660D02*
X1116740Y110700D01*
G01X1116140Y108600D02*
X1117180Y109640D01*
G01X1116740Y110700D02*
X1123760D01*
G01X1117180Y109640D02*
X1123320D01*
G01X1123760Y110700D02*
X1124800Y109660D01*
G01X1123320Y109640D02*
X1124360Y108600D01*
G01X1124800Y109660D02*
X1129741D01*
G01X1124360Y108600D02*
X1129301D01*
G01X1129741Y109660D02*
X1131378Y108023D01*
G01X1132723Y106678D02*
X1137041Y102360D01*
G01X1129301Y108600D02*
X1136601Y101300D01*
G01X1137041Y102360D02*
X1139550D01*
G01X1141450D02*
X1147508D01*
G01X1136601Y101300D02*
X1147068D01*
G01X1147508Y102360D02*
X1150238Y99630D01*
G01X1147068Y101300D02*
X1149178Y99190D01*
G01X1150238Y99630D02*
Y97800D01*
G01Y95900D02*
Y94900D01*
G01X1114899Y115200D02*
X1151829D01*
G01X1115339Y116260D02*
X1152269D01*
G01X1151829Y115200D02*
X1153120Y113909D01*
G01X1152269Y116260D02*
X1154180Y114349D01*
G01X1153120Y113909D02*
Y98612D01*
G01X1154180Y114349D02*
Y102220D01*
G01X1153120Y113909D02*
Y98612D01*
G01X1154180Y99980D02*
Y99052D01*
G01X1153120Y98612D02*
X1154498Y97234D01*
G01X1154180Y99052D02*
X1155558Y97674D01*
G01D02*
Y95542D01*
G01X1107050Y170950D02*
X1137200Y140800D01*
G01X1107050Y170950D02*
X1137200Y140800D01*
G01X1107050Y170950D02*
X1137200Y140800D01*
G01X1107050Y170950D02*
X1137200Y140800D01*
G01X1107050Y170950D02*
X1137200Y140800D01*
G01X1107050Y170950D02*
X1137200Y140800D01*
G01X1107050Y170950D02*
X1137200Y140800D01*
G01X1121272Y158228D02*
X1137640Y141860D01*
G01X1137200Y140800D02*
X1170001D01*
G01X1137640Y141860D02*
X1170441D01*
G01X1115092Y170209D02*
X1139641Y145660D01*
G01X1111981Y171820D02*
X1139201Y144600D01*
G01X1139641Y145660D02*
X1171740D01*
G01X1139201Y144600D02*
X1171300D01*
G01X1121272Y158228D02*
X1137640Y141860D01*
G01X1107050Y170950D02*
X1137200Y140800D01*
G01X1137640Y141860D02*
X1170441D01*
G01X1137200Y140800D02*
X1170001D01*
G01X1111981Y171820D02*
X1139201Y144600D01*
G01X1111981Y171820D02*
X1139201Y144600D01*
G01X1111981Y171820D02*
X1139201Y144600D01*
G01X1115092Y170209D02*
X1139641Y145660D01*
G01X1139201Y144600D02*
X1171300D01*
G01X1139641Y145660D02*
X1171740D01*
G01X1107050Y170950D02*
X1137200Y140800D01*
G01X1107050Y170950D02*
X1137200Y140800D01*
G01X1107050Y170950D02*
X1137200Y140800D01*
G01X1107050Y170950D02*
X1137200Y140800D01*
G01X1107050Y170950D02*
X1137200Y140800D01*
G01X1107050Y170950D02*
X1137200Y140800D01*
G01X1107050Y170950D02*
X1137200Y140800D01*
G01X1121272Y158228D02*
X1137640Y141860D01*
G01X1137200Y140800D02*
X1170001D01*
G01X1137640Y141860D02*
X1170441D01*
G01X1115092Y170209D02*
X1139641Y145660D01*
G01X1111981Y171820D02*
X1139201Y144600D01*
G01X1139641Y145660D02*
X1171740D01*
G01X1139201Y144600D02*
X1171300D01*
G01X1121272Y158228D02*
X1137640Y141860D01*
G01X1107050Y170950D02*
X1137200Y140800D01*
G01X1137640Y141860D02*
X1170441D01*
G01X1137200Y140800D02*
X1170001D01*
G01X1111981Y171820D02*
X1139201Y144600D01*
G01X1111981Y171820D02*
X1139201Y144600D01*
G01X1111981Y171820D02*
X1139201Y144600D01*
G01X1115092Y170209D02*
X1139641Y145660D01*
G01X1139201Y144600D02*
X1171300D01*
G01X1139641Y145660D02*
X1171740D01*
G01X1107050Y189726D02*
Y170950D01*
G01X1108110Y189726D02*
Y188726D01*
G01X1107050Y189726D02*
Y170950D01*
G01X1108110Y186826D02*
Y185650D01*
G01X1107050Y189726D02*
Y170950D01*
G01X1108110Y183750D02*
Y182750D01*
G01X1107050Y189726D02*
Y170950D01*
G01X1108110Y180850D02*
Y179850D01*
G01X1107050Y189726D02*
Y170950D01*
G01X1108110Y177950D02*
Y176650D01*
G01X1107050Y189726D02*
Y170950D01*
G01X1108110Y174750D02*
Y171390D01*
G01D02*
X1108817Y170683D01*
G01X1110161Y169339D02*
X1110978Y168522D01*
G01X1112322Y167178D02*
X1113128Y166372D01*
G01X1114472Y165028D02*
X1115179Y164321D01*
G01X1116523Y162977D02*
X1117528Y161972D01*
G01X1118872Y160628D02*
X1119928Y159572D01*
G01X1113041Y190613D02*
Y189550D01*
G01Y187650D02*
Y186150D01*
G01Y184250D02*
Y182950D01*
G01Y181050D02*
Y180050D01*
G01Y178150D02*
Y176750D01*
G01Y174850D02*
Y172260D01*
G01X1111981Y190613D02*
Y171820D01*
G01X1113041Y172260D02*
X1113748Y171553D01*
G01D02*
X1114384D01*
G01X1108110Y189726D02*
Y188726D01*
G01Y186826D02*
Y185650D01*
G01Y183750D02*
Y182750D01*
G01Y180850D02*
Y179850D01*
G01Y177950D02*
Y176650D01*
G01Y174750D02*
Y171390D01*
G01X1107050Y189726D02*
Y170950D01*
G01X1108110Y171390D02*
X1108817Y170683D01*
G01X1110161Y169339D02*
X1110978Y168522D01*
G01X1112322Y167178D02*
X1113128Y166372D01*
G01X1114472Y165028D02*
X1115179Y164321D01*
G01X1116523Y162977D02*
X1117528Y161972D01*
G01X1118872Y160628D02*
X1119928Y159572D01*
G01X1111981Y190613D02*
Y171820D01*
G01X1113041Y190613D02*
Y189550D01*
G01X1111981Y190613D02*
Y171820D01*
G01X1113041Y187650D02*
Y186150D01*
G01X1111981Y190613D02*
Y171820D01*
G01X1113041Y184250D02*
Y182950D01*
G01X1111981Y190613D02*
Y171820D01*
G01X1113041Y181050D02*
Y180050D01*
G01X1111981Y190613D02*
Y171820D01*
G01X1113041Y178150D02*
Y176750D01*
G01X1111981Y190613D02*
Y171820D01*
G01X1113041Y174850D02*
Y172260D01*
G01D02*
X1113748Y171553D01*
G01D02*
X1114384D01*
G01X1137066Y200542D02*
X1154979Y182629D01*
G01X1137812Y201289D02*
X1138519Y200582D01*
G01X1137066Y200542D02*
X1154979Y182629D01*
G01X1138519Y200582D02*
X1139155D01*
G01X1137066Y200542D02*
X1154979Y182629D01*
G01X1139863Y199238D02*
X1140570Y198531D01*
G01X1137066Y200542D02*
X1154979Y182629D01*
G01X1140570Y198531D02*
X1141206D01*
G01X1137066Y200542D02*
X1154979Y182629D01*
G01X1141914Y197187D02*
X1142621Y196480D01*
G01X1137066Y200542D02*
X1154979Y182629D01*
G01X1142621Y196480D02*
X1143257D01*
G01X1137066Y200542D02*
X1154979Y182629D01*
G01X1143965Y195136D02*
X1144728Y194373D01*
G01X1137066Y200542D02*
X1154979Y182629D01*
G01X1144728Y194373D02*
X1145365D01*
G01X1137066Y200542D02*
X1154979Y182629D01*
G01X1146073Y193028D02*
X1146780Y192321D01*
G01X1137066Y200542D02*
X1154979Y182629D01*
G01X1146780Y192321D02*
X1147416D01*
G01X1137066Y200542D02*
X1154979Y182629D01*
G01X1148124Y190977D02*
X1148878Y190223D01*
G01X1137066Y200542D02*
X1154979Y182629D01*
G01X1148878Y190223D02*
X1149515D01*
G01X1137066Y200542D02*
X1154979Y182629D01*
G01X1150223Y188878D02*
X1150930Y188171D01*
G01X1137066Y200542D02*
X1154979Y182629D01*
G01X1150930Y188171D02*
X1151566D01*
G01X1137066Y200542D02*
X1154979Y182629D01*
G01X1152274Y186827D02*
X1152980Y186120D01*
G01X1137066Y200542D02*
X1154979Y182629D01*
G01X1152980Y186120D02*
X1153617D01*
G01X1137066Y200542D02*
X1154979Y182629D01*
G01X1154325Y184776D02*
X1155411Y183689D01*
G01X1154979Y182629D02*
X1158072D01*
G01X1155411Y183689D02*
X1158512D01*
G01X1140599Y204288D02*
X1158253Y186634D01*
G01X1139849Y203538D02*
X1157813Y185574D01*
G01X1137812Y201289D02*
X1138519Y200582D01*
G01D02*
X1139155D01*
G01X1139863Y199238D02*
X1140570Y198531D01*
G01D02*
X1141206D01*
G01X1141914Y197187D02*
X1142621Y196480D01*
G01D02*
X1143257D01*
G01X1143965Y195136D02*
X1144728Y194373D01*
G01D02*
X1145365D01*
G01X1146073Y193028D02*
X1146780Y192321D01*
G01D02*
X1147416D01*
G01X1148124Y190977D02*
X1148878Y190223D01*
G01D02*
X1149515D01*
G01X1150223Y188878D02*
X1150930Y188171D01*
G01D02*
X1151566D01*
G01X1152274Y186827D02*
X1152980Y186120D01*
G01D02*
X1153617D01*
G01X1154325Y184776D02*
X1155411Y183689D01*
G01X1137066Y200542D02*
X1154979Y182629D01*
G01X1155411Y183689D02*
X1158512D01*
G01X1154979Y182629D02*
X1158072D01*
G01X1139849Y203538D02*
X1157813Y185574D01*
G01X1140599Y204288D02*
X1158253Y186634D01*
G01X1107050Y189726D02*
Y170950D01*
G01X1108110Y189726D02*
Y188726D01*
G01X1107050Y189726D02*
Y170950D01*
G01X1108110Y186826D02*
Y185650D01*
G01X1107050Y189726D02*
Y170950D01*
G01X1108110Y183750D02*
Y182750D01*
G01X1107050Y189726D02*
Y170950D01*
G01X1108110Y180850D02*
Y179850D01*
G01X1107050Y189726D02*
Y170950D01*
G01X1108110Y177950D02*
Y176650D01*
G01X1107050Y189726D02*
Y170950D01*
G01X1108110Y174750D02*
Y171390D01*
G01D02*
X1108817Y170683D01*
G01X1110161Y169339D02*
X1110978Y168522D01*
G01X1112322Y167178D02*
X1113128Y166372D01*
G01X1114472Y165028D02*
X1115179Y164321D01*
G01X1116523Y162977D02*
X1117528Y161972D01*
G01X1118872Y160628D02*
X1119928Y159572D01*
G01X1113041Y190613D02*
Y189550D01*
G01Y187650D02*
Y186150D01*
G01Y184250D02*
Y182950D01*
G01Y181050D02*
Y180050D01*
G01Y178150D02*
Y176750D01*
G01Y174850D02*
Y172260D01*
G01X1111981Y190613D02*
Y171820D01*
G01X1113041Y172260D02*
X1113748Y171553D01*
G01D02*
X1114384D01*
G01X1108110Y189726D02*
Y188726D01*
G01Y186826D02*
Y185650D01*
G01Y183750D02*
Y182750D01*
G01Y180850D02*
Y179850D01*
G01Y177950D02*
Y176650D01*
G01Y174750D02*
Y171390D01*
G01X1107050Y189726D02*
Y170950D01*
G01X1108110Y171390D02*
X1108817Y170683D01*
G01X1110161Y169339D02*
X1110978Y168522D01*
G01X1112322Y167178D02*
X1113128Y166372D01*
G01X1114472Y165028D02*
X1115179Y164321D01*
G01X1116523Y162977D02*
X1117528Y161972D01*
G01X1118872Y160628D02*
X1119928Y159572D01*
G01X1111981Y190613D02*
Y171820D01*
G01X1113041Y190613D02*
Y189550D01*
G01X1111981Y190613D02*
Y171820D01*
G01X1113041Y187650D02*
Y186150D01*
G01X1111981Y190613D02*
Y171820D01*
G01X1113041Y184250D02*
Y182950D01*
G01X1111981Y190613D02*
Y171820D01*
G01X1113041Y181050D02*
Y180050D01*
G01X1111981Y190613D02*
Y171820D01*
G01X1113041Y178150D02*
Y176750D01*
G01X1111981Y190613D02*
Y171820D01*
G01X1113041Y174850D02*
Y172260D01*
G01D02*
X1113748Y171553D01*
G01D02*
X1114384D01*
G01X1137066Y200542D02*
X1154979Y182629D01*
G01X1137812Y201289D02*
X1138519Y200582D01*
G01X1137066Y200542D02*
X1154979Y182629D01*
G01X1138519Y200582D02*
X1139155D01*
G01X1137066Y200542D02*
X1154979Y182629D01*
G01X1139863Y199238D02*
X1140570Y198531D01*
G01X1137066Y200542D02*
X1154979Y182629D01*
G01X1140570Y198531D02*
X1141206D01*
G01X1137066Y200542D02*
X1154979Y182629D01*
G01X1141914Y197187D02*
X1142621Y196480D01*
G01X1137066Y200542D02*
X1154979Y182629D01*
G01X1142621Y196480D02*
X1143257D01*
G01X1137066Y200542D02*
X1154979Y182629D01*
G01X1143965Y195136D02*
X1144728Y194373D01*
G01X1137066Y200542D02*
X1154979Y182629D01*
G01X1144728Y194373D02*
X1145365D01*
G01X1137066Y200542D02*
X1154979Y182629D01*
G01X1146073Y193028D02*
X1146780Y192321D01*
G01X1137066Y200542D02*
X1154979Y182629D01*
G01X1146780Y192321D02*
X1147416D01*
G01X1137066Y200542D02*
X1154979Y182629D01*
G01X1148124Y190977D02*
X1148878Y190223D01*
G01X1137066Y200542D02*
X1154979Y182629D01*
G01X1148878Y190223D02*
X1149515D01*
G01X1137066Y200542D02*
X1154979Y182629D01*
G01X1150223Y188878D02*
X1150930Y188171D01*
G01X1137066Y200542D02*
X1154979Y182629D01*
G01X1150930Y188171D02*
X1151566D01*
G01X1137066Y200542D02*
X1154979Y182629D01*
G01X1152274Y186827D02*
X1152980Y186120D01*
G01X1137066Y200542D02*
X1154979Y182629D01*
G01X1152980Y186120D02*
X1153617D01*
G01X1137066Y200542D02*
X1154979Y182629D01*
G01X1154325Y184776D02*
X1155411Y183689D01*
G01X1154979Y182629D02*
X1158072D01*
G01X1155411Y183689D02*
X1158512D01*
G01X1140599Y204288D02*
X1158253Y186634D01*
G01X1139849Y203538D02*
X1157813Y185574D01*
G01X1137812Y201289D02*
X1138519Y200582D01*
G01D02*
X1139155D01*
G01X1139863Y199238D02*
X1140570Y198531D01*
G01D02*
X1141206D01*
G01X1141914Y197187D02*
X1142621Y196480D01*
G01D02*
X1143257D01*
G01X1143965Y195136D02*
X1144728Y194373D01*
G01D02*
X1145365D01*
G01X1146073Y193028D02*
X1146780Y192321D01*
G01D02*
X1147416D01*
G01X1148124Y190977D02*
X1148878Y190223D01*
G01D02*
X1149515D01*
G01X1150223Y188878D02*
X1150930Y188171D01*
G01D02*
X1151566D01*
G01X1152274Y186827D02*
X1152980Y186120D01*
G01D02*
X1153617D01*
G01X1154325Y184776D02*
X1155411Y183689D01*
G01X1137066Y200542D02*
X1154979Y182629D01*
G01X1155411Y183689D02*
X1158512D01*
G01X1154979Y182629D02*
X1158072D01*
G01X1139849Y203538D02*
X1157813Y185574D01*
G01X1140599Y204288D02*
X1158253Y186634D01*
G01X1113946Y416387D02*
Y434846D01*
G01X1115006Y416387D02*
Y434406D01*
G01X1113946Y434846D02*
X1122040Y442940D01*
G01X1115006Y434406D02*
X1123100Y442500D01*
G01X1122040Y442940D02*
Y447108D01*
G01X1123100Y442500D02*
Y446668D01*
G01X1122040Y447108D02*
X1138145Y463213D01*
G01X1123100Y446668D02*
X1138585Y462153D01*
G01X1138145Y463213D02*
X1178831D01*
G01X1138585Y462153D02*
X1179274D01*
G01X1154870Y418100D02*
X1159530Y422760D01*
G01X1155621Y417351D02*
X1159970Y421700D01*
G01X1118696Y419887D02*
Y433196D01*
G01X1117636Y419887D02*
Y433636D01*
G01X1118696Y433196D02*
X1126600Y441100D01*
G01X1117636Y433636D02*
X1125540Y441540D01*
G01X1126600Y441100D02*
Y444129D01*
G01X1125540Y441540D02*
Y444569D01*
G01X1126600Y444129D02*
X1140817Y458346D01*
G01X1125540Y444569D02*
X1140377Y459406D01*
G01X1140817Y458346D02*
X1164058D01*
G01X1140377Y459406D02*
X1164498D01*
G01X1156250Y415130D02*
X1160830Y419710D01*
G01X1115006Y416387D02*
Y434406D01*
G01X1113946Y416387D02*
Y434846D01*
G01X1115006Y434406D02*
X1123100Y442500D01*
G01X1113946Y434846D02*
X1122040Y442940D01*
G01X1123100Y442500D02*
Y446668D01*
G01X1122040Y442940D02*
Y447108D01*
G01X1123100Y446668D02*
X1138585Y462153D01*
G01X1122040Y447108D02*
X1138145Y463213D01*
G01X1138585Y462153D02*
X1179274D01*
G01X1138145Y463213D02*
X1178831D01*
G01X1155621Y417351D02*
X1159970Y421700D01*
G01X1154870Y418100D02*
X1159530Y422760D01*
G01X1117636Y419887D02*
Y433636D01*
G01X1118696Y419887D02*
Y433196D01*
G01X1117636Y433636D02*
X1125540Y441540D01*
G01X1118696Y433196D02*
X1126600Y441100D01*
G01X1125540Y441540D02*
Y444569D01*
G01X1126600Y441100D02*
Y444129D01*
G01X1125540Y444569D02*
X1140377Y459406D01*
G01X1126600Y444129D02*
X1140817Y458346D01*
G01X1140377Y459406D02*
X1164498D01*
G01X1140817Y458346D02*
X1164058D01*
G01X1156250Y415130D02*
X1160830Y419710D01*
G01X1113946Y416387D02*
Y434846D01*
G01X1115006Y416387D02*
Y434406D01*
G01X1113946Y434846D02*
X1122040Y442940D01*
G01X1115006Y434406D02*
X1123100Y442500D01*
G01X1122040Y442940D02*
Y447108D01*
G01X1123100Y442500D02*
Y446668D01*
G01X1122040Y447108D02*
X1138145Y463213D01*
G01X1123100Y446668D02*
X1138585Y462153D01*
G01X1138145Y463213D02*
X1178831D01*
G01X1138585Y462153D02*
X1179274D01*
G01X1118696Y419887D02*
Y433196D01*
G01X1117636Y419887D02*
Y433636D01*
G01X1118696Y433196D02*
X1126600Y441100D01*
G01X1117636Y433636D02*
X1125540Y441540D01*
G01X1126600Y441100D02*
Y444129D01*
G01X1125540Y441540D02*
Y444569D01*
G01X1126600Y444129D02*
X1140817Y458346D01*
G01X1125540Y444569D02*
X1140377Y459406D01*
G01X1140817Y458346D02*
X1164058D01*
G01X1140377Y459406D02*
X1164498D01*
G01X1115006Y416387D02*
Y434406D01*
G01X1113946Y416387D02*
Y434846D01*
G01X1115006Y434406D02*
X1123100Y442500D01*
G01X1113946Y434846D02*
X1122040Y442940D01*
G01X1123100Y442500D02*
Y446668D01*
G01X1122040Y442940D02*
Y447108D01*
G01X1123100Y446668D02*
X1138585Y462153D01*
G01X1122040Y447108D02*
X1138145Y463213D01*
G01X1138585Y462153D02*
X1179274D01*
G01X1138145Y463213D02*
X1178831D01*
G01X1117636Y419887D02*
Y433636D01*
G01X1118696Y419887D02*
Y433196D01*
G01X1117636Y433636D02*
X1125540Y441540D01*
G01X1118696Y433196D02*
X1126600Y441100D01*
G01X1125540Y441540D02*
Y444569D01*
G01X1126600Y441100D02*
Y444129D01*
G01X1125540Y444569D02*
X1140377Y459406D01*
G01X1126600Y444129D02*
X1140817Y458346D01*
G01X1140377Y459406D02*
X1164498D01*
G01X1140817Y458346D02*
X1164058D01*
G01X1154870Y418100D02*
X1159530Y422760D01*
G01X1155621Y417351D02*
X1159970Y421700D01*
G01X1156250Y415130D02*
X1160830Y419710D01*
G01X1155621Y417351D02*
X1159970Y421700D01*
G01X1154870Y418100D02*
X1159530Y422760D01*
G01X1156250Y415130D02*
X1160830Y419710D01*
G01X1149164Y514336D02*
Y532411D01*
G01X1150224Y520290D02*
Y521660D01*
G01X1149164Y514336D02*
Y532411D01*
G01X1150224Y525340D02*
Y526760D01*
G01X1119024Y492692D02*
X1129663D01*
G01X1119464Y491632D02*
X1130103D01*
G01X1129663Y492692D02*
X1130951Y493980D01*
G01X1132414Y495443D02*
X1133320Y496349D01*
G01X1130103Y491632D02*
X1134380Y495909D01*
G01X1133320Y496349D02*
Y499241D01*
G01X1134380Y495909D02*
Y498801D01*
G01X1133320Y499241D02*
X1135728Y501649D01*
G01X1134380Y498801D02*
X1136168Y500589D01*
G01X1135728Y501649D02*
X1137560D01*
G01X1139800D02*
X1140800D01*
G01X1143040D02*
X1144040D01*
G01X1146280D02*
X1147280D01*
G01X1149520D02*
X1150620D01*
G01X1136168Y500589D02*
X1151060D01*
G01X1150620Y501649D02*
X1153172Y504201D01*
G01X1151060Y500589D02*
X1154232Y503761D01*
G01X1153172Y504201D02*
Y506922D01*
G01Y509162D02*
Y511780D01*
G01X1154232Y503761D02*
Y512220D01*
G01X1153172Y511780D02*
X1152252Y512700D01*
G01X1154232Y512220D02*
X1151152Y515300D01*
G01X1155448Y519900D02*
X1154777Y520571D01*
G01X1154547Y519300D02*
X1153717Y520130D01*
G01X1154777Y520571D02*
Y521848D01*
G01Y525338D02*
Y526229D01*
G01X1153717Y520130D02*
Y526670D01*
G01X1154777Y526229D02*
X1155548Y527000D01*
G01X1121040Y487464D02*
X1157973D01*
G01X1120600Y488524D02*
X1128115D01*
G01X1121040Y487464D02*
X1157973D01*
G01X1130355Y488524D02*
X1131355D01*
G01X1121040Y487464D02*
X1157973D01*
G01X1133595Y488524D02*
X1134595D01*
G01X1121040Y487464D02*
X1157973D01*
G01X1136835Y488524D02*
X1137835D01*
G01X1121040Y487464D02*
X1157973D01*
G01X1140075Y488524D02*
X1141075D01*
G01X1121040Y487464D02*
X1157973D01*
G01X1143315Y488524D02*
X1147555D01*
G01X1121040Y487464D02*
X1157973D01*
G01X1149795Y488524D02*
X1150795D01*
G01X1121040Y487464D02*
X1157973D01*
G01X1153035Y488524D02*
X1154035D01*
G01X1121040Y487464D02*
X1157973D01*
G01X1156275Y488524D02*
X1157533D01*
G01X1159632Y512134D02*
X1156252Y515514D01*
G01X1150224Y520290D02*
Y521660D01*
G01Y525340D02*
Y526760D01*
G01X1149164Y514336D02*
Y532411D01*
G01X1119464Y491632D02*
X1130103D01*
G01X1119024Y492692D02*
X1129663D01*
G01X1130103Y491632D02*
X1134380Y495909D01*
G01X1129663Y492692D02*
X1130951Y493980D01*
G01X1130103Y491632D02*
X1134380Y495909D01*
G01X1132414Y495443D02*
X1133320Y496349D01*
G01X1134380Y495909D02*
Y498801D01*
G01X1133320Y496349D02*
Y499241D01*
G01X1134380Y498801D02*
X1136168Y500589D01*
G01X1133320Y499241D02*
X1135728Y501649D01*
G01X1136168Y500589D02*
X1151060D01*
G01X1135728Y501649D02*
X1137560D01*
G01X1136168Y500589D02*
X1151060D01*
G01X1139800Y501649D02*
X1140800D01*
G01X1136168Y500589D02*
X1151060D01*
G01X1143040Y501649D02*
X1144040D01*
G01X1136168Y500589D02*
X1151060D01*
G01X1146280Y501649D02*
X1147280D01*
G01X1136168Y500589D02*
X1151060D01*
G01X1149520Y501649D02*
X1150620D01*
G01X1151060Y500589D02*
X1154232Y503761D01*
G01X1150620Y501649D02*
X1153172Y504201D01*
G01X1154232Y503761D02*
Y512220D01*
G01X1153172Y504201D02*
Y506922D01*
G01X1154232Y503761D02*
Y512220D01*
G01X1153172Y509162D02*
Y511780D01*
G01X1154232Y512220D02*
X1151152Y515300D01*
G01X1153172Y511780D02*
X1152252Y512700D01*
G01X1154547Y519300D02*
X1153717Y520130D01*
G01X1155448Y519900D02*
X1154777Y520571D01*
G01X1153717Y520130D02*
Y526670D01*
G01X1154777Y520571D02*
Y521848D01*
G01X1153717Y520130D02*
Y526670D01*
G01X1154777Y525338D02*
Y526229D01*
G01D02*
X1155548Y527000D01*
G01X1120600Y488524D02*
X1128115D01*
G01X1130355D02*
X1131355D01*
G01X1133595D02*
X1134595D01*
G01X1136835D02*
X1137835D01*
G01X1140075D02*
X1141075D01*
G01X1143315D02*
X1147555D01*
G01X1149795D02*
X1150795D01*
G01X1153035D02*
X1154035D01*
G01X1156275D02*
X1157533D01*
G01X1121040Y487464D02*
X1157973D01*
G01X1156275Y488524D02*
X1157533D01*
G01X1159632Y512134D02*
X1156252Y515514D01*
G01X1112353Y532412D02*
Y514347D01*
G01X1113413Y526760D02*
Y525340D01*
G01X1112353Y532412D02*
Y514347D01*
G01X1113413Y521660D02*
Y520290D01*
G01X1149164Y514336D02*
Y532411D01*
G01X1150224Y520290D02*
Y521660D01*
G01X1149164Y514336D02*
Y532411D01*
G01X1150224Y525340D02*
Y526760D01*
G01X1119024Y492692D02*
X1129663D01*
G01X1119464Y491632D02*
X1130103D01*
G01X1129663Y492692D02*
X1130951Y493980D01*
G01X1132414Y495443D02*
X1133320Y496349D01*
G01X1130103Y491632D02*
X1134380Y495909D01*
G01X1133320Y496349D02*
Y499241D01*
G01X1134380Y495909D02*
Y498801D01*
G01X1133320Y499241D02*
X1135728Y501649D01*
G01X1134380Y498801D02*
X1136168Y500589D01*
G01X1135728Y501649D02*
X1137560D01*
G01X1139800D02*
X1140800D01*
G01X1143040D02*
X1144040D01*
G01X1146280D02*
X1147280D01*
G01X1149520D02*
X1150620D01*
G01X1136168Y500589D02*
X1151060D01*
G01X1150620Y501649D02*
X1153172Y504201D01*
G01X1151060Y500589D02*
X1154232Y503761D01*
G01X1153172Y504201D02*
Y506922D01*
G01Y509162D02*
Y511780D01*
G01X1154232Y503761D02*
Y512220D01*
G01X1153172Y511780D02*
X1152252Y512700D01*
G01X1154232Y512220D02*
X1151152Y515300D01*
G01X1118737Y527000D02*
X1117966Y526229D01*
G01D02*
Y525338D01*
G01Y521848D02*
Y520571D01*
G01X1116906Y526670D02*
Y520130D01*
G01X1117966Y520571D02*
X1118637Y519900D01*
G01X1116906Y520130D02*
X1117735Y519301D01*
G01X1155448Y519900D02*
X1154777Y520571D01*
G01X1154547Y519300D02*
X1153717Y520130D01*
G01X1154777Y520571D02*
Y521848D01*
G01Y525338D02*
Y526229D01*
G01X1153717Y520130D02*
Y526670D01*
G01X1154777Y526229D02*
X1155548Y527000D01*
G01X1121040Y487464D02*
X1157973D01*
G01X1120600Y488524D02*
X1128115D01*
G01X1121040Y487464D02*
X1157973D01*
G01X1130355Y488524D02*
X1131355D01*
G01X1121040Y487464D02*
X1157973D01*
G01X1133595Y488524D02*
X1134595D01*
G01X1121040Y487464D02*
X1157973D01*
G01X1136835Y488524D02*
X1137835D01*
G01X1121040Y487464D02*
X1157973D01*
G01X1140075Y488524D02*
X1141075D01*
G01X1121040Y487464D02*
X1157973D01*
G01X1143315Y488524D02*
X1147555D01*
G01X1121040Y487464D02*
X1157973D01*
G01X1149795Y488524D02*
X1150795D01*
G01X1121040Y487464D02*
X1157973D01*
G01X1153035Y488524D02*
X1154035D01*
G01X1121040Y487464D02*
X1157973D01*
G01X1156275Y488524D02*
X1157533D01*
G01X1159632Y512134D02*
X1156252Y515514D01*
G01X1113413Y526760D02*
Y525340D01*
G01Y521660D02*
Y520290D01*
G01X1112353Y532412D02*
Y514347D01*
G01X1150224Y520290D02*
Y521660D01*
G01Y525340D02*
Y526760D01*
G01X1149164Y514336D02*
Y532411D01*
G01X1119464Y491632D02*
X1130103D01*
G01X1119024Y492692D02*
X1129663D01*
G01X1130103Y491632D02*
X1134380Y495909D01*
G01X1129663Y492692D02*
X1130951Y493980D01*
G01X1130103Y491632D02*
X1134380Y495909D01*
G01X1132414Y495443D02*
X1133320Y496349D01*
G01X1134380Y495909D02*
Y498801D01*
G01X1133320Y496349D02*
Y499241D01*
G01X1134380Y498801D02*
X1136168Y500589D01*
G01X1133320Y499241D02*
X1135728Y501649D01*
G01X1136168Y500589D02*
X1151060D01*
G01X1135728Y501649D02*
X1137560D01*
G01X1136168Y500589D02*
X1151060D01*
G01X1139800Y501649D02*
X1140800D01*
G01X1136168Y500589D02*
X1151060D01*
G01X1143040Y501649D02*
X1144040D01*
G01X1136168Y500589D02*
X1151060D01*
G01X1146280Y501649D02*
X1147280D01*
G01X1136168Y500589D02*
X1151060D01*
G01X1149520Y501649D02*
X1150620D01*
G01X1151060Y500589D02*
X1154232Y503761D01*
G01X1150620Y501649D02*
X1153172Y504201D01*
G01X1154232Y503761D02*
Y512220D01*
G01X1153172Y504201D02*
Y506922D01*
G01X1154232Y503761D02*
Y512220D01*
G01X1153172Y509162D02*
Y511780D01*
G01X1154232Y512220D02*
X1151152Y515300D01*
G01X1153172Y511780D02*
X1152252Y512700D01*
G01X1118737Y527000D02*
X1117966Y526229D01*
G01X1116906Y526670D02*
Y520130D01*
G01X1117966Y526229D02*
Y525338D01*
G01X1116906Y526670D02*
Y520130D01*
G01X1117966Y521848D02*
Y520571D01*
G01X1116906Y520130D02*
X1117735Y519301D01*
G01X1117966Y520571D02*
X1118637Y519900D01*
G01X1154547Y519300D02*
X1153717Y520130D01*
G01X1155448Y519900D02*
X1154777Y520571D01*
G01X1153717Y520130D02*
Y526670D01*
G01X1154777Y520571D02*
Y521848D01*
G01X1153717Y520130D02*
Y526670D01*
G01X1154777Y525338D02*
Y526229D01*
G01D02*
X1155548Y527000D01*
G01X1120600Y488524D02*
X1128115D01*
G01X1130355D02*
X1131355D01*
G01X1133595D02*
X1134595D01*
G01X1136835D02*
X1137835D01*
G01X1140075D02*
X1141075D01*
G01X1143315D02*
X1147555D01*
G01X1149795D02*
X1150795D01*
G01X1153035D02*
X1154035D01*
G01X1156275D02*
X1157533D01*
G01X1121040Y487464D02*
X1157973D01*
G01X1156275Y488524D02*
X1157533D01*
G01X1159632Y512134D02*
X1156252Y515514D01*
G01X1153717Y526670D02*
X1154547Y527500D01*
G01X1153717Y526670D02*
X1154547Y527500D01*
G01X1117735Y527499D02*
X1116906Y526670D01*
G01X1153717D02*
X1154547Y527500D01*
G01X1117735Y527499D02*
X1116906Y526670D01*
G01X1153717D02*
X1154547Y527500D01*
G01X1157350Y87515D02*
X1158384Y86481D01*
G01X1159444Y86922D02*
Y71532D01*
G01X1158384Y86481D02*
Y83706D01*
G01X1159444Y86922D02*
Y71532D01*
G01X1158384Y79880D02*
Y78507D01*
G01X1159444Y86922D02*
Y71532D01*
G01X1158384Y74593D02*
Y71972D01*
G01D02*
X1157361Y70949D01*
G01X1157350Y87515D02*
X1158384Y86481D01*
G01D02*
Y83706D01*
G01Y79880D02*
Y78507D01*
G01Y74593D02*
Y71972D01*
G01X1159444Y86922D02*
Y71532D01*
G01X1158384Y71972D02*
X1157361Y70949D01*
G01X1157350Y87515D02*
X1158384Y86481D01*
G01X1159444Y86922D02*
Y71532D01*
G01X1158384Y86481D02*
Y83706D01*
G01X1159444Y86922D02*
Y71532D01*
G01X1158384Y79880D02*
Y78507D01*
G01X1159444Y86922D02*
Y71532D01*
G01X1158384Y74593D02*
Y71972D01*
G01D02*
X1157361Y70949D01*
G01X1157350Y87515D02*
X1158384Y86481D01*
G01D02*
Y83706D01*
G01Y79880D02*
Y78507D01*
G01Y74593D02*
Y71972D01*
G01X1159444Y86922D02*
Y71532D01*
G01X1158384Y71972D02*
X1157361Y70949D01*
G01X1189064Y87300D02*
X1190009Y86355D01*
G01X1189082Y88782D02*
X1190597Y87266D01*
G01X1189064Y87300D02*
X1190009Y86355D01*
G01X1190597Y87266D02*
X1191069Y86794D01*
G01X1190009Y86355D02*
Y83820D01*
G01Y79680D02*
Y78720D01*
G01Y74380D02*
Y71091D01*
G01X1191069Y86794D02*
Y70648D01*
G01X1190009Y71091D02*
X1189298Y70380D01*
G01D02*
X1188782D01*
G01X1191069Y70648D02*
X1189741Y69320D01*
G01X1189298Y70380D02*
X1188782D01*
G01X1189741Y69320D02*
X1188759D01*
G01X1186109Y97579D02*
Y89154D01*
G01X1194630Y88546D02*
X1195911Y87266D01*
G01X1193063Y87515D02*
X1194161D01*
G01X1194630Y88546D02*
X1195911Y87266D01*
G01D02*
X1196255Y86922D01*
G01X1194161Y87515D02*
X1195195Y86481D01*
G01X1196255Y86922D02*
Y71532D01*
G01X1195195Y86481D02*
Y83706D01*
G01X1196255Y86922D02*
Y71532D01*
G01X1195195Y79880D02*
Y78507D01*
G01X1196255Y86922D02*
Y71532D01*
G01X1195195Y74593D02*
Y71972D01*
G01X1196255Y71532D02*
X1193063Y68340D01*
G01X1195195Y71972D02*
X1194172Y70949D01*
G01X1191309Y96976D02*
Y89268D01*
G01X1189082Y88782D02*
X1190597Y87266D01*
G01D02*
X1191069Y86794D01*
G01X1189064Y87300D02*
X1190009Y86355D01*
G01X1191069Y86794D02*
Y70648D01*
G01X1190009Y86355D02*
Y83820D01*
G01X1191069Y86794D02*
Y70648D01*
G01X1190009Y79680D02*
Y78720D01*
G01X1191069Y86794D02*
Y70648D01*
G01X1190009Y74380D02*
Y71091D01*
G01X1191069Y70648D02*
X1189741Y69320D01*
G01X1190009Y71091D02*
X1189298Y70380D01*
G01X1191069Y70648D02*
X1189741Y69320D01*
G01D02*
X1188759D01*
G01X1189298Y70380D02*
X1188782D01*
G01X1186109Y97579D02*
Y89154D01*
G01X1193063Y87515D02*
X1194161D01*
G01D02*
X1195195Y86481D01*
G01X1194630Y88546D02*
X1195911Y87266D01*
G01X1194161Y87515D02*
X1195195Y86481D01*
G01X1195911Y87266D02*
X1196255Y86922D01*
G01X1195195Y86481D02*
Y83706D01*
G01Y79880D02*
Y78507D01*
G01Y74593D02*
Y71972D01*
G01X1196255Y86922D02*
Y71532D01*
G01X1195195Y71972D02*
X1194172Y70949D01*
G01X1196255Y71532D02*
X1193063Y68340D01*
G01X1191309Y96976D02*
Y89268D01*
G01X1189064Y87300D02*
X1190009Y86355D01*
G01X1189082Y88782D02*
X1190597Y87266D01*
G01X1189064Y87300D02*
X1190009Y86355D01*
G01X1190597Y87266D02*
X1191069Y86794D01*
G01X1190009Y86355D02*
Y83820D01*
G01Y79680D02*
Y78720D01*
G01Y74380D02*
Y71091D01*
G01X1191069Y86794D02*
Y70648D01*
G01X1190009Y71091D02*
X1189298Y70380D01*
G01D02*
X1188782D01*
G01X1191069Y70648D02*
X1189741Y69320D01*
G01X1189298Y70380D02*
X1188782D01*
G01X1189741Y69320D02*
X1188759D01*
G01X1186109Y97579D02*
Y89154D01*
G01X1194630Y88546D02*
X1195911Y87266D01*
G01X1193063Y87515D02*
X1194161D01*
G01X1194630Y88546D02*
X1195911Y87266D01*
G01D02*
X1196255Y86922D01*
G01X1194161Y87515D02*
X1195195Y86481D01*
G01X1196255Y86922D02*
Y71532D01*
G01X1195195Y86481D02*
Y83706D01*
G01X1196255Y86922D02*
Y71532D01*
G01X1195195Y79880D02*
Y78507D01*
G01X1196255Y86922D02*
Y71532D01*
G01X1195195Y74593D02*
Y71972D01*
G01X1196255Y71532D02*
X1193063Y68340D01*
G01X1195195Y71972D02*
X1194172Y70949D01*
G01X1191309Y96976D02*
Y89268D01*
G01X1189082Y88782D02*
X1190597Y87266D01*
G01D02*
X1191069Y86794D01*
G01X1189064Y87300D02*
X1190009Y86355D01*
G01X1191069Y86794D02*
Y70648D01*
G01X1190009Y86355D02*
Y83820D01*
G01X1191069Y86794D02*
Y70648D01*
G01X1190009Y79680D02*
Y78720D01*
G01X1191069Y86794D02*
Y70648D01*
G01X1190009Y74380D02*
Y71091D01*
G01X1191069Y70648D02*
X1189741Y69320D01*
G01X1190009Y71091D02*
X1189298Y70380D01*
G01X1191069Y70648D02*
X1189741Y69320D01*
G01D02*
X1188759D01*
G01X1189298Y70380D02*
X1188782D01*
G01X1186109Y97579D02*
Y89154D01*
G01X1193063Y87515D02*
X1194161D01*
G01D02*
X1195195Y86481D01*
G01X1194630Y88546D02*
X1195911Y87266D01*
G01X1194161Y87515D02*
X1195195Y86481D01*
G01X1195911Y87266D02*
X1196255Y86922D01*
G01X1195195Y86481D02*
Y83706D01*
G01Y79880D02*
Y78507D01*
G01Y74593D02*
Y71972D01*
G01X1196255Y86922D02*
Y71532D01*
G01X1195195Y71972D02*
X1194172Y70949D01*
G01X1196255Y71532D02*
X1193063Y68340D01*
G01X1191309Y96976D02*
Y89268D01*
G01X1170001Y140800D02*
X1172251Y138550D01*
G01X1170441Y141860D02*
X1173311Y138990D01*
G01X1172251Y138550D02*
Y137688D01*
G01X1173311Y138990D02*
Y137248D01*
G01X1172251Y137688D02*
X1171474Y136911D01*
G01X1173311Y137248D02*
X1172534Y136471D01*
G01X1171474Y136911D02*
Y135327D01*
G01X1172534Y136471D02*
Y135767D01*
G01X1171474Y135327D02*
X1173238Y133563D01*
G01X1172534Y135767D02*
X1173678Y134623D01*
G01X1173238Y133563D02*
X1174822D01*
G01D02*
X1175599Y134340D01*
G01X1173678Y134623D02*
X1174382D01*
G01X1174822Y133563D02*
X1175599Y134340D01*
G01D02*
X1176461D01*
G01X1174382Y134623D02*
X1175159Y135400D01*
G01X1175599Y134340D02*
X1176461D01*
G01X1175159Y135400D02*
X1176901D01*
G01X1176461Y134340D02*
X1177445Y133356D01*
G01X1176901Y135400D02*
X1178505Y133796D01*
G01X1177445Y133356D02*
Y132494D01*
G01X1178505Y133796D02*
Y132054D01*
G01X1177445Y132494D02*
X1176618Y131667D01*
G01X1178505Y132054D02*
X1177678Y131227D01*
G01X1176618Y131667D02*
Y130083D01*
G01X1177678Y131227D02*
Y130523D01*
G01X1176618Y130083D02*
X1178382Y128319D01*
G01X1177678Y130523D02*
X1178822Y129379D01*
G01X1178382Y128319D02*
X1179966D01*
G01D02*
X1180793Y129146D01*
G01X1178822Y129379D02*
X1179526D01*
G01X1179966Y128319D02*
X1180793Y129146D01*
G01D02*
X1181655D01*
G01X1179526Y129379D02*
X1180353Y130206D01*
G01X1180793Y129146D02*
X1181655D01*
G01X1180353Y130206D02*
X1182095D01*
G01X1181655Y129146D02*
X1182639Y128162D01*
G01X1182095Y130206D02*
X1183699Y128602D01*
G01X1182639Y128162D02*
Y127300D01*
G01X1183699Y128602D02*
Y126860D01*
G01X1182639Y127300D02*
X1181662Y126323D01*
G01X1183699Y126860D02*
X1182722Y125883D01*
G01X1181662Y126323D02*
Y124739D01*
G01X1182722Y125883D02*
Y125179D01*
G01X1181662Y124739D02*
X1183426Y122975D01*
G01X1182722Y125179D02*
X1183866Y124035D01*
G01X1183426Y122975D02*
X1187826D01*
G01X1183866Y124035D02*
X1188266D01*
G01X1187826Y122975D02*
X1189994Y120807D01*
G01X1188266Y124035D02*
X1191054Y121247D01*
G01X1189994Y120807D02*
Y101464D01*
G01X1191054Y121247D02*
Y118420D01*
G01X1189994Y120807D02*
Y101464D01*
G01X1191054Y116180D02*
Y104093D01*
G01X1189994Y120807D02*
Y101464D01*
G01X1191054Y101853D02*
Y101021D01*
G01X1189994Y101464D02*
X1186109Y97579D01*
G01X1191054Y101021D02*
X1187169Y97136D01*
G01D02*
Y95220D01*
G01X1171740Y145660D02*
X1196154Y121246D01*
G01X1171300Y144600D02*
X1195094Y120806D01*
G01X1196154Y121246D02*
Y100321D01*
G01X1195094Y120806D02*
Y100761D01*
G01X1196154Y100321D02*
X1192369Y96536D01*
G01X1195094Y100761D02*
X1191309Y96976D01*
G01X1192369Y96536D02*
Y95281D01*
G01X1170441Y141860D02*
X1173311Y138990D01*
G01X1170001Y140800D02*
X1172251Y138550D01*
G01X1173311Y138990D02*
Y137248D01*
G01X1172251Y138550D02*
Y137688D01*
G01X1173311Y137248D02*
X1172534Y136471D01*
G01X1172251Y137688D02*
X1171474Y136911D01*
G01X1172534Y136471D02*
Y135767D01*
G01X1171474Y136911D02*
Y135327D01*
G01X1172534Y135767D02*
X1173678Y134623D01*
G01X1171474Y135327D02*
X1173238Y133563D01*
G01X1173678Y134623D02*
X1174382D01*
G01X1173238Y133563D02*
X1174822D01*
G01X1173678Y134623D02*
X1174382D01*
G01D02*
X1175159Y135400D01*
G01X1174822Y133563D02*
X1175599Y134340D01*
G01X1174382Y134623D02*
X1175159Y135400D01*
G01D02*
X1176901D01*
G01X1175599Y134340D02*
X1176461D01*
G01X1176901Y135400D02*
X1178505Y133796D01*
G01X1176461Y134340D02*
X1177445Y133356D01*
G01X1178505Y133796D02*
Y132054D01*
G01X1177445Y133356D02*
Y132494D01*
G01X1178505Y132054D02*
X1177678Y131227D01*
G01X1177445Y132494D02*
X1176618Y131667D01*
G01X1177678Y131227D02*
Y130523D01*
G01X1176618Y131667D02*
Y130083D01*
G01X1177678Y130523D02*
X1178822Y129379D01*
G01X1176618Y130083D02*
X1178382Y128319D01*
G01X1178822Y129379D02*
X1179526D01*
G01X1178382Y128319D02*
X1179966D01*
G01X1178822Y129379D02*
X1179526D01*
G01D02*
X1180353Y130206D01*
G01X1179966Y128319D02*
X1180793Y129146D01*
G01X1179526Y129379D02*
X1180353Y130206D01*
G01D02*
X1182095D01*
G01X1180793Y129146D02*
X1181655D01*
G01X1182095Y130206D02*
X1183699Y128602D01*
G01X1181655Y129146D02*
X1182639Y128162D01*
G01X1183699Y128602D02*
Y126860D01*
G01X1182639Y128162D02*
Y127300D01*
G01X1183699Y126860D02*
X1182722Y125883D01*
G01X1182639Y127300D02*
X1181662Y126323D01*
G01X1182722Y125883D02*
Y125179D01*
G01X1181662Y126323D02*
Y124739D01*
G01X1182722Y125179D02*
X1183866Y124035D01*
G01X1181662Y124739D02*
X1183426Y122975D01*
G01X1183866Y124035D02*
X1188266D01*
G01X1183426Y122975D02*
X1187826D01*
G01X1188266Y124035D02*
X1191054Y121247D01*
G01X1187826Y122975D02*
X1189994Y120807D01*
G01X1191054Y121247D02*
Y118420D01*
G01Y116180D02*
Y104093D01*
G01Y101853D02*
Y101021D01*
G01X1189994Y120807D02*
Y101464D01*
G01X1191054Y101021D02*
X1187169Y97136D01*
G01X1189994Y101464D02*
X1186109Y97579D01*
G01X1187169Y97136D02*
Y95220D01*
G01X1171300Y144600D02*
X1195094Y120806D01*
G01X1171740Y145660D02*
X1196154Y121246D01*
G01X1195094Y120806D02*
Y100761D01*
G01X1196154Y121246D02*
Y100321D01*
G01X1195094Y100761D02*
X1191309Y96976D01*
G01X1196154Y100321D02*
X1192369Y96536D01*
G01D02*
Y95281D01*
G01X1188000Y172300D02*
X1213059Y147241D01*
G01X1188440Y173360D02*
X1213499Y148301D01*
G01X1213059Y147241D02*
X1223859D01*
G01X1213499Y148301D02*
X1224299D01*
G01X1186941Y181160D02*
X1215466Y152635D01*
G01X1186501Y180100D02*
X1215026Y151575D01*
G01X1215466Y152635D02*
X1225765D01*
G01X1215026Y151575D02*
X1225325D01*
G01X1188440Y173360D02*
X1213499Y148301D01*
G01X1188000Y172300D02*
X1213059Y147241D01*
G01X1213499Y148301D02*
X1224299D01*
G01X1213059Y147241D02*
X1223859D01*
G01X1186501Y180100D02*
X1215026Y151575D01*
G01X1186941Y181160D02*
X1215466Y152635D01*
G01X1215026Y151575D02*
X1225325D01*
G01X1215466Y152635D02*
X1225765D01*
G01X1170001Y140800D02*
X1172251Y138550D01*
G01X1170441Y141860D02*
X1173311Y138990D01*
G01X1172251Y138550D02*
Y137688D01*
G01X1173311Y138990D02*
Y137248D01*
G01X1172251Y137688D02*
X1171474Y136911D01*
G01X1173311Y137248D02*
X1172534Y136471D01*
G01X1171474Y136911D02*
Y135327D01*
G01X1172534Y136471D02*
Y135767D01*
G01X1171474Y135327D02*
X1173238Y133563D01*
G01X1172534Y135767D02*
X1173678Y134623D01*
G01X1173238Y133563D02*
X1174822D01*
G01D02*
X1175599Y134340D01*
G01X1173678Y134623D02*
X1174382D01*
G01X1174822Y133563D02*
X1175599Y134340D01*
G01D02*
X1176461D01*
G01X1174382Y134623D02*
X1175159Y135400D01*
G01X1175599Y134340D02*
X1176461D01*
G01X1175159Y135400D02*
X1176901D01*
G01X1176461Y134340D02*
X1177445Y133356D01*
G01X1176901Y135400D02*
X1178505Y133796D01*
G01X1177445Y133356D02*
Y132494D01*
G01X1178505Y133796D02*
Y132054D01*
G01X1177445Y132494D02*
X1176618Y131667D01*
G01X1178505Y132054D02*
X1177678Y131227D01*
G01X1176618Y131667D02*
Y130083D01*
G01X1177678Y131227D02*
Y130523D01*
G01X1176618Y130083D02*
X1178382Y128319D01*
G01X1177678Y130523D02*
X1178822Y129379D01*
G01X1178382Y128319D02*
X1179966D01*
G01D02*
X1180793Y129146D01*
G01X1178822Y129379D02*
X1179526D01*
G01X1179966Y128319D02*
X1180793Y129146D01*
G01D02*
X1181655D01*
G01X1179526Y129379D02*
X1180353Y130206D01*
G01X1180793Y129146D02*
X1181655D01*
G01X1180353Y130206D02*
X1182095D01*
G01X1181655Y129146D02*
X1182639Y128162D01*
G01X1182095Y130206D02*
X1183699Y128602D01*
G01X1182639Y128162D02*
Y127300D01*
G01X1183699Y128602D02*
Y126860D01*
G01X1182639Y127300D02*
X1181662Y126323D01*
G01X1183699Y126860D02*
X1182722Y125883D01*
G01X1181662Y126323D02*
Y124739D01*
G01X1182722Y125883D02*
Y125179D01*
G01X1181662Y124739D02*
X1183426Y122975D01*
G01X1182722Y125179D02*
X1183866Y124035D01*
G01X1183426Y122975D02*
X1187826D01*
G01X1183866Y124035D02*
X1188266D01*
G01X1187826Y122975D02*
X1189994Y120807D01*
G01X1188266Y124035D02*
X1191054Y121247D01*
G01X1189994Y120807D02*
Y101464D01*
G01X1191054Y121247D02*
Y118420D01*
G01X1189994Y120807D02*
Y101464D01*
G01X1191054Y116180D02*
Y104093D01*
G01X1189994Y120807D02*
Y101464D01*
G01X1191054Y101853D02*
Y101021D01*
G01X1189994Y101464D02*
X1186109Y97579D01*
G01X1191054Y101021D02*
X1187169Y97136D01*
G01D02*
Y95220D01*
G01X1171740Y145660D02*
X1196154Y121246D01*
G01X1171300Y144600D02*
X1195094Y120806D01*
G01X1196154Y121246D02*
Y100321D01*
G01X1195094Y120806D02*
Y100761D01*
G01X1196154Y100321D02*
X1192369Y96536D01*
G01X1195094Y100761D02*
X1191309Y96976D01*
G01X1192369Y96536D02*
Y95281D01*
G01X1170441Y141860D02*
X1173311Y138990D01*
G01X1170001Y140800D02*
X1172251Y138550D01*
G01X1173311Y138990D02*
Y137248D01*
G01X1172251Y138550D02*
Y137688D01*
G01X1173311Y137248D02*
X1172534Y136471D01*
G01X1172251Y137688D02*
X1171474Y136911D01*
G01X1172534Y136471D02*
Y135767D01*
G01X1171474Y136911D02*
Y135327D01*
G01X1172534Y135767D02*
X1173678Y134623D01*
G01X1171474Y135327D02*
X1173238Y133563D01*
G01X1173678Y134623D02*
X1174382D01*
G01X1173238Y133563D02*
X1174822D01*
G01X1173678Y134623D02*
X1174382D01*
G01D02*
X1175159Y135400D01*
G01X1174822Y133563D02*
X1175599Y134340D01*
G01X1174382Y134623D02*
X1175159Y135400D01*
G01D02*
X1176901D01*
G01X1175599Y134340D02*
X1176461D01*
G01X1176901Y135400D02*
X1178505Y133796D01*
G01X1176461Y134340D02*
X1177445Y133356D01*
G01X1178505Y133796D02*
Y132054D01*
G01X1177445Y133356D02*
Y132494D01*
G01X1178505Y132054D02*
X1177678Y131227D01*
G01X1177445Y132494D02*
X1176618Y131667D01*
G01X1177678Y131227D02*
Y130523D01*
G01X1176618Y131667D02*
Y130083D01*
G01X1177678Y130523D02*
X1178822Y129379D01*
G01X1176618Y130083D02*
X1178382Y128319D01*
G01X1178822Y129379D02*
X1179526D01*
G01X1178382Y128319D02*
X1179966D01*
G01X1178822Y129379D02*
X1179526D01*
G01D02*
X1180353Y130206D01*
G01X1179966Y128319D02*
X1180793Y129146D01*
G01X1179526Y129379D02*
X1180353Y130206D01*
G01D02*
X1182095D01*
G01X1180793Y129146D02*
X1181655D01*
G01X1182095Y130206D02*
X1183699Y128602D01*
G01X1181655Y129146D02*
X1182639Y128162D01*
G01X1183699Y128602D02*
Y126860D01*
G01X1182639Y128162D02*
Y127300D01*
G01X1183699Y126860D02*
X1182722Y125883D01*
G01X1182639Y127300D02*
X1181662Y126323D01*
G01X1182722Y125883D02*
Y125179D01*
G01X1181662Y126323D02*
Y124739D01*
G01X1182722Y125179D02*
X1183866Y124035D01*
G01X1181662Y124739D02*
X1183426Y122975D01*
G01X1183866Y124035D02*
X1188266D01*
G01X1183426Y122975D02*
X1187826D01*
G01X1188266Y124035D02*
X1191054Y121247D01*
G01X1187826Y122975D02*
X1189994Y120807D01*
G01X1191054Y121247D02*
Y118420D01*
G01Y116180D02*
Y104093D01*
G01Y101853D02*
Y101021D01*
G01X1189994Y120807D02*
Y101464D01*
G01X1191054Y101021D02*
X1187169Y97136D01*
G01X1189994Y101464D02*
X1186109Y97579D01*
G01X1187169Y97136D02*
Y95220D01*
G01X1171300Y144600D02*
X1195094Y120806D01*
G01X1171740Y145660D02*
X1196154Y121246D01*
G01X1195094Y120806D02*
Y100761D01*
G01X1196154Y121246D02*
Y100321D01*
G01X1195094Y100761D02*
X1191309Y96976D01*
G01X1196154Y100321D02*
X1192369Y96536D01*
G01D02*
Y95281D01*
G01X1188000Y172300D02*
X1213059Y147241D01*
G01X1188440Y173360D02*
X1213499Y148301D01*
G01X1213059Y147241D02*
X1223859D01*
G01X1213499Y148301D02*
X1224299D01*
G01X1186941Y181160D02*
X1215466Y152635D01*
G01X1186501Y180100D02*
X1215026Y151575D01*
G01X1215466Y152635D02*
X1225765D01*
G01X1215026Y151575D02*
X1225325D01*
G01X1188440Y173360D02*
X1213499Y148301D01*
G01X1188000Y172300D02*
X1213059Y147241D01*
G01X1213499Y148301D02*
X1224299D01*
G01X1213059Y147241D02*
X1223859D01*
G01X1186501Y180100D02*
X1215026Y151575D01*
G01X1186941Y181160D02*
X1215466Y152635D01*
G01X1215026Y151575D02*
X1225325D01*
G01X1215466Y152635D02*
X1225765D01*
G01X1158072Y182629D02*
X1168401Y172300D01*
G01X1158512Y183689D02*
X1159219Y182982D01*
G01X1158072Y182629D02*
X1168401Y172300D01*
G01X1159219Y182982D02*
X1159855D01*
G01X1158072Y182629D02*
X1168401Y172300D01*
G01X1160563Y181638D02*
X1161270Y180931D01*
G01X1158072Y182629D02*
X1168401Y172300D01*
G01X1161270Y180931D02*
X1161906D01*
G01X1158072Y182629D02*
X1168401Y172300D01*
G01X1162614Y179587D02*
X1163321Y178880D01*
G01X1158072Y182629D02*
X1168401Y172300D01*
G01X1163321Y178880D02*
X1163957D01*
G01X1158072Y182629D02*
X1168401Y172300D01*
G01X1164665Y177536D02*
X1165372Y176829D01*
G01X1158072Y182629D02*
X1168401Y172300D01*
G01X1165372Y176829D02*
X1166008D01*
G01X1158072Y182629D02*
X1168401Y172300D01*
G01X1166716Y175485D02*
X1168841Y173360D01*
G01X1168401Y172300D02*
X1171911D01*
G01X1168841Y173360D02*
X1171471D01*
G01X1171911Y172300D02*
X1173141Y173530D01*
G01X1171471Y173360D02*
X1172081Y173970D01*
G01X1173141Y173530D02*
Y176530D01*
G01X1172081Y173970D02*
Y176970D01*
G01X1173141Y176530D02*
X1173751Y177140D01*
G01D02*
X1175141D01*
G01X1172081Y176970D02*
X1173311Y178200D01*
G01X1173751Y177140D02*
X1175141D01*
G01X1173311Y178200D02*
X1175581D01*
G01X1173751Y177140D02*
X1175141D01*
G01D02*
X1175751Y176530D01*
G01X1175581Y178200D02*
X1176811Y176970D01*
G01X1175751Y176530D02*
Y173530D01*
G01X1176811Y176970D02*
Y173970D01*
G01X1175751Y173530D02*
X1176981Y172300D01*
G01X1176811Y173970D02*
X1177421Y173360D01*
G01X1176981Y172300D02*
X1188000D01*
G01X1177421Y173360D02*
X1188440D01*
G01X1158253Y186634D02*
X1163166D01*
G01X1157813Y185574D02*
X1162726D01*
G01X1163166Y186634D02*
X1168640Y181160D01*
G01X1162726Y185574D02*
X1168200Y180100D01*
G01X1168640Y181160D02*
X1186941D01*
G01X1168200Y180100D02*
X1186501D01*
G01X1158512Y183689D02*
X1159219Y182982D01*
G01D02*
X1159855D01*
G01X1160563Y181638D02*
X1161270Y180931D01*
G01D02*
X1161906D01*
G01X1162614Y179587D02*
X1163321Y178880D01*
G01D02*
X1163957D01*
G01X1164665Y177536D02*
X1165372Y176829D01*
G01D02*
X1166008D01*
G01X1166716Y175485D02*
X1168841Y173360D01*
G01X1158072Y182629D02*
X1168401Y172300D01*
G01X1168841Y173360D02*
X1171471D01*
G01X1168401Y172300D02*
X1171911D01*
G01X1171471Y173360D02*
X1172081Y173970D01*
G01X1171911Y172300D02*
X1173141Y173530D01*
G01X1172081Y173970D02*
Y176970D01*
G01X1173141Y173530D02*
Y176530D01*
G01X1172081Y176970D02*
X1173311Y178200D01*
G01X1173141Y176530D02*
X1173751Y177140D01*
G01X1172081Y176970D02*
X1173311Y178200D01*
G01D02*
X1175581D01*
G01D02*
X1176811Y176970D01*
G01X1173751Y177140D02*
X1175141D01*
G01X1175581Y178200D02*
X1176811Y176970D01*
G01X1175141Y177140D02*
X1175751Y176530D01*
G01X1176811Y176970D02*
Y173970D01*
G01X1175751Y176530D02*
Y173530D01*
G01X1176811Y173970D02*
X1177421Y173360D01*
G01X1175751Y173530D02*
X1176981Y172300D01*
G01X1177421Y173360D02*
X1188440D01*
G01X1176981Y172300D02*
X1188000D01*
G01X1157813Y185574D02*
X1162726D01*
G01X1158253Y186634D02*
X1163166D01*
G01X1162726Y185574D02*
X1168200Y180100D01*
G01X1163166Y186634D02*
X1168640Y181160D01*
G01X1168200Y180100D02*
X1186501D01*
G01X1168640Y181160D02*
X1186941D01*
G01X1158072Y182629D02*
X1168401Y172300D01*
G01X1158512Y183689D02*
X1159219Y182982D01*
G01X1158072Y182629D02*
X1168401Y172300D01*
G01X1159219Y182982D02*
X1159855D01*
G01X1158072Y182629D02*
X1168401Y172300D01*
G01X1160563Y181638D02*
X1161270Y180931D01*
G01X1158072Y182629D02*
X1168401Y172300D01*
G01X1161270Y180931D02*
X1161906D01*
G01X1158072Y182629D02*
X1168401Y172300D01*
G01X1162614Y179587D02*
X1163321Y178880D01*
G01X1158072Y182629D02*
X1168401Y172300D01*
G01X1163321Y178880D02*
X1163957D01*
G01X1158072Y182629D02*
X1168401Y172300D01*
G01X1164665Y177536D02*
X1165372Y176829D01*
G01X1158072Y182629D02*
X1168401Y172300D01*
G01X1165372Y176829D02*
X1166008D01*
G01X1158072Y182629D02*
X1168401Y172300D01*
G01X1166716Y175485D02*
X1168841Y173360D01*
G01X1168401Y172300D02*
X1171911D01*
G01X1168841Y173360D02*
X1171471D01*
G01X1171911Y172300D02*
X1173141Y173530D01*
G01X1171471Y173360D02*
X1172081Y173970D01*
G01X1173141Y173530D02*
Y176530D01*
G01X1172081Y173970D02*
Y176970D01*
G01X1173141Y176530D02*
X1173751Y177140D01*
G01D02*
X1175141D01*
G01X1172081Y176970D02*
X1173311Y178200D01*
G01X1173751Y177140D02*
X1175141D01*
G01X1173311Y178200D02*
X1175581D01*
G01X1173751Y177140D02*
X1175141D01*
G01D02*
X1175751Y176530D01*
G01X1175581Y178200D02*
X1176811Y176970D01*
G01X1175751Y176530D02*
Y173530D01*
G01X1176811Y176970D02*
Y173970D01*
G01X1175751Y173530D02*
X1176981Y172300D01*
G01X1176811Y173970D02*
X1177421Y173360D01*
G01X1176981Y172300D02*
X1188000D01*
G01X1177421Y173360D02*
X1188440D01*
G01X1158253Y186634D02*
X1163166D01*
G01X1157813Y185574D02*
X1162726D01*
G01X1163166Y186634D02*
X1168640Y181160D01*
G01X1162726Y185574D02*
X1168200Y180100D01*
G01X1168640Y181160D02*
X1186941D01*
G01X1168200Y180100D02*
X1186501D01*
G01X1158512Y183689D02*
X1159219Y182982D01*
G01D02*
X1159855D01*
G01X1160563Y181638D02*
X1161270Y180931D01*
G01D02*
X1161906D01*
G01X1162614Y179587D02*
X1163321Y178880D01*
G01D02*
X1163957D01*
G01X1164665Y177536D02*
X1165372Y176829D01*
G01D02*
X1166008D01*
G01X1166716Y175485D02*
X1168841Y173360D01*
G01X1158072Y182629D02*
X1168401Y172300D01*
G01X1168841Y173360D02*
X1171471D01*
G01X1168401Y172300D02*
X1171911D01*
G01X1171471Y173360D02*
X1172081Y173970D01*
G01X1171911Y172300D02*
X1173141Y173530D01*
G01X1172081Y173970D02*
Y176970D01*
G01X1173141Y173530D02*
Y176530D01*
G01X1172081Y176970D02*
X1173311Y178200D01*
G01X1173141Y176530D02*
X1173751Y177140D01*
G01X1172081Y176970D02*
X1173311Y178200D01*
G01D02*
X1175581D01*
G01D02*
X1176811Y176970D01*
G01X1173751Y177140D02*
X1175141D01*
G01X1175581Y178200D02*
X1176811Y176970D01*
G01X1175141Y177140D02*
X1175751Y176530D01*
G01X1176811Y176970D02*
Y173970D01*
G01X1175751Y176530D02*
Y173530D01*
G01X1176811Y173970D02*
X1177421Y173360D01*
G01X1175751Y173530D02*
X1176981Y172300D01*
G01X1177421Y173360D02*
X1188440D01*
G01X1176981Y172300D02*
X1188000D01*
G01X1157813Y185574D02*
X1162726D01*
G01X1158253Y186634D02*
X1163166D01*
G01X1162726Y185574D02*
X1168200Y180100D01*
G01X1163166Y186634D02*
X1168640Y181160D01*
G01X1168200Y180100D02*
X1186501D01*
G01X1168640Y181160D02*
X1186941D01*
G01X1178831Y463213D02*
X1190010Y474392D01*
G01X1179272Y462154D02*
X1191070Y473952D01*
G01X1159530Y422760D02*
X1174710D01*
G01X1159970Y421700D02*
X1175150D01*
G01X1174710Y422760D02*
X1178210Y426260D01*
G01X1175150Y421700D02*
X1178650Y425200D01*
G01X1178210Y426260D02*
X1185428D01*
G01X1178650Y425200D02*
X1185868D01*
G01X1185428Y426260D02*
X1231160Y471992D01*
G01X1185868Y425200D02*
X1232220Y471552D01*
G01X1164058Y458346D02*
X1164930Y457474D01*
G01X1164498Y459406D02*
X1165990Y457914D01*
G01X1164930Y457474D02*
Y455709D01*
G01X1165990Y457914D02*
Y456152D01*
G01X1164930Y455709D02*
X1166419Y454220D01*
G01X1165990Y456152D02*
X1166862Y455280D01*
G01X1164930Y455709D02*
X1166419Y454220D01*
G01D02*
X1168998D01*
G01X1166862Y455280D02*
X1168558D01*
G01X1168998Y454220D02*
X1170490Y455712D01*
G01X1168558Y455280D02*
X1169430Y456152D01*
G01X1170490Y455712D02*
Y457328D01*
G01X1169430Y456152D02*
Y457768D01*
G01X1170490Y457328D02*
X1171250Y458088D01*
G01X1169430Y457768D02*
X1170810Y459148D01*
G01X1171250Y458088D02*
X1173170D01*
G01X1170810Y459148D02*
X1173610D01*
G01X1173170Y458088D02*
X1173930Y457328D01*
G01X1173610Y459148D02*
X1174990Y457768D01*
G01X1173930Y457328D02*
Y455712D01*
G01X1174990Y457768D02*
Y456152D01*
G01X1173930Y455712D02*
X1175422Y454220D01*
G01X1174990Y456152D02*
X1175862Y455280D01*
G01X1175422Y454220D02*
X1177898D01*
G01D02*
X1196143Y472465D01*
G01X1175862Y455280D02*
X1177458D01*
G01X1177898Y454220D02*
X1196143Y472465D01*
G01X1177458Y455280D02*
X1188200Y466022D01*
G01X1177898Y454220D02*
X1196143Y472465D01*
G01X1177898Y454220D02*
X1196143Y472465D01*
G01X1177898Y454220D02*
X1196143Y472465D01*
G01X1177898Y454220D02*
X1196143Y472465D01*
G01X1177898Y454220D02*
X1196143Y472465D01*
G01X1177898Y454220D02*
X1196143Y472465D01*
G01X1157120Y414500D02*
X1161270Y418650D01*
G01D02*
X1176550D01*
G01X1160830Y419710D02*
X1176110D01*
G01X1176550Y418650D02*
X1179900Y422000D01*
G01X1176110Y419710D02*
X1179460Y423060D01*
G01X1179900Y422000D02*
X1188368D01*
G01X1179460Y423060D02*
X1187928D01*
G01X1188368Y422000D02*
X1222453Y456085D01*
G01X1187928Y423060D02*
X1222013Y457145D01*
G01X1179272Y462154D02*
X1191070Y473952D01*
G01X1178831Y463213D02*
X1190010Y474392D01*
G01X1159970Y421700D02*
X1175150D01*
G01X1159530Y422760D02*
X1174710D01*
G01X1175150Y421700D02*
X1178650Y425200D01*
G01X1174710Y422760D02*
X1178210Y426260D01*
G01X1178650Y425200D02*
X1185868D01*
G01X1178210Y426260D02*
X1185428D01*
G01X1185868Y425200D02*
X1232220Y471552D01*
G01X1185428Y426260D02*
X1231160Y471992D01*
G01X1164498Y459406D02*
X1165990Y457914D01*
G01X1164058Y458346D02*
X1164930Y457474D01*
G01X1165990Y457914D02*
Y456152D01*
G01X1164930Y457474D02*
Y455709D01*
G01X1165990Y456152D02*
X1166862Y455280D01*
G01D02*
X1168558D01*
G01X1164930Y455709D02*
X1166419Y454220D01*
G01X1166862Y455280D02*
X1168558D01*
G01X1166419Y454220D02*
X1168998D01*
G01X1168558Y455280D02*
X1169430Y456152D01*
G01X1168998Y454220D02*
X1170490Y455712D01*
G01X1169430Y456152D02*
Y457768D01*
G01X1170490Y455712D02*
Y457328D01*
G01X1169430Y457768D02*
X1170810Y459148D01*
G01X1170490Y457328D02*
X1171250Y458088D01*
G01X1170810Y459148D02*
X1173610D01*
G01X1171250Y458088D02*
X1173170D01*
G01X1173610Y459148D02*
X1174990Y457768D01*
G01X1173170Y458088D02*
X1173930Y457328D01*
G01X1174990Y457768D02*
Y456152D01*
G01X1173930Y457328D02*
Y455712D01*
G01X1174990Y456152D02*
X1175862Y455280D01*
G01X1173930Y455712D02*
X1175422Y454220D01*
G01X1175862Y455280D02*
X1177458D01*
G01X1175422Y454220D02*
X1177898D01*
G01X1175862Y455280D02*
X1177458D01*
G01D02*
X1188200Y466022D01*
G01X1177898Y454220D02*
X1196143Y472465D01*
G01X1157120Y414500D02*
X1161270Y418650D01*
G01X1160830Y419710D02*
X1176110D01*
G01X1161270Y418650D02*
X1176550D01*
G01X1176110Y419710D02*
X1179460Y423060D01*
G01X1176550Y418650D02*
X1179900Y422000D01*
G01X1179460Y423060D02*
X1187928D01*
G01X1179900Y422000D02*
X1188368D01*
G01X1187928Y423060D02*
X1222013Y457145D01*
G01X1188368Y422000D02*
X1222453Y456085D01*
G01X1178831Y463213D02*
X1190010Y474392D01*
G01X1179272Y462154D02*
X1191070Y473952D01*
G01X1164058Y458346D02*
X1164930Y457474D01*
G01X1164498Y459406D02*
X1165990Y457914D01*
G01X1164930Y457474D02*
Y455709D01*
G01X1165990Y457914D02*
Y456152D01*
G01X1164930Y455709D02*
X1166419Y454220D01*
G01X1165990Y456152D02*
X1166862Y455280D01*
G01X1164930Y455709D02*
X1166419Y454220D01*
G01D02*
X1168998D01*
G01X1166862Y455280D02*
X1168558D01*
G01X1168998Y454220D02*
X1170490Y455712D01*
G01X1168558Y455280D02*
X1169430Y456152D01*
G01X1170490Y455712D02*
Y457328D01*
G01X1169430Y456152D02*
Y457768D01*
G01X1170490Y457328D02*
X1171250Y458088D01*
G01X1169430Y457768D02*
X1170810Y459148D01*
G01X1171250Y458088D02*
X1173170D01*
G01X1170810Y459148D02*
X1173610D01*
G01X1173170Y458088D02*
X1173930Y457328D01*
G01X1173610Y459148D02*
X1174990Y457768D01*
G01X1173930Y457328D02*
Y455712D01*
G01X1174990Y457768D02*
Y456152D01*
G01X1173930Y455712D02*
X1175422Y454220D01*
G01X1174990Y456152D02*
X1175862Y455280D01*
G01X1175422Y454220D02*
X1177898D01*
G01D02*
X1196143Y472465D01*
G01X1175862Y455280D02*
X1177458D01*
G01X1177898Y454220D02*
X1196143Y472465D01*
G01X1177458Y455280D02*
X1188200Y466022D01*
G01X1177898Y454220D02*
X1196143Y472465D01*
G01X1177898Y454220D02*
X1196143Y472465D01*
G01X1177898Y454220D02*
X1196143Y472465D01*
G01X1177898Y454220D02*
X1196143Y472465D01*
G01X1177898Y454220D02*
X1196143Y472465D01*
G01X1177898Y454220D02*
X1196143Y472465D01*
G01X1179272Y462154D02*
X1191070Y473952D01*
G01X1178831Y463213D02*
X1190010Y474392D01*
G01X1164498Y459406D02*
X1165990Y457914D01*
G01X1164058Y458346D02*
X1164930Y457474D01*
G01X1165990Y457914D02*
Y456152D01*
G01X1164930Y457474D02*
Y455709D01*
G01X1165990Y456152D02*
X1166862Y455280D01*
G01D02*
X1168558D01*
G01X1164930Y455709D02*
X1166419Y454220D01*
G01X1166862Y455280D02*
X1168558D01*
G01X1166419Y454220D02*
X1168998D01*
G01X1168558Y455280D02*
X1169430Y456152D01*
G01X1168998Y454220D02*
X1170490Y455712D01*
G01X1169430Y456152D02*
Y457768D01*
G01X1170490Y455712D02*
Y457328D01*
G01X1169430Y457768D02*
X1170810Y459148D01*
G01X1170490Y457328D02*
X1171250Y458088D01*
G01X1170810Y459148D02*
X1173610D01*
G01X1171250Y458088D02*
X1173170D01*
G01X1173610Y459148D02*
X1174990Y457768D01*
G01X1173170Y458088D02*
X1173930Y457328D01*
G01X1174990Y457768D02*
Y456152D01*
G01X1173930Y457328D02*
Y455712D01*
G01X1174990Y456152D02*
X1175862Y455280D01*
G01X1173930Y455712D02*
X1175422Y454220D01*
G01X1175862Y455280D02*
X1177458D01*
G01X1175422Y454220D02*
X1177898D01*
G01X1175862Y455280D02*
X1177458D01*
G01D02*
X1188200Y466022D01*
G01X1177898Y454220D02*
X1196143Y472465D01*
G01X1159530Y422760D02*
X1174710D01*
G01X1159970Y421700D02*
X1175150D01*
G01X1174710Y422760D02*
X1178210Y426260D01*
G01X1175150Y421700D02*
X1178650Y425200D01*
G01X1178210Y426260D02*
X1185428D01*
G01X1178650Y425200D02*
X1185868D01*
G01X1185428Y426260D02*
X1231160Y471992D01*
G01X1185868Y425200D02*
X1232220Y471552D01*
G01X1157120Y414500D02*
X1161270Y418650D01*
G01D02*
X1176550D01*
G01X1160830Y419710D02*
X1176110D01*
G01X1176550Y418650D02*
X1179900Y422000D01*
G01X1176110Y419710D02*
X1179460Y423060D01*
G01X1179900Y422000D02*
X1188368D01*
G01X1179460Y423060D02*
X1187928D01*
G01X1188368Y422000D02*
X1222453Y456085D01*
G01X1187928Y423060D02*
X1222013Y457145D01*
G01X1159970Y421700D02*
X1175150D01*
G01X1159530Y422760D02*
X1174710D01*
G01X1175150Y421700D02*
X1178650Y425200D01*
G01X1174710Y422760D02*
X1178210Y426260D01*
G01X1178650Y425200D02*
X1185868D01*
G01X1178210Y426260D02*
X1185428D01*
G01X1185868Y425200D02*
X1232220Y471552D01*
G01X1185428Y426260D02*
X1231160Y471992D01*
G01X1157120Y414500D02*
X1161270Y418650D01*
G01X1160830Y419710D02*
X1176110D01*
G01X1161270Y418650D02*
X1176550D01*
G01X1176110Y419710D02*
X1179460Y423060D01*
G01X1176550Y418650D02*
X1179900Y422000D01*
G01X1179460Y423060D02*
X1187928D01*
G01X1179900Y422000D02*
X1188368D01*
G01X1187928Y423060D02*
X1222013Y457145D01*
G01X1188368Y422000D02*
X1222453Y456085D01*
G01X1157973Y487464D02*
X1159632Y489123D01*
G01X1157973Y487464D02*
X1159632Y489123D01*
G01X1157533Y488524D02*
X1158572Y489563D01*
G01X1159632Y489123D02*
Y512134D01*
G01X1158572Y489563D02*
Y492740D01*
G01X1159632Y489123D02*
Y512134D01*
G01X1158572Y494716D02*
Y496275D01*
G01X1159632Y489123D02*
Y512134D01*
G01X1158572Y498183D02*
Y500443D01*
G01X1159632Y489123D02*
Y512134D01*
G01X1158572Y502683D02*
Y503683D01*
G01X1159632Y489123D02*
Y512134D01*
G01X1158572Y505923D02*
Y506923D01*
G01X1159632Y489123D02*
Y512134D01*
G01X1158572Y509163D02*
Y511694D01*
G01D02*
X1157352Y512914D01*
G01X1157533Y488524D02*
X1158572Y489563D01*
G01X1157973Y487464D02*
X1159632Y489123D01*
G01X1158572Y489563D02*
Y492740D01*
G01Y494716D02*
Y496275D01*
G01Y498183D02*
Y500443D01*
G01Y502683D02*
Y503683D01*
G01Y505923D02*
Y506923D01*
G01Y509163D02*
Y511694D01*
G01X1159632Y489123D02*
Y512134D01*
G01X1158572Y511694D02*
X1157352Y512914D01*
G01X1185975Y514400D02*
Y532411D01*
G01X1187035Y520290D02*
Y521660D01*
G01X1185975Y514400D02*
Y532411D01*
G01X1187035Y525340D02*
Y526760D01*
G01X1190010Y474392D02*
Y506416D01*
G01Y508656D02*
Y511753D01*
G01X1191070Y473952D02*
Y512193D01*
G01X1190010Y511753D02*
X1189063Y512700D01*
G01D02*
X1187963D01*
G01X1191070Y512193D02*
X1187963Y515300D01*
G01X1192259Y519900D02*
X1191588Y520571D01*
G01X1191358Y519300D02*
X1190528Y520130D01*
G01X1191588Y520571D02*
Y521848D01*
G01Y525338D02*
Y526229D01*
G01X1190528Y520130D02*
Y526670D01*
G01X1191588Y526229D02*
X1192359Y527000D01*
G01X1188928Y467600D02*
X1189778D01*
G01D02*
X1190600Y468422D01*
G01X1191328Y470000D02*
X1192178D01*
G01D02*
X1192900Y470722D01*
G01X1193528Y472200D02*
X1194378D01*
G01D02*
X1195083Y472905D01*
G01X1196143Y472465D02*
Y512434D01*
G01X1195083Y472905D02*
Y474980D01*
G01X1196143Y472465D02*
Y512434D01*
G01X1195083Y477100D02*
Y478220D01*
G01X1196143Y472465D02*
Y512434D01*
G01X1195083Y480340D02*
Y481460D01*
G01X1196143Y472465D02*
Y512434D01*
G01X1195083Y483580D02*
Y484700D01*
G01X1196143Y472465D02*
Y512434D01*
G01X1195083Y486820D02*
Y487940D01*
G01X1196143Y472465D02*
Y512434D01*
G01X1195083Y490060D02*
Y499816D01*
G01X1196143Y472465D02*
Y512434D01*
G01X1195083Y502284D02*
Y503516D01*
G01X1196143Y472465D02*
Y512434D01*
G01X1195083Y505784D02*
Y506916D01*
G01X1196143Y472465D02*
Y512434D01*
G01X1195083Y509260D02*
Y511994D01*
G01X1196143Y512434D02*
X1193063Y515514D01*
G01X1195083Y511994D02*
X1193967Y513110D01*
G01X1196143Y512434D02*
X1193063Y515514D01*
G01X1193967Y513110D02*
X1193259D01*
G01X1187035Y520290D02*
Y521660D01*
G01Y525340D02*
Y526760D01*
G01X1185975Y514400D02*
Y532411D01*
G01X1191070Y473952D02*
Y512193D01*
G01X1190010Y474392D02*
Y506416D01*
G01X1191070Y473952D02*
Y512193D01*
G01X1190010Y508656D02*
Y511753D01*
G01X1191070Y512193D02*
X1187963Y515300D01*
G01X1190010Y511753D02*
X1189063Y512700D01*
G01X1191070Y512193D02*
X1187963Y515300D01*
G01X1189063Y512700D02*
X1187963D01*
G01X1191358Y519300D02*
X1190528Y520130D01*
G01X1192259Y519900D02*
X1191588Y520571D01*
G01X1190528Y520130D02*
Y526670D01*
G01X1191588Y520571D02*
Y521848D01*
G01X1190528Y520130D02*
Y526670D01*
G01X1191588Y525338D02*
Y526229D01*
G01D02*
X1192359Y527000D01*
G01X1188928Y467600D02*
X1189778D01*
G01D02*
X1190600Y468422D01*
G01X1191328Y470000D02*
X1192178D01*
G01D02*
X1192900Y470722D01*
G01X1193528Y472200D02*
X1194378D01*
G01D02*
X1195083Y472905D01*
G01D02*
Y474980D01*
G01Y477100D02*
Y478220D01*
G01Y480340D02*
Y481460D01*
G01Y483580D02*
Y484700D01*
G01Y486820D02*
Y487940D01*
G01Y490060D02*
Y499816D01*
G01Y502284D02*
Y503516D01*
G01Y505784D02*
Y506916D01*
G01Y509260D02*
Y511994D01*
G01X1196143Y472465D02*
Y512434D01*
G01X1195083Y511994D02*
X1193967Y513110D01*
G01D02*
X1193259D01*
G01X1196143Y512434D02*
X1193063Y515514D01*
G01X1157973Y487464D02*
X1159632Y489123D01*
G01X1157973Y487464D02*
X1159632Y489123D01*
G01X1157533Y488524D02*
X1158572Y489563D01*
G01X1159632Y489123D02*
Y512134D01*
G01X1158572Y489563D02*
Y492740D01*
G01X1159632Y489123D02*
Y512134D01*
G01X1158572Y494716D02*
Y496275D01*
G01X1159632Y489123D02*
Y512134D01*
G01X1158572Y498183D02*
Y500443D01*
G01X1159632Y489123D02*
Y512134D01*
G01X1158572Y502683D02*
Y503683D01*
G01X1159632Y489123D02*
Y512134D01*
G01X1158572Y505923D02*
Y506923D01*
G01X1159632Y489123D02*
Y512134D01*
G01X1158572Y509163D02*
Y511694D01*
G01D02*
X1157352Y512914D01*
G01X1157533Y488524D02*
X1158572Y489563D01*
G01X1157973Y487464D02*
X1159632Y489123D01*
G01X1158572Y489563D02*
Y492740D01*
G01Y494716D02*
Y496275D01*
G01Y498183D02*
Y500443D01*
G01Y502683D02*
Y503683D01*
G01Y505923D02*
Y506923D01*
G01Y509163D02*
Y511694D01*
G01X1159632Y489123D02*
Y512134D01*
G01X1158572Y511694D02*
X1157352Y512914D01*
G01X1185975Y514400D02*
Y532411D01*
G01X1187035Y520290D02*
Y521660D01*
G01X1185975Y514400D02*
Y532411D01*
G01X1187035Y525340D02*
Y526760D01*
G01X1190010Y474392D02*
Y506416D01*
G01Y508656D02*
Y511753D01*
G01X1191070Y473952D02*
Y512193D01*
G01X1190010Y511753D02*
X1189063Y512700D01*
G01D02*
X1187963D01*
G01X1191070Y512193D02*
X1187963Y515300D01*
G01X1192259Y519900D02*
X1191588Y520571D01*
G01X1191358Y519300D02*
X1190528Y520130D01*
G01X1191588Y520571D02*
Y521848D01*
G01Y525338D02*
Y526229D01*
G01X1190528Y520130D02*
Y526670D01*
G01X1191588Y526229D02*
X1192359Y527000D01*
G01X1188928Y467600D02*
X1189778D01*
G01D02*
X1190600Y468422D01*
G01X1191328Y470000D02*
X1192178D01*
G01D02*
X1192900Y470722D01*
G01X1193528Y472200D02*
X1194378D01*
G01D02*
X1195083Y472905D01*
G01X1196143Y472465D02*
Y512434D01*
G01X1195083Y472905D02*
Y474980D01*
G01X1196143Y472465D02*
Y512434D01*
G01X1195083Y477100D02*
Y478220D01*
G01X1196143Y472465D02*
Y512434D01*
G01X1195083Y480340D02*
Y481460D01*
G01X1196143Y472465D02*
Y512434D01*
G01X1195083Y483580D02*
Y484700D01*
G01X1196143Y472465D02*
Y512434D01*
G01X1195083Y486820D02*
Y487940D01*
G01X1196143Y472465D02*
Y512434D01*
G01X1195083Y490060D02*
Y499816D01*
G01X1196143Y472465D02*
Y512434D01*
G01X1195083Y502284D02*
Y503516D01*
G01X1196143Y472465D02*
Y512434D01*
G01X1195083Y505784D02*
Y506916D01*
G01X1196143Y472465D02*
Y512434D01*
G01X1195083Y509260D02*
Y511994D01*
G01X1196143Y512434D02*
X1193063Y515514D01*
G01X1195083Y511994D02*
X1193967Y513110D01*
G01X1196143Y512434D02*
X1193063Y515514D01*
G01X1193967Y513110D02*
X1193259D01*
G01X1187035Y520290D02*
Y521660D01*
G01Y525340D02*
Y526760D01*
G01X1185975Y514400D02*
Y532411D01*
G01X1191070Y473952D02*
Y512193D01*
G01X1190010Y474392D02*
Y506416D01*
G01X1191070Y473952D02*
Y512193D01*
G01X1190010Y508656D02*
Y511753D01*
G01X1191070Y512193D02*
X1187963Y515300D01*
G01X1190010Y511753D02*
X1189063Y512700D01*
G01X1191070Y512193D02*
X1187963Y515300D01*
G01X1189063Y512700D02*
X1187963D01*
G01X1191358Y519300D02*
X1190528Y520130D01*
G01X1192259Y519900D02*
X1191588Y520571D01*
G01X1190528Y520130D02*
Y526670D01*
G01X1191588Y520571D02*
Y521848D01*
G01X1190528Y520130D02*
Y526670D01*
G01X1191588Y525338D02*
Y526229D01*
G01D02*
X1192359Y527000D01*
G01X1188928Y467600D02*
X1189778D01*
G01D02*
X1190600Y468422D01*
G01X1191328Y470000D02*
X1192178D01*
G01D02*
X1192900Y470722D01*
G01X1193528Y472200D02*
X1194378D01*
G01D02*
X1195083Y472905D01*
G01D02*
Y474980D01*
G01Y477100D02*
Y478220D01*
G01Y480340D02*
Y481460D01*
G01Y483580D02*
Y484700D01*
G01Y486820D02*
Y487940D01*
G01Y490060D02*
Y499816D01*
G01Y502284D02*
Y503516D01*
G01Y505784D02*
Y506916D01*
G01Y509260D02*
Y511994D01*
G01X1196143Y472465D02*
Y512434D01*
G01X1195083Y511994D02*
X1193967Y513110D01*
G01D02*
X1193259D01*
G01X1196143Y512434D02*
X1193063Y515514D01*
G01X1190528Y526670D02*
X1191358Y527500D01*
G01X1190528Y526670D02*
X1191358Y527500D01*
G01X1190528Y526670D02*
X1191358Y527500D01*
G01X1190528Y526670D02*
X1191358Y527500D01*
G01X1225873Y87300D02*
X1226820Y86353D01*
G01X1224774Y89900D02*
X1227880Y86794D01*
G01X1226820Y86353D02*
Y83820D01*
G01Y79680D02*
Y78720D01*
G01Y74380D02*
Y71091D01*
G01X1227880Y86794D02*
Y70648D01*
G01X1226820Y71091D02*
X1226109Y70380D01*
G01X1227880Y70648D02*
X1226552Y69320D01*
G01X1226109Y70380D02*
X1225593D01*
G01X1226552Y69320D02*
X1225570D01*
G01X1223200Y96900D02*
Y93661D01*
G01X1229874Y90114D02*
X1233066Y86922D01*
G01X1229874Y87515D02*
X1230972D01*
G01X1229874Y90114D02*
X1233066Y86922D01*
G01X1230972Y87515D02*
X1232006Y86481D01*
G01X1233066Y86922D02*
Y71532D01*
G01X1232006Y86481D02*
Y83706D01*
G01X1233066Y86922D02*
Y71532D01*
G01X1232006Y79880D02*
Y78507D01*
G01X1233066Y86922D02*
Y71532D01*
G01X1232006Y74593D02*
Y71972D01*
G01X1233066Y71532D02*
X1229874Y68340D01*
G01X1232006Y71972D02*
X1230983Y70949D01*
G01X1228150Y96350D02*
Y89238D01*
G01X1224774Y89900D02*
X1227880Y86794D01*
G01X1225873Y87300D02*
X1226820Y86353D01*
G01X1227880Y86794D02*
Y70648D01*
G01X1226820Y86353D02*
Y83820D01*
G01X1227880Y86794D02*
Y70648D01*
G01X1226820Y79680D02*
Y78720D01*
G01X1227880Y86794D02*
Y70648D01*
G01X1226820Y74380D02*
Y71091D01*
G01X1227880Y70648D02*
X1226552Y69320D01*
G01X1226820Y71091D02*
X1226109Y70380D01*
G01X1226552Y69320D02*
X1225570D01*
G01X1226109Y70380D02*
X1225593D01*
G01X1223200Y96900D02*
Y93661D01*
G01X1229874Y87515D02*
X1230972D01*
G01D02*
X1232006Y86481D01*
G01X1229874Y90114D02*
X1233066Y86922D01*
G01X1232006Y86481D02*
Y83706D01*
G01Y79880D02*
Y78507D01*
G01Y74593D02*
Y71972D01*
G01X1233066Y86922D02*
Y71532D01*
G01X1232006Y71972D02*
X1230983Y70949D01*
G01X1233066Y71532D02*
X1229874Y68340D01*
G01X1228150Y96350D02*
Y89238D01*
G01X1225873Y87300D02*
X1226820Y86353D01*
G01X1224774Y89900D02*
X1227880Y86794D01*
G01X1226820Y86353D02*
Y83820D01*
G01Y79680D02*
Y78720D01*
G01Y74380D02*
Y71091D01*
G01X1227880Y86794D02*
Y70648D01*
G01X1226820Y71091D02*
X1226109Y70380D01*
G01X1227880Y70648D02*
X1226552Y69320D01*
G01X1226109Y70380D02*
X1225593D01*
G01X1226552Y69320D02*
X1225570D01*
G01X1223200Y96900D02*
Y93661D01*
G01X1229874Y90114D02*
X1233066Y86922D01*
G01X1229874Y87515D02*
X1230972D01*
G01X1229874Y90114D02*
X1233066Y86922D01*
G01X1230972Y87515D02*
X1232006Y86481D01*
G01X1233066Y86922D02*
Y71532D01*
G01X1232006Y86481D02*
Y83706D01*
G01X1233066Y86922D02*
Y71532D01*
G01X1232006Y79880D02*
Y78507D01*
G01X1233066Y86922D02*
Y71532D01*
G01X1232006Y74593D02*
Y71972D01*
G01X1233066Y71532D02*
X1229874Y68340D01*
G01X1232006Y71972D02*
X1230983Y70949D01*
G01X1228150Y96350D02*
Y89238D01*
G01X1224774Y89900D02*
X1227880Y86794D01*
G01X1225873Y87300D02*
X1226820Y86353D01*
G01X1227880Y86794D02*
Y70648D01*
G01X1226820Y86353D02*
Y83820D01*
G01X1227880Y86794D02*
Y70648D01*
G01X1226820Y79680D02*
Y78720D01*
G01X1227880Y86794D02*
Y70648D01*
G01X1226820Y74380D02*
Y71091D01*
G01X1227880Y70648D02*
X1226552Y69320D01*
G01X1226820Y71091D02*
X1226109Y70380D01*
G01X1226552Y69320D02*
X1225570D01*
G01X1226109Y70380D02*
X1225593D01*
G01X1223200Y96900D02*
Y93661D01*
G01X1229874Y87515D02*
X1230972D01*
G01D02*
X1232006Y86481D01*
G01X1229874Y90114D02*
X1233066Y86922D01*
G01X1232006Y86481D02*
Y83706D01*
G01Y79880D02*
Y78507D01*
G01Y74593D02*
Y71972D01*
G01X1233066Y86922D02*
Y71532D01*
G01X1232006Y71972D02*
X1230983Y70949D01*
G01X1233066Y71532D02*
X1229874Y68340D01*
G01X1228150Y96350D02*
Y89238D01*
G01X1223859Y147241D02*
X1226000Y145100D01*
G01X1224299Y148301D02*
X1227060Y145540D01*
G01X1226000Y145100D02*
Y99700D01*
G01X1227060Y145540D02*
Y104150D01*
G01X1226000Y99700D02*
X1223200Y96900D01*
G01X1227510Y99710D02*
X1224260Y96460D01*
G01D02*
Y94940D01*
G01X1225765Y152635D02*
X1231060Y147340D01*
G01X1225325Y151575D02*
X1230000Y146900D01*
G01X1231060Y147340D02*
Y97760D01*
G01X1230000Y146900D02*
Y98200D01*
G01X1231060Y97760D02*
X1229210Y95910D01*
G01X1230000Y98200D02*
X1228150Y96350D01*
G01X1229210Y95910D02*
Y95290D01*
G01X1224299Y148301D02*
X1227060Y145540D01*
G01X1223859Y147241D02*
X1226000Y145100D01*
G01X1227060Y145540D02*
Y104150D01*
G01X1226000Y145100D02*
Y99700D01*
G01X1227510Y99710D02*
X1224260Y96460D01*
G01X1226000Y99700D02*
X1223200Y96900D01*
G01X1224260Y96460D02*
Y94940D01*
G01X1225325Y151575D02*
X1230000Y146900D01*
G01X1225765Y152635D02*
X1231060Y147340D01*
G01X1230000Y146900D02*
Y98200D01*
G01X1231060Y147340D02*
Y97760D01*
G01X1230000Y98200D02*
X1228150Y96350D01*
G01X1231060Y97760D02*
X1229210Y95910D01*
G01D02*
Y95290D01*
G01X1223859Y147241D02*
X1226000Y145100D01*
G01X1224299Y148301D02*
X1227060Y145540D01*
G01X1226000Y145100D02*
Y99700D01*
G01X1227060Y145540D02*
Y104150D01*
G01X1226000Y99700D02*
X1223200Y96900D01*
G01X1227510Y99710D02*
X1224260Y96460D01*
G01D02*
Y94940D01*
G01X1225765Y152635D02*
X1231060Y147340D01*
G01X1225325Y151575D02*
X1230000Y146900D01*
G01X1231060Y147340D02*
Y97760D01*
G01X1230000Y146900D02*
Y98200D01*
G01X1231060Y97760D02*
X1229210Y95910D01*
G01X1230000Y98200D02*
X1228150Y96350D01*
G01X1229210Y95910D02*
Y95290D01*
G01X1224299Y148301D02*
X1227060Y145540D01*
G01X1223859Y147241D02*
X1226000Y145100D01*
G01X1227060Y145540D02*
Y104150D01*
G01X1226000Y145100D02*
Y99700D01*
G01X1227510Y99710D02*
X1224260Y96460D01*
G01X1226000Y99700D02*
X1223200Y96900D01*
G01X1224260Y96460D02*
Y94940D01*
G01X1225325Y151575D02*
X1230000Y146900D01*
G01X1225765Y152635D02*
X1231060Y147340D01*
G01X1230000Y146900D02*
Y98200D01*
G01X1231060Y147340D02*
Y97760D01*
G01X1230000Y98200D02*
X1228150Y96350D01*
G01X1231060Y97760D02*
X1229210Y95910D01*
G01D02*
Y95290D01*
G01X1222453Y456085D02*
X1223684D01*
G01X1222013Y457145D02*
X1224127D01*
G01X1223684Y456085D02*
X1224745Y455024D01*
G01X1224127Y457145D02*
X1225188Y456084D01*
G01X1224745Y455024D02*
X1226857D01*
G01X1225188Y456084D02*
X1226414D01*
G01X1226857Y455024D02*
X1229248Y457415D01*
G01X1226414Y456084D02*
X1228188Y457858D01*
G01X1229248Y457415D02*
Y459527D01*
G01X1228188Y457858D02*
Y459084D01*
G01X1229248Y459527D02*
X1228280Y460495D01*
G01X1228188Y459084D02*
X1227220Y460052D01*
G01X1228280Y460495D02*
Y461909D01*
G01X1227220Y460052D02*
Y462349D01*
G01X1228280Y461909D02*
X1229956Y463585D01*
G01X1227220Y462349D02*
X1229516Y464645D01*
G01X1229956Y463585D02*
X1231187D01*
G01X1229516Y464645D02*
X1231627D01*
G01X1229956Y463585D02*
X1231187D01*
G01D02*
X1232305Y462467D01*
G01X1231627Y464645D02*
X1232745Y463527D01*
G01X1232305Y462467D02*
X1234416D01*
G01X1232745Y463527D02*
X1233976D01*
G01X1234416Y462467D02*
X1237180Y465231D01*
G01X1233976Y463527D02*
X1236120Y465671D01*
G01X1222013Y457145D02*
X1224127D01*
G01X1222453Y456085D02*
X1223684D01*
G01X1224127Y457145D02*
X1225188Y456084D01*
G01X1223684Y456085D02*
X1224745Y455024D01*
G01X1225188Y456084D02*
X1226414D01*
G01X1224745Y455024D02*
X1226857D01*
G01X1226414Y456084D02*
X1228188Y457858D01*
G01X1226857Y455024D02*
X1229248Y457415D01*
G01X1228188Y457858D02*
Y459084D01*
G01X1229248Y457415D02*
Y459527D01*
G01X1228188Y459084D02*
X1227220Y460052D01*
G01X1229248Y459527D02*
X1228280Y460495D01*
G01X1227220Y460052D02*
Y462349D01*
G01X1228280Y460495D02*
Y461909D01*
G01X1227220Y462349D02*
X1229516Y464645D01*
G01X1228280Y461909D02*
X1229956Y463585D01*
G01X1229516Y464645D02*
X1231627D01*
G01D02*
X1232745Y463527D01*
G01X1229956Y463585D02*
X1231187D01*
G01X1231627Y464645D02*
X1232745Y463527D01*
G01X1231187Y463585D02*
X1232305Y462467D01*
G01X1232745Y463527D02*
X1233976D01*
G01X1232305Y462467D02*
X1234416D01*
G01X1233976Y463527D02*
X1236120Y465671D01*
G01X1234416Y462467D02*
X1237180Y465231D01*
G01X1222453Y456085D02*
X1223684D01*
G01X1222013Y457145D02*
X1224127D01*
G01X1223684Y456085D02*
X1224745Y455024D01*
G01X1224127Y457145D02*
X1225188Y456084D01*
G01X1224745Y455024D02*
X1226857D01*
G01X1225188Y456084D02*
X1226414D01*
G01X1226857Y455024D02*
X1229248Y457415D01*
G01X1226414Y456084D02*
X1228188Y457858D01*
G01X1229248Y457415D02*
Y459527D01*
G01X1228188Y457858D02*
Y459084D01*
G01X1229248Y459527D02*
X1228280Y460495D01*
G01X1228188Y459084D02*
X1227220Y460052D01*
G01X1228280Y460495D02*
Y461909D01*
G01X1227220Y460052D02*
Y462349D01*
G01X1228280Y461909D02*
X1229956Y463585D01*
G01X1227220Y462349D02*
X1229516Y464645D01*
G01X1229956Y463585D02*
X1231187D01*
G01X1229516Y464645D02*
X1231627D01*
G01X1229956Y463585D02*
X1231187D01*
G01D02*
X1232305Y462467D01*
G01X1231627Y464645D02*
X1232745Y463527D01*
G01X1232305Y462467D02*
X1234416D01*
G01X1232745Y463527D02*
X1233976D01*
G01X1234416Y462467D02*
X1237180Y465231D01*
G01X1233976Y463527D02*
X1236120Y465671D01*
G01X1222013Y457145D02*
X1224127D01*
G01X1222453Y456085D02*
X1223684D01*
G01X1224127Y457145D02*
X1225188Y456084D01*
G01X1223684Y456085D02*
X1224745Y455024D01*
G01X1225188Y456084D02*
X1226414D01*
G01X1224745Y455024D02*
X1226857D01*
G01X1226414Y456084D02*
X1228188Y457858D01*
G01X1226857Y455024D02*
X1229248Y457415D01*
G01X1228188Y457858D02*
Y459084D01*
G01X1229248Y457415D02*
Y459527D01*
G01X1228188Y459084D02*
X1227220Y460052D01*
G01X1229248Y459527D02*
X1228280Y460495D01*
G01X1227220Y460052D02*
Y462349D01*
G01X1228280Y460495D02*
Y461909D01*
G01X1227220Y462349D02*
X1229516Y464645D01*
G01X1228280Y461909D02*
X1229956Y463585D01*
G01X1229516Y464645D02*
X1231627D01*
G01D02*
X1232745Y463527D01*
G01X1229956Y463585D02*
X1231187D01*
G01X1231627Y464645D02*
X1232745Y463527D01*
G01X1231187Y463585D02*
X1232305Y462467D01*
G01X1232745Y463527D02*
X1233976D01*
G01X1232305Y462467D02*
X1234416D01*
G01X1233976Y463527D02*
X1236120Y465671D01*
G01X1234416Y462467D02*
X1237180Y465231D01*
G01X1222786Y514400D02*
Y532411D01*
G01X1223846Y520290D02*
Y521660D01*
G01X1222786Y514400D02*
Y532411D01*
G01X1223846Y525340D02*
Y526760D01*
G01X1231160Y471992D02*
Y479951D01*
G01Y481883D02*
Y483059D01*
G01Y485299D02*
Y486299D01*
G01Y488539D02*
Y489539D01*
G01Y491779D02*
Y492779D01*
G01Y495019D02*
Y496019D01*
G01Y498259D02*
Y499259D01*
G01Y501499D02*
Y502711D01*
G01X1232220Y471552D02*
Y503151D01*
G01X1231160Y502711D02*
X1229799Y504072D01*
G01X1228512Y505359D02*
X1226894Y506977D01*
G01X1232220Y503151D02*
X1227954Y507417D01*
G01X1226894Y506977D02*
Y511680D01*
G01X1227954Y507417D02*
Y512120D01*
G01X1226894Y511680D02*
X1225874Y512700D01*
G01D02*
X1224774D01*
G01X1227954Y512120D02*
X1224774Y515300D01*
G01X1229070Y519900D02*
X1228399Y520571D01*
G01X1228169Y519300D02*
X1227339Y520130D01*
G01X1228399Y520571D02*
Y521848D01*
G01Y525338D02*
Y526229D01*
G01X1227339Y520130D02*
Y526670D01*
G01X1228399Y526229D02*
X1229170Y527000D01*
G01X1237180Y465231D02*
Y504743D01*
G01X1236120Y465671D02*
Y484732D01*
G01X1237180Y465231D02*
Y504743D01*
G01X1236120Y486972D02*
Y487972D01*
G01X1237180Y465231D02*
Y504743D01*
G01X1236120Y490212D02*
Y491212D01*
G01X1237180Y465231D02*
Y504743D01*
G01X1236120Y493452D02*
Y494452D01*
G01X1237180Y465231D02*
Y504743D01*
G01X1236120Y496692D02*
Y497692D01*
G01X1237180Y465231D02*
Y504743D01*
G01X1236120Y499932D02*
Y500932D01*
G01X1237180Y465231D02*
Y504743D01*
G01X1236120Y503172D02*
Y504303D01*
G01X1237180Y504743D02*
X1233334Y508589D01*
G01X1236120Y504303D02*
X1234666Y505757D01*
G01X1237180Y504743D02*
X1233334Y508589D01*
G01X1233444Y506979D02*
X1232274Y508149D01*
G01X1233334Y508589D02*
Y512054D01*
G01X1232274Y508149D02*
Y511614D01*
G01X1233334Y512054D02*
X1229874Y515514D01*
G01X1232274Y511614D02*
X1230974Y512914D01*
G01X1223846Y520290D02*
Y521660D01*
G01Y525340D02*
Y526760D01*
G01X1222786Y514400D02*
Y532411D01*
G01X1232220Y471552D02*
Y503151D01*
G01X1231160Y471992D02*
Y479951D01*
G01X1232220Y471552D02*
Y503151D01*
G01X1231160Y481883D02*
Y483059D01*
G01X1232220Y471552D02*
Y503151D01*
G01X1231160Y485299D02*
Y486299D01*
G01X1232220Y471552D02*
Y503151D01*
G01X1231160Y488539D02*
Y489539D01*
G01X1232220Y471552D02*
Y503151D01*
G01X1231160Y491779D02*
Y492779D01*
G01X1232220Y471552D02*
Y503151D01*
G01X1231160Y495019D02*
Y496019D01*
G01X1232220Y471552D02*
Y503151D01*
G01X1231160Y498259D02*
Y499259D01*
G01X1232220Y471552D02*
Y503151D01*
G01X1231160Y501499D02*
Y502711D01*
G01X1232220Y503151D02*
X1227954Y507417D01*
G01X1231160Y502711D02*
X1229799Y504072D01*
G01X1232220Y503151D02*
X1227954Y507417D01*
G01X1228512Y505359D02*
X1226894Y506977D01*
G01X1227954Y507417D02*
Y512120D01*
G01X1226894Y506977D02*
Y511680D01*
G01X1227954Y512120D02*
X1224774Y515300D01*
G01X1226894Y511680D02*
X1225874Y512700D01*
G01X1227954Y512120D02*
X1224774Y515300D01*
G01X1225874Y512700D02*
X1224774D01*
G01X1228169Y519300D02*
X1227339Y520130D01*
G01X1229070Y519900D02*
X1228399Y520571D01*
G01X1227339Y520130D02*
Y526670D01*
G01X1228399Y520571D02*
Y521848D01*
G01X1227339Y520130D02*
Y526670D01*
G01X1228399Y525338D02*
Y526229D01*
G01D02*
X1229170Y527000D01*
G01X1236120Y465671D02*
Y484732D01*
G01Y486972D02*
Y487972D01*
G01Y490212D02*
Y491212D01*
G01Y493452D02*
Y494452D01*
G01Y496692D02*
Y497692D01*
G01Y499932D02*
Y500932D01*
G01Y503172D02*
Y504303D01*
G01X1237180Y465231D02*
Y504743D01*
G01X1236120Y504303D02*
X1234666Y505757D01*
G01X1233444Y506979D02*
X1232274Y508149D01*
G01X1237180Y504743D02*
X1233334Y508589D01*
G01X1232274Y508149D02*
Y511614D01*
G01X1233334Y508589D02*
Y512054D01*
G01X1232274Y511614D02*
X1230974Y512914D01*
G01X1233334Y512054D02*
X1229874Y515514D01*
G01X1222786Y514400D02*
Y532411D01*
G01X1223846Y520290D02*
Y521660D01*
G01X1222786Y514400D02*
Y532411D01*
G01X1223846Y525340D02*
Y526760D01*
G01X1231160Y471992D02*
Y479951D01*
G01Y481883D02*
Y483059D01*
G01Y485299D02*
Y486299D01*
G01Y488539D02*
Y489539D01*
G01Y491779D02*
Y492779D01*
G01Y495019D02*
Y496019D01*
G01Y498259D02*
Y499259D01*
G01Y501499D02*
Y502711D01*
G01X1232220Y471552D02*
Y503151D01*
G01X1231160Y502711D02*
X1229799Y504072D01*
G01X1228512Y505359D02*
X1226894Y506977D01*
G01X1232220Y503151D02*
X1227954Y507417D01*
G01X1226894Y506977D02*
Y511680D01*
G01X1227954Y507417D02*
Y512120D01*
G01X1226894Y511680D02*
X1225874Y512700D01*
G01D02*
X1224774D01*
G01X1227954Y512120D02*
X1224774Y515300D01*
G01X1229070Y519900D02*
X1228399Y520571D01*
G01X1228169Y519300D02*
X1227339Y520130D01*
G01X1228399Y520571D02*
Y521848D01*
G01Y525338D02*
Y526229D01*
G01X1227339Y520130D02*
Y526670D01*
G01X1228399Y526229D02*
X1229170Y527000D01*
G01X1237180Y465231D02*
Y504743D01*
G01X1236120Y465671D02*
Y484732D01*
G01X1237180Y465231D02*
Y504743D01*
G01X1236120Y486972D02*
Y487972D01*
G01X1237180Y465231D02*
Y504743D01*
G01X1236120Y490212D02*
Y491212D01*
G01X1237180Y465231D02*
Y504743D01*
G01X1236120Y493452D02*
Y494452D01*
G01X1237180Y465231D02*
Y504743D01*
G01X1236120Y496692D02*
Y497692D01*
G01X1237180Y465231D02*
Y504743D01*
G01X1236120Y499932D02*
Y500932D01*
G01X1237180Y465231D02*
Y504743D01*
G01X1236120Y503172D02*
Y504303D01*
G01X1237180Y504743D02*
X1233334Y508589D01*
G01X1236120Y504303D02*
X1234666Y505757D01*
G01X1237180Y504743D02*
X1233334Y508589D01*
G01X1233444Y506979D02*
X1232274Y508149D01*
G01X1233334Y508589D02*
Y512054D01*
G01X1232274Y508149D02*
Y511614D01*
G01X1233334Y512054D02*
X1229874Y515514D01*
G01X1232274Y511614D02*
X1230974Y512914D01*
G01X1223846Y520290D02*
Y521660D01*
G01Y525340D02*
Y526760D01*
G01X1222786Y514400D02*
Y532411D01*
G01X1232220Y471552D02*
Y503151D01*
G01X1231160Y471992D02*
Y479951D01*
G01X1232220Y471552D02*
Y503151D01*
G01X1231160Y481883D02*
Y483059D01*
G01X1232220Y471552D02*
Y503151D01*
G01X1231160Y485299D02*
Y486299D01*
G01X1232220Y471552D02*
Y503151D01*
G01X1231160Y488539D02*
Y489539D01*
G01X1232220Y471552D02*
Y503151D01*
G01X1231160Y491779D02*
Y492779D01*
G01X1232220Y471552D02*
Y503151D01*
G01X1231160Y495019D02*
Y496019D01*
G01X1232220Y471552D02*
Y503151D01*
G01X1231160Y498259D02*
Y499259D01*
G01X1232220Y471552D02*
Y503151D01*
G01X1231160Y501499D02*
Y502711D01*
G01X1232220Y503151D02*
X1227954Y507417D01*
G01X1231160Y502711D02*
X1229799Y504072D01*
G01X1232220Y503151D02*
X1227954Y507417D01*
G01X1228512Y505359D02*
X1226894Y506977D01*
G01X1227954Y507417D02*
Y512120D01*
G01X1226894Y506977D02*
Y511680D01*
G01X1227954Y512120D02*
X1224774Y515300D01*
G01X1226894Y511680D02*
X1225874Y512700D01*
G01X1227954Y512120D02*
X1224774Y515300D01*
G01X1225874Y512700D02*
X1224774D01*
G01X1228169Y519300D02*
X1227339Y520130D01*
G01X1229070Y519900D02*
X1228399Y520571D01*
G01X1227339Y520130D02*
Y526670D01*
G01X1228399Y520571D02*
Y521848D01*
G01X1227339Y520130D02*
Y526670D01*
G01X1228399Y525338D02*
Y526229D01*
G01D02*
X1229170Y527000D01*
G01X1236120Y465671D02*
Y484732D01*
G01Y486972D02*
Y487972D01*
G01Y490212D02*
Y491212D01*
G01Y493452D02*
Y494452D01*
G01Y496692D02*
Y497692D01*
G01Y499932D02*
Y500932D01*
G01Y503172D02*
Y504303D01*
G01X1237180Y465231D02*
Y504743D01*
G01X1236120Y504303D02*
X1234666Y505757D01*
G01X1233444Y506979D02*
X1232274Y508149D01*
G01X1237180Y504743D02*
X1233334Y508589D01*
G01X1232274Y508149D02*
Y511614D01*
G01X1233334Y508589D02*
Y512054D01*
G01X1232274Y511614D02*
X1230974Y512914D01*
G01X1233334Y512054D02*
X1229874Y515514D01*
G01X1227339Y526670D02*
X1228169Y527500D01*
G01X1227339Y526670D02*
X1228169Y527500D01*
G01X1227339Y526670D02*
X1228169Y527500D01*
G01X1227339Y526670D02*
X1228169Y527500D01*
M02*
